G04 ================== begin FILE IDENTIFICATION RECORD ==================*
G04 Layout Name:  D:/<user>/Wistron_project/16316-1/gbr-0621/16316-1.brd*
G04 Film Name:    16316-1_X_Y*
G04 File Format:  Gerber RS274X*
G04 File Origin:  Cadence Allegro 16.5-S056*
G04 Origin Date:  Wed Jun 21 09:31:28 2017*
G04 *
G04 Layer:  BOARD GEOMETRY/PANEL_DRAWING*
G04 *
G04 Offset:    (0.00 0.00)*
G04 Mirror:    No*
G04 Mode:      Positive*
G04 Rotation:  0*
G04 FullContactRelief:  No*
G04 UndefLineWidth:     6.00*
G04 ================== end FILE IDENTIFICATION RECORD ====================*
%FSLAX35Y35*MOIN*%
%IR0*IPPOS*OFA0.00000B0.00000*MIA0B0*SFA1.00000B1.00000*%
%ADD10C,.006*%
G75*
%LPD*%
G75*
G36*
G01X1253198Y54396D02*
X1258000Y63647D01*
X1254227Y64769D01*
X1253198Y54396D01*
G37*
G36*
G01X1204402Y991670D02*
X1213071Y985881D01*
X1207167Y994472D01*
X1204402Y991670D01*
G37*
G36*
G01X1326232Y-455663D02*
X1336238Y-452739D01*
X1334440Y-449236D01*
X1326232Y-455663D01*
G37*
G36*
G01X1324993Y-485922D02*
X1330509Y-494767D01*
X1333396Y-492090D01*
X1324993Y-485922D01*
G37*
G36*
G01X1325312Y-444619D02*
X1329845Y-435233D01*
X1326041Y-434221D01*
X1325312Y-444619D01*
G37*
G36*
G01X1503486Y53018D02*
X1506809Y62898D01*
X1502907Y63425D01*
X1503486Y53018D01*
G37*
G36*
G01X1506539Y965971D02*
X1505920Y976376D01*
X1502105Y975404D01*
X1506539Y965971D01*
G37*
G36*
G01X1506683Y953090D02*
X1501538Y962156D01*
X1498543Y959601D01*
X1506683Y953090D01*
G37*
G36*
G01X1739002Y-137384D02*
X1738618Y-147801D01*
X1742509Y-147200D01*
X1739002Y-137384D01*
G37*
G36*
G01X1742356Y52461D02*
X1747071Y61758D01*
X1743286Y62844D01*
X1742356Y52461D01*
G37*
G36*
G01X1752036Y784026D02*
X1758909Y776189D01*
X1761326Y779298D01*
X1752036Y784026D01*
G37*
G36*
G01X1748852Y966491D02*
X1751623Y976539D01*
X1747698Y976850D01*
X1748852Y966491D01*
G37*
G36*
G01X1748321Y954672D02*
X1751679Y964541D01*
X1747779Y965082D01*
X1748321Y954672D01*
G37*
G36*
G01X1752608Y798239D02*
X1758908Y806543D01*
X1755379Y808288D01*
X1752608Y798239D01*
G37*
G36*
G01X1992571Y55775D02*
X1993812Y66125D01*
X1989885Y65847D01*
X1992571Y55775D01*
G37*
G36*
G01X2084865Y1012040D02*
X2080237Y1002699D01*
X2087999Y1009658D01*
X2084865Y1012040D01*
G37*
G54D10*
G01X-380629Y-775313D02*
X-379918Y-776449D01*
X-379066Y-777206D01*
X-378072Y-777585D01*
X-376936Y-777206D01*
X-376084Y-776449D01*
X-375231Y-775313D01*
X-374947Y-773798D01*
Y-766223D01*
G01X-379492Y-550341D02*
X-376084D01*
G01X-377788D02*
Y-561703D01*
G01X-379492D02*
X-376084D01*
G01X-380771Y-346011D02*
Y-334649D01*
G01X-374805D02*
Y-346011D01*
G01Y-340330D02*
X-380771D01*
G01X-376936Y-124448D02*
X-374095D01*
Y-127857D01*
X-374947Y-128993D01*
X-375942Y-129750D01*
X-377362Y-130129D01*
X-378782Y-129750D01*
X-379776Y-128993D01*
X-380629Y-127857D01*
X-381197Y-126531D01*
X-381481Y-125016D01*
Y-123691D01*
X-381197Y-122555D01*
X-380629Y-121229D01*
X-379776Y-120093D01*
X-378924Y-119335D01*
X-377788Y-118767D01*
X-376794D01*
X-375658Y-119146D01*
X-374805Y-119903D01*
G01X-380865Y85943D02*
Y97305D01*
X-375467D01*
G01X-377456Y91813D02*
X-380865D01*
G01X-374947Y302014D02*
X-380629D01*
Y313376D01*
X-374947D01*
G01X-377220Y307884D02*
X-380629D01*
G01X-380913Y517706D02*
Y529068D01*
X-378072D01*
X-376936Y528500D01*
X-376084Y527742D01*
X-375373Y526606D01*
X-374805Y525280D01*
X-374663Y523387D01*
X-374805Y521493D01*
X-375373Y520168D01*
X-376084Y519031D01*
X-376936Y518274D01*
X-378072Y517706D01*
X-380913D01*
G01X-374663Y744193D02*
X-375516Y744761D01*
X-376510Y745140D01*
X-377646D01*
X-378924Y744572D01*
X-379918Y743625D01*
X-380629Y742489D01*
X-381197Y740595D01*
X-381339Y738891D01*
X-381055Y737187D01*
X-380629Y736050D01*
X-379776Y734914D01*
X-378782Y734157D01*
X-377788Y733778D01*
X-376794D01*
X-375800Y734157D01*
X-374947Y734725D01*
X-374237Y735482D01*
G01X-376652Y955530D02*
X-376084Y956098D01*
X-375658Y957044D01*
X-375373Y958370D01*
X-375658Y959506D01*
X-376226Y960264D01*
X-377220Y960832D01*
X-381055D01*
Y949470D01*
X-376368D01*
X-375373Y950227D01*
X-374805Y951364D01*
X-374521Y952689D01*
X-374805Y954015D01*
X-375658Y955151D01*
X-376652Y955530D01*
X-381055D01*
G01X-381339Y1165352D02*
X-377788Y1176714D01*
X-374237Y1165352D01*
G01X-375516Y1169329D02*
X-380061D01*
G01X-250910Y-894995D02*
Y-883633D01*
X-252614Y-885905D01*
G01Y-894995D02*
X-249206D01*
G01X-250910Y1282761D02*
Y1294123D01*
X-252614Y1291851D01*
G01Y1282761D02*
X-249206D01*
G01X-76025Y-98450D02*
X-76813Y-98712D01*
X-77403Y-99369D01*
X-77797Y-100156D01*
X-78092Y-101206D01*
X-78191Y-102387D01*
X-78092Y-103568D01*
X-77797Y-104618D01*
X-77403Y-105406D01*
X-76813Y-106062D01*
X-76025Y-106324D01*
X-75238Y-106062D01*
X-74647Y-105406D01*
X-74253Y-104618D01*
X-73958Y-103568D01*
X-73859Y-102387D01*
X-73958Y-101206D01*
X-74253Y-100156D01*
X-74647Y-99369D01*
X-75238Y-98712D01*
X-76025Y-98450D01*
G01X-68150Y-106586D02*
X-68347Y-106455D01*
Y-106193D01*
X-68150Y-106062D01*
X-67953Y-106193D01*
Y-106455D01*
X-68150Y-106586D01*
G01X-60275Y-98450D02*
X-61063Y-98712D01*
X-61653Y-99369D01*
X-62047Y-100156D01*
X-62342Y-101206D01*
X-62441Y-102387D01*
X-62342Y-103568D01*
X-62047Y-104618D01*
X-61653Y-105406D01*
X-61063Y-106062D01*
X-60275Y-106324D01*
X-59488Y-106062D01*
X-58897Y-105406D01*
X-58503Y-104618D01*
X-58208Y-103568D01*
X-58109Y-102387D01*
X-58208Y-101206D01*
X-58503Y-100156D01*
X-58897Y-99369D01*
X-59488Y-98712D01*
X-60275Y-98450D01*
G01X-52400D02*
X-53188Y-98712D01*
X-53778Y-99369D01*
X-54172Y-100156D01*
X-54467Y-101206D01*
X-54566Y-102387D01*
X-54467Y-103568D01*
X-54172Y-104618D01*
X-53778Y-105406D01*
X-53188Y-106062D01*
X-52400Y-106324D01*
X-51613Y-106062D01*
X-51022Y-105406D01*
X-50628Y-104618D01*
X-50333Y-103568D01*
X-50234Y-102387D01*
X-50333Y-101206D01*
X-50628Y-100156D01*
X-51022Y-99369D01*
X-51613Y-98712D01*
X-52400Y-98450D01*
G01X-85975Y2061D02*
X-85385Y2848D01*
X-84696Y3242D01*
X-83908Y3373D01*
X-82924Y3111D01*
X-82235Y2454D01*
X-82038Y1667D01*
X-82136Y879D01*
X-82530Y223D01*
X-84499Y-1089D01*
X-85385Y-2008D01*
X-85975Y-3320D01*
X-86172Y-4501D01*
X-82038D01*
G01X-78100Y-1220D02*
X-77411Y-301D01*
X-76821Y223D01*
X-76033Y486D01*
X-75344Y223D01*
X-74852Y-301D01*
X-74458Y-1089D01*
X-74360Y-2008D01*
X-74458Y-2795D01*
X-74852Y-3583D01*
X-75443Y-4239D01*
X-76131Y-4501D01*
X-76919Y-4239D01*
X-77608Y-3451D01*
X-78002Y-2270D01*
X-78100Y-958D01*
X-77903Y748D01*
X-77608Y1667D01*
X-77116Y2586D01*
X-76427Y3242D01*
X-75738Y3373D01*
X-75049Y3111D01*
X-74557Y2454D01*
G01X-68355Y-4763D02*
X-68552Y-4632D01*
Y-4370D01*
X-68355Y-4239D01*
X-68158Y-4370D01*
Y-4632D01*
X-68355Y-4763D01*
G01X-60480Y3373D02*
X-61268Y3111D01*
X-61858Y2454D01*
X-62252Y1667D01*
X-62547Y617D01*
X-62646Y-564D01*
X-62547Y-1745D01*
X-62252Y-2795D01*
X-61858Y-3583D01*
X-61268Y-4239D01*
X-60480Y-4501D01*
X-59693Y-4239D01*
X-59102Y-3583D01*
X-58708Y-2795D01*
X-58413Y-1745D01*
X-58314Y-564D01*
X-58413Y617D01*
X-58708Y1667D01*
X-59102Y2454D01*
X-59693Y3111D01*
X-60480Y3373D01*
G01X-52605D02*
X-53393Y3111D01*
X-53983Y2454D01*
X-54377Y1667D01*
X-54672Y617D01*
X-54771Y-564D01*
X-54672Y-1745D01*
X-54377Y-2795D01*
X-53983Y-3583D01*
X-53393Y-4239D01*
X-52605Y-4501D01*
X-51818Y-4239D01*
X-51227Y-3583D01*
X-50833Y-2795D01*
X-50538Y-1745D01*
X-50439Y-564D01*
X-50538Y617D01*
X-50833Y1667D01*
X-51227Y2454D01*
X-51818Y3111D01*
X-52605Y3373D01*
G01X-92616Y567266D02*
Y575140D01*
X-93797Y573565D01*
G01Y567266D02*
X-91435D01*
G01X-84938D02*
X-84741Y568972D01*
X-84446Y570415D01*
X-84052Y571728D01*
X-83560Y573171D01*
X-82772Y575140D01*
X-86710D01*
G01X-76866Y567266D02*
Y575140D01*
X-78047Y573565D01*
G01Y567266D02*
X-75685D01*
G01X-68991Y567004D02*
X-69188Y567135D01*
Y567397D01*
X-68991Y567528D01*
X-68794Y567397D01*
Y567135D01*
X-68991Y567004D01*
G01X-61116Y575140D02*
X-61904Y574878D01*
X-62494Y574221D01*
X-62888Y573434D01*
X-63183Y572384D01*
X-63282Y571203D01*
X-63183Y570022D01*
X-62888Y568972D01*
X-62494Y568184D01*
X-61904Y567528D01*
X-61116Y567266D01*
X-60329Y567528D01*
X-59738Y568184D01*
X-59344Y568972D01*
X-59049Y570022D01*
X-58950Y571203D01*
X-59049Y572384D01*
X-59344Y573434D01*
X-59738Y574221D01*
X-60329Y574878D01*
X-61116Y575140D01*
G01X-53241D02*
X-54029Y574878D01*
X-54619Y574221D01*
X-55013Y573434D01*
X-55308Y572384D01*
X-55407Y571203D01*
X-55308Y570022D01*
X-55013Y568972D01*
X-54619Y568184D01*
X-54029Y567528D01*
X-53241Y567266D01*
X-52454Y567528D01*
X-51863Y568184D01*
X-51469Y568972D01*
X-51174Y570022D01*
X-51075Y571203D01*
X-51174Y572384D01*
X-51469Y573434D01*
X-51863Y574221D01*
X-52454Y574878D01*
X-53241Y575140D01*
G01X-35833Y-885527D02*
X-34980Y-884391D01*
X-33986Y-883822D01*
X-32850Y-883633D01*
X-31430Y-884012D01*
X-30435Y-884959D01*
X-30151Y-886095D01*
X-30293Y-887231D01*
X-30862Y-888178D01*
X-33702Y-890071D01*
X-34980Y-891397D01*
X-35833Y-893291D01*
X-36117Y-894995D01*
X-30151D01*
G01X-3540Y622606D02*
X-3278Y621818D01*
X-2621Y621228D01*
X-1834Y620834D01*
X-784Y620539D01*
X397Y620440D01*
X1578Y620539D01*
X2628Y620834D01*
X3416Y621228D01*
X4072Y621818D01*
X4334Y622606D01*
X4072Y623393D01*
X3416Y623984D01*
X2628Y624378D01*
X1578Y624673D01*
X397Y624772D01*
X-784Y624673D01*
X-1834Y624378D01*
X-2621Y623984D01*
X-3278Y623393D01*
X-3540Y622606D01*
G01X4596Y630481D02*
X4465Y630284D01*
X4203D01*
X4072Y630481D01*
X4203Y630678D01*
X4465D01*
X4596Y630481D01*
G01X-3540Y638356D02*
X-3278Y637568D01*
X-2621Y636978D01*
X-1834Y636584D01*
X-784Y636289D01*
X397Y636190D01*
X1578Y636289D01*
X2628Y636584D01*
X3416Y636978D01*
X4072Y637568D01*
X4334Y638356D01*
X4072Y639143D01*
X3416Y639734D01*
X2628Y640128D01*
X1578Y640423D01*
X397Y640522D01*
X-784Y640423D01*
X-1834Y640128D01*
X-2621Y639734D01*
X-3278Y639143D01*
X-3540Y638356D01*
G01Y646231D02*
X-3278Y645443D01*
X-2621Y644853D01*
X-1834Y644459D01*
X-784Y644164D01*
X397Y644065D01*
X1578Y644164D01*
X2628Y644459D01*
X3416Y644853D01*
X4072Y645443D01*
X4334Y646231D01*
X4072Y647018D01*
X3416Y647609D01*
X2628Y648003D01*
X1578Y648298D01*
X397Y648397D01*
X-784Y648298D01*
X-1834Y648003D01*
X-2621Y647609D01*
X-3278Y647018D01*
X-3540Y646231D01*
G01X-35833Y1292229D02*
X-34980Y1293365D01*
X-33986Y1293934D01*
X-32850Y1294123D01*
X-31430Y1293744D01*
X-30435Y1292797D01*
X-30151Y1291661D01*
X-30293Y1290525D01*
X-30862Y1289578D01*
X-33702Y1287685D01*
X-34980Y1286359D01*
X-35833Y1284465D01*
X-36117Y1282761D01*
X-30151D01*
G01X183410Y-892723D02*
X184262Y-894048D01*
X185399Y-894806D01*
X186677Y-894995D01*
X187813Y-894806D01*
X188950Y-893859D01*
X189660Y-892723D01*
X189802Y-891586D01*
X189518Y-890261D01*
X188523Y-889314D01*
X187529Y-888935D01*
X186251D01*
G01X187529D02*
X188381Y-888367D01*
X189092Y-887421D01*
X189376Y-886284D01*
X189092Y-885148D01*
X188381Y-884201D01*
X187103Y-883633D01*
X185825Y-883822D01*
X184547Y-884580D01*
G01X183410Y1285033D02*
X184262Y1283708D01*
X185399Y1282950D01*
X186677Y1282761D01*
X187813Y1282950D01*
X188950Y1283897D01*
X189660Y1285033D01*
X189802Y1286170D01*
X189518Y1287495D01*
X188523Y1288442D01*
X187529Y1288821D01*
X186251D01*
G01X187529D02*
X188381Y1289389D01*
X189092Y1290335D01*
X189376Y1291472D01*
X189092Y1292608D01*
X188381Y1293555D01*
X187103Y1294123D01*
X185825Y1293934D01*
X184547Y1293176D01*
G01X315589Y273831D02*
Y258231D01*
G01X311104Y273831D02*
X320074D01*
G01X407908Y-894995D02*
Y-883633D01*
X402653Y-891776D01*
X409755D01*
G01X407908Y1282761D02*
Y1294123D01*
X402653Y1285980D01*
X409755D01*
G01X622749Y-893291D02*
X623601Y-894238D01*
X624596Y-894806D01*
X625874Y-894995D01*
X627152Y-894616D01*
X628146Y-893859D01*
X628857Y-892533D01*
X628999Y-891018D01*
X628715Y-889503D01*
X628004Y-888557D01*
X627010Y-887799D01*
X626016Y-887610D01*
X625022Y-887799D01*
X623744Y-888557D01*
X624170Y-883633D01*
X628004D01*
G01X622749Y1284465D02*
X623601Y1283518D01*
X624596Y1282950D01*
X625874Y1282761D01*
X627152Y1283140D01*
X628146Y1283897D01*
X628857Y1285223D01*
X628999Y1286738D01*
X628715Y1288253D01*
X628004Y1289199D01*
X627010Y1289957D01*
X626016Y1290146D01*
X625022Y1289957D01*
X623744Y1289199D01*
X624170Y1294123D01*
X628004D01*
G01X842844Y-890261D02*
X843839Y-888935D01*
X844691Y-888178D01*
X845827Y-887799D01*
X846821Y-888178D01*
X847531Y-888935D01*
X848100Y-890071D01*
X848242Y-891397D01*
X848100Y-892533D01*
X847531Y-893670D01*
X846679Y-894616D01*
X845685Y-894995D01*
X844549Y-894616D01*
X843555Y-893480D01*
X842986Y-891776D01*
X842844Y-889882D01*
X843128Y-887421D01*
X843555Y-886095D01*
X844265Y-884769D01*
X845259Y-883822D01*
X846253Y-883633D01*
X847247Y-884012D01*
X847958Y-884959D01*
G01X824553Y621286D02*
X823766Y621876D01*
X823372Y622565D01*
X823241Y623353D01*
X823503Y624337D01*
X824160Y625026D01*
X824947Y625223D01*
X825735Y625125D01*
X826391Y624731D01*
X827703Y622762D01*
X828622Y621876D01*
X829934Y621286D01*
X831115Y621089D01*
Y625223D01*
G01Y631031D02*
X823241D01*
X824816Y629850D01*
G01X831115D02*
Y632212D01*
G01X823241Y638906D02*
X823503Y638118D01*
X824160Y637528D01*
X824947Y637134D01*
X825997Y636839D01*
X827178Y636740D01*
X828359Y636839D01*
X829409Y637134D01*
X830197Y637528D01*
X830853Y638118D01*
X831115Y638906D01*
X830853Y639693D01*
X830197Y640284D01*
X829409Y640678D01*
X828359Y640973D01*
X827178Y641072D01*
X825997Y640973D01*
X824947Y640678D01*
X824160Y640284D01*
X823503Y639693D01*
X823241Y638906D01*
G01X831377Y646781D02*
X831246Y646584D01*
X830984D01*
X830853Y646781D01*
X830984Y646978D01*
X831246D01*
X831377Y646781D01*
G01X823241Y654656D02*
X823503Y653868D01*
X824160Y653278D01*
X824947Y652884D01*
X825997Y652589D01*
X827178Y652490D01*
X828359Y652589D01*
X829409Y652884D01*
X830197Y653278D01*
X830853Y653868D01*
X831115Y654656D01*
X830853Y655443D01*
X830197Y656034D01*
X829409Y656428D01*
X828359Y656723D01*
X827178Y656822D01*
X825997Y656723D01*
X824947Y656428D01*
X824160Y656034D01*
X823503Y655443D01*
X823241Y654656D01*
G01Y662531D02*
X823503Y661743D01*
X824160Y661153D01*
X824947Y660759D01*
X825997Y660464D01*
X827178Y660365D01*
X828359Y660464D01*
X829409Y660759D01*
X830197Y661153D01*
X830853Y661743D01*
X831115Y662531D01*
X830853Y663318D01*
X830197Y663909D01*
X829409Y664303D01*
X828359Y664598D01*
X827178Y664697D01*
X825997Y664598D01*
X824947Y664303D01*
X824160Y663909D01*
X823503Y663318D01*
X823241Y662531D01*
G01X842844Y1287495D02*
X843839Y1288821D01*
X844691Y1289578D01*
X845827Y1289957D01*
X846821Y1289578D01*
X847531Y1288821D01*
X848100Y1287685D01*
X848242Y1286359D01*
X848100Y1285223D01*
X847531Y1284086D01*
X846679Y1283140D01*
X845685Y1282761D01*
X844549Y1283140D01*
X843555Y1284276D01*
X842986Y1285980D01*
X842844Y1287874D01*
X843128Y1290335D01*
X843555Y1291661D01*
X844265Y1292987D01*
X845259Y1293934D01*
X846253Y1294123D01*
X847247Y1293744D01*
X847958Y1292797D01*
G01X1064928Y-894995D02*
X1065212Y-892533D01*
X1065638Y-890450D01*
X1066206Y-888557D01*
X1066916Y-886474D01*
X1068053Y-883633D01*
X1062371D01*
G01X1068457Y1023692D02*
X1069324Y1022970D01*
X1070298Y1022537D01*
X1071164D01*
X1072030Y1022970D01*
X1072680Y1023692D01*
X1073005Y1024702D01*
X1072788Y1025713D01*
X1072247Y1026579D01*
X1071272Y1027156D01*
X1069973Y1027445D01*
X1069215Y1028022D01*
X1068890Y1029033D01*
X1069107Y1030043D01*
X1069648Y1030765D01*
X1070406Y1031198D01*
X1071164D01*
X1071922Y1030909D01*
X1072572Y1030188D01*
G01X1081557Y1022537D02*
X1077227D01*
Y1031198D01*
X1081557D01*
G01X1079825Y1027012D02*
X1077227D01*
G01X1090218Y1022537D02*
X1085888D01*
Y1031198D01*
X1090218D01*
G01X1088486Y1027012D02*
X1085888D01*
G01X1102993Y1022537D02*
Y1031198D01*
X1105158D01*
X1106025Y1030765D01*
X1106674Y1030188D01*
X1107216Y1029322D01*
X1107649Y1028311D01*
X1107757Y1026867D01*
X1107649Y1025424D01*
X1107216Y1024413D01*
X1106674Y1023547D01*
X1106025Y1022970D01*
X1105158Y1022537D01*
X1102993D01*
G01X1116201D02*
X1111871D01*
Y1031198D01*
X1116201D01*
G01X1114469Y1027012D02*
X1111871D01*
G01X1122697Y1031198D02*
Y1022537D01*
G01X1120207Y1031198D02*
X1125187D01*
G01X1128651Y1022537D02*
X1131358Y1031198D01*
X1134065Y1022537D01*
G01X1133090Y1025568D02*
X1129626D01*
G01X1138720Y1031198D02*
X1141318D01*
G01X1140019D02*
Y1022537D01*
G01X1138720D02*
X1141318D01*
G01X1146515Y1031198D02*
Y1022537D01*
X1150845D01*
G01X1064928Y1282761D02*
X1065212Y1285223D01*
X1065638Y1287306D01*
X1066206Y1289199D01*
X1066916Y1291282D01*
X1068053Y1294123D01*
X1062371D01*
G01X1132323Y-454780D02*
X1133081Y-455501D01*
X1133947Y-455790D01*
X1134814Y-455501D01*
X1135571Y-454635D01*
X1136113Y-453336D01*
X1136329Y-452037D01*
Y-450449D01*
X1136113Y-449150D01*
X1135571Y-447995D01*
X1134922Y-447418D01*
X1134164Y-447129D01*
X1133298Y-447418D01*
X1132648Y-447995D01*
X1132215Y-448861D01*
X1131999Y-450016D01*
X1132215Y-451026D01*
X1132757Y-452037D01*
X1133406Y-452614D01*
X1134164Y-452759D01*
X1135030Y-452470D01*
X1135680Y-451748D01*
X1136329Y-450449D01*
G01X1142825Y-456079D02*
X1142608Y-455934D01*
Y-455646D01*
X1142825Y-455501D01*
X1143042Y-455646D01*
Y-455934D01*
X1142825Y-456079D01*
G01X1149645Y-454780D02*
X1150403Y-455501D01*
X1151269Y-455790D01*
X1152136Y-455501D01*
X1152893Y-454635D01*
X1153435Y-453336D01*
X1153651Y-452037D01*
Y-450449D01*
X1153435Y-449150D01*
X1152893Y-447995D01*
X1152244Y-447418D01*
X1151486Y-447129D01*
X1150620Y-447418D01*
X1149970Y-447995D01*
X1149537Y-448861D01*
X1149321Y-450016D01*
X1149537Y-451026D01*
X1150079Y-452037D01*
X1150728Y-452614D01*
X1151486Y-452759D01*
X1152352Y-452470D01*
X1153002Y-451748D01*
X1153651Y-450449D01*
G01X1158090Y-448572D02*
X1158740Y-447707D01*
X1159497Y-447273D01*
X1160364Y-447129D01*
X1161446Y-447418D01*
X1162204Y-448139D01*
X1162421Y-449005D01*
X1162312Y-449872D01*
X1161879Y-450593D01*
X1159714Y-452037D01*
X1158740Y-453047D01*
X1158090Y-454491D01*
X1157873Y-455790D01*
X1162421D01*
G01X1190547Y-601413D02*
X1190836Y-602279D01*
X1191557Y-602929D01*
X1192423Y-603362D01*
X1193578Y-603687D01*
X1194878Y-603795D01*
X1196177Y-603687D01*
X1197332Y-603362D01*
X1198198Y-602929D01*
X1198919Y-602279D01*
X1199208Y-601413D01*
X1198919Y-600547D01*
X1198198Y-599897D01*
X1197332Y-599464D01*
X1196177Y-599139D01*
X1194878Y-599031D01*
X1193578Y-599139D01*
X1192423Y-599464D01*
X1191557Y-599897D01*
X1190836Y-600547D01*
X1190547Y-601413D01*
G01X1199497Y-592752D02*
X1199352Y-592969D01*
X1199064D01*
X1198919Y-592752D01*
X1199064Y-592535D01*
X1199352D01*
X1199497Y-592752D01*
G01X1190547Y-584091D02*
X1190836Y-584957D01*
X1191557Y-585607D01*
X1192423Y-586040D01*
X1193578Y-586365D01*
X1194878Y-586473D01*
X1196177Y-586365D01*
X1197332Y-586040D01*
X1198198Y-585607D01*
X1198919Y-584957D01*
X1199208Y-584091D01*
X1198919Y-583225D01*
X1198198Y-582575D01*
X1197332Y-582142D01*
X1196177Y-581817D01*
X1194878Y-581709D01*
X1193578Y-581817D01*
X1192423Y-582142D01*
X1191557Y-582575D01*
X1190836Y-583225D01*
X1190547Y-584091D01*
G01Y-575430D02*
X1190836Y-576296D01*
X1191557Y-576946D01*
X1192423Y-577379D01*
X1193578Y-577704D01*
X1194878Y-577812D01*
X1196177Y-577704D01*
X1197332Y-577379D01*
X1198198Y-576946D01*
X1198919Y-576296D01*
X1199208Y-575430D01*
X1198919Y-574564D01*
X1198198Y-573914D01*
X1197332Y-573481D01*
X1196177Y-573156D01*
X1194878Y-573048D01*
X1193578Y-573156D01*
X1192423Y-573481D01*
X1191557Y-573914D01*
X1190836Y-574564D01*
X1190547Y-575430D01*
G01X1138230Y-478546D02*
X1138880Y-479556D01*
X1139746Y-480134D01*
X1140720Y-480278D01*
X1141586Y-480134D01*
X1142453Y-479412D01*
X1142994Y-478546D01*
X1143102Y-477680D01*
X1142886Y-476669D01*
X1142128Y-475948D01*
X1141370Y-475659D01*
X1140395D01*
G01X1141370D02*
X1142019Y-475226D01*
X1142561Y-474504D01*
X1142777Y-473638D01*
X1142561Y-472772D01*
X1142019Y-472050D01*
X1141045Y-471617D01*
X1140071Y-471761D01*
X1139096Y-472339D01*
G01X1149273Y-480567D02*
X1149056Y-480422D01*
Y-480134D01*
X1149273Y-479989D01*
X1149490Y-480134D01*
Y-480422D01*
X1149273Y-480567D01*
G01X1157717Y-480278D02*
X1157934Y-478402D01*
X1158259Y-476814D01*
X1158692Y-475370D01*
X1159233Y-473782D01*
X1160099Y-471617D01*
X1155769D01*
G01X1166595D02*
X1165729Y-471906D01*
X1165079Y-472627D01*
X1164646Y-473493D01*
X1164321Y-474648D01*
X1164213Y-475948D01*
X1164321Y-477247D01*
X1164646Y-478402D01*
X1165079Y-479268D01*
X1165729Y-479989D01*
X1166595Y-480278D01*
X1167461Y-479989D01*
X1168111Y-479268D01*
X1168544Y-478402D01*
X1168869Y-477247D01*
X1168977Y-475948D01*
X1168869Y-474648D01*
X1168544Y-473493D01*
X1168111Y-472627D01*
X1167461Y-471906D01*
X1166595Y-471617D01*
G01X1140612Y-486184D02*
X1139746Y-486473D01*
X1139096Y-487194D01*
X1138663Y-488060D01*
X1138338Y-489215D01*
X1138230Y-490515D01*
X1138338Y-491814D01*
X1138663Y-492969D01*
X1139096Y-493835D01*
X1139746Y-494556D01*
X1140612Y-494845D01*
X1141478Y-494556D01*
X1142128Y-493835D01*
X1142561Y-492969D01*
X1142886Y-491814D01*
X1142994Y-490515D01*
X1142886Y-489215D01*
X1142561Y-488060D01*
X1142128Y-487194D01*
X1141478Y-486473D01*
X1140612Y-486184D01*
G01X1149273Y-495134D02*
X1149056Y-494989D01*
Y-494701D01*
X1149273Y-494556D01*
X1149490Y-494701D01*
Y-494989D01*
X1149273Y-495134D01*
G01X1157934Y-486184D02*
X1157068Y-486473D01*
X1156418Y-487194D01*
X1155985Y-488060D01*
X1155660Y-489215D01*
X1155552Y-490515D01*
X1155660Y-491814D01*
X1155985Y-492969D01*
X1156418Y-493835D01*
X1157068Y-494556D01*
X1157934Y-494845D01*
X1158800Y-494556D01*
X1159450Y-493835D01*
X1159883Y-492969D01*
X1160208Y-491814D01*
X1160316Y-490515D01*
X1160208Y-489215D01*
X1159883Y-488060D01*
X1159450Y-487194D01*
X1158800Y-486473D01*
X1157934Y-486184D01*
G01X1166595D02*
X1165729Y-486473D01*
X1165079Y-487194D01*
X1164646Y-488060D01*
X1164321Y-489215D01*
X1164213Y-490515D01*
X1164321Y-491814D01*
X1164646Y-492969D01*
X1165079Y-493835D01*
X1165729Y-494556D01*
X1166595Y-494845D01*
X1167461Y-494556D01*
X1168111Y-493835D01*
X1168544Y-492969D01*
X1168869Y-491814D01*
X1168977Y-490515D01*
X1168869Y-489215D01*
X1168544Y-488060D01*
X1168111Y-487194D01*
X1167461Y-486473D01*
X1166595Y-486184D01*
G01X1152354Y427178D02*
X1151488Y426889D01*
X1150838Y426168D01*
X1150405Y425302D01*
X1150080Y424147D01*
X1149972Y422847D01*
X1150080Y421548D01*
X1150405Y420393D01*
X1150838Y419527D01*
X1151488Y418806D01*
X1152354Y418517D01*
X1153220Y418806D01*
X1153870Y419527D01*
X1154303Y420393D01*
X1154628Y421548D01*
X1154736Y422847D01*
X1154628Y424147D01*
X1154303Y425302D01*
X1153870Y426168D01*
X1153220Y426889D01*
X1152354Y427178D01*
G01X1161015Y418228D02*
X1160798Y418373D01*
Y418661D01*
X1161015Y418806D01*
X1161232Y418661D01*
Y418373D01*
X1161015Y418228D01*
G01X1169676Y427178D02*
X1168810Y426889D01*
X1168160Y426168D01*
X1167727Y425302D01*
X1167402Y424147D01*
X1167294Y422847D01*
X1167402Y421548D01*
X1167727Y420393D01*
X1168160Y419527D01*
X1168810Y418806D01*
X1169676Y418517D01*
X1170542Y418806D01*
X1171192Y419527D01*
X1171625Y420393D01*
X1171950Y421548D01*
X1172058Y422847D01*
X1171950Y424147D01*
X1171625Y425302D01*
X1171192Y426168D01*
X1170542Y426889D01*
X1169676Y427178D01*
G01X1178337D02*
X1177471Y426889D01*
X1176821Y426168D01*
X1176388Y425302D01*
X1176063Y424147D01*
X1175955Y422847D01*
X1176063Y421548D01*
X1176388Y420393D01*
X1176821Y419527D01*
X1177471Y418806D01*
X1178337Y418517D01*
X1179203Y418806D01*
X1179853Y419527D01*
X1180286Y420393D01*
X1180611Y421548D01*
X1180719Y422847D01*
X1180611Y424147D01*
X1180286Y425302D01*
X1179853Y426168D01*
X1179203Y426889D01*
X1178337Y427178D01*
G01X1135897Y918242D02*
Y926903D01*
X1134598Y925171D01*
G01Y918242D02*
X1137196D01*
G01X1142501Y925460D02*
X1143151Y926325D01*
X1143908Y926759D01*
X1144775Y926903D01*
X1145857Y926614D01*
X1146615Y925893D01*
X1146832Y925027D01*
X1146723Y924160D01*
X1146290Y923439D01*
X1144125Y921995D01*
X1143151Y920985D01*
X1142501Y919541D01*
X1142284Y918242D01*
X1146832D01*
G01X1151162Y921851D02*
X1151920Y922861D01*
X1152569Y923439D01*
X1153436Y923727D01*
X1154193Y923439D01*
X1154735Y922861D01*
X1155168Y921995D01*
X1155276Y920985D01*
X1155168Y920118D01*
X1154735Y919252D01*
X1154085Y918531D01*
X1153327Y918242D01*
X1152461Y918531D01*
X1151703Y919397D01*
X1151270Y920696D01*
X1151162Y922139D01*
X1151378Y924016D01*
X1151703Y925027D01*
X1152245Y926037D01*
X1153002Y926759D01*
X1153760Y926903D01*
X1154518Y926614D01*
X1155060Y925893D01*
G01X1161880Y917953D02*
X1161663Y918098D01*
Y918386D01*
X1161880Y918531D01*
X1162097Y918386D01*
Y918098D01*
X1161880Y917953D01*
G01X1168700Y919252D02*
X1169458Y918531D01*
X1170324Y918242D01*
X1171191Y918531D01*
X1171948Y919397D01*
X1172490Y920696D01*
X1172706Y921995D01*
Y923583D01*
X1172490Y924882D01*
X1171948Y926037D01*
X1171299Y926614D01*
X1170541Y926903D01*
X1169675Y926614D01*
X1169025Y926037D01*
X1168592Y925171D01*
X1168376Y924016D01*
X1168592Y923006D01*
X1169134Y921995D01*
X1169783Y921418D01*
X1170541Y921273D01*
X1171407Y921562D01*
X1172057Y922284D01*
X1172706Y923583D01*
G01X1176820Y919974D02*
X1177470Y918964D01*
X1178336Y918386D01*
X1179310Y918242D01*
X1180176Y918386D01*
X1181043Y919108D01*
X1181584Y919974D01*
X1181692Y920840D01*
X1181476Y921851D01*
X1180718Y922572D01*
X1179960Y922861D01*
X1178985D01*
G01X1179960D02*
X1180609Y923294D01*
X1181151Y924016D01*
X1181367Y924882D01*
X1181151Y925748D01*
X1180609Y926470D01*
X1179635Y926903D01*
X1178661Y926759D01*
X1177686Y926181D01*
G01X1137207Y935958D02*
Y944619D01*
X1135908Y942887D01*
G01Y935958D02*
X1138506D01*
G01X1143486Y937690D02*
X1144136Y936680D01*
X1145002Y936102D01*
X1145976Y935958D01*
X1146842Y936102D01*
X1147709Y936824D01*
X1148250Y937690D01*
X1148358Y938556D01*
X1148142Y939567D01*
X1147384Y940288D01*
X1146626Y940577D01*
X1145651D01*
G01X1146626D02*
X1147275Y941010D01*
X1147817Y941732D01*
X1148033Y942598D01*
X1147817Y943464D01*
X1147275Y944186D01*
X1146301Y944619D01*
X1145327Y944475D01*
X1144352Y943897D01*
G01X1154529Y935958D02*
Y944619D01*
X1153230Y942887D01*
G01Y935958D02*
X1155828D01*
G01X1163190Y935669D02*
X1162973Y935814D01*
Y936102D01*
X1163190Y936247D01*
X1163407Y936102D01*
Y935814D01*
X1163190Y935669D01*
G01X1173150Y935958D02*
Y944619D01*
X1169144Y938412D01*
X1174558D01*
G01X1178130Y937690D02*
X1178780Y936680D01*
X1179646Y936102D01*
X1180620Y935958D01*
X1181486Y936102D01*
X1182353Y936824D01*
X1182894Y937690D01*
X1183002Y938556D01*
X1182786Y939567D01*
X1182028Y940288D01*
X1181270Y940577D01*
X1180295D01*
G01X1181270D02*
X1181919Y941010D01*
X1182461Y941732D01*
X1182677Y942598D01*
X1182461Y943464D01*
X1181919Y944186D01*
X1180945Y944619D01*
X1179971Y944475D01*
X1178996Y943897D01*
G01X1135897Y953675D02*
Y962336D01*
X1134598Y960604D01*
G01Y953675D02*
X1137196D01*
G01X1142176Y955407D02*
X1142826Y954397D01*
X1143692Y953819D01*
X1144666Y953675D01*
X1145532Y953819D01*
X1146399Y954541D01*
X1146940Y955407D01*
X1147048Y956273D01*
X1146832Y957284D01*
X1146074Y958005D01*
X1145316Y958294D01*
X1144341D01*
G01X1145316D02*
X1145965Y958727D01*
X1146507Y959449D01*
X1146723Y960315D01*
X1146507Y961181D01*
X1145965Y961903D01*
X1144991Y962336D01*
X1144017Y962192D01*
X1143042Y961614D01*
G01X1150837Y954974D02*
X1151487Y954252D01*
X1152245Y953819D01*
X1153219Y953675D01*
X1154193Y953964D01*
X1154951Y954541D01*
X1155493Y955551D01*
X1155601Y956706D01*
X1155384Y957861D01*
X1154843Y958583D01*
X1154085Y959160D01*
X1153327Y959305D01*
X1152569Y959160D01*
X1151595Y958583D01*
X1151920Y962336D01*
X1154843D01*
G01X1161880Y953386D02*
X1161663Y953531D01*
Y953819D01*
X1161880Y953964D01*
X1162097Y953819D01*
Y953531D01*
X1161880Y953386D01*
G01X1168700Y954685D02*
X1169458Y953964D01*
X1170324Y953675D01*
X1171191Y953964D01*
X1171948Y954830D01*
X1172490Y956129D01*
X1172706Y957428D01*
Y959016D01*
X1172490Y960315D01*
X1171948Y961470D01*
X1171299Y962047D01*
X1170541Y962336D01*
X1169675Y962047D01*
X1169025Y961470D01*
X1168592Y960604D01*
X1168376Y959449D01*
X1168592Y958439D01*
X1169134Y957428D01*
X1169783Y956851D01*
X1170541Y956706D01*
X1171407Y956995D01*
X1172057Y957717D01*
X1172706Y959016D01*
G01X1176820Y955407D02*
X1177470Y954397D01*
X1178336Y953819D01*
X1179310Y953675D01*
X1180176Y953819D01*
X1181043Y954541D01*
X1181584Y955407D01*
X1181692Y956273D01*
X1181476Y957284D01*
X1180718Y958005D01*
X1179960Y958294D01*
X1178985D01*
G01X1179960D02*
X1180609Y958727D01*
X1181151Y959449D01*
X1181367Y960315D01*
X1181151Y961181D01*
X1180609Y961903D01*
X1179635Y962336D01*
X1178661Y962192D01*
X1177686Y961614D01*
G01X1135897Y989383D02*
Y998044D01*
X1134598Y996312D01*
G01Y989383D02*
X1137196D01*
G01X1145857D02*
Y998044D01*
X1141851Y991837D01*
X1147265D01*
G01X1150837Y990682D02*
X1151487Y989960D01*
X1152245Y989527D01*
X1153219Y989383D01*
X1154193Y989672D01*
X1154951Y990249D01*
X1155493Y991259D01*
X1155601Y992414D01*
X1155384Y993569D01*
X1154843Y994291D01*
X1154085Y994868D01*
X1153327Y995013D01*
X1152569Y994868D01*
X1151595Y994291D01*
X1151920Y998044D01*
X1154843D01*
G01X1161880Y989094D02*
X1161663Y989239D01*
Y989527D01*
X1161880Y989672D01*
X1162097Y989527D01*
Y989239D01*
X1161880Y989094D01*
G01X1170541Y998044D02*
X1169675Y997755D01*
X1169025Y997034D01*
X1168592Y996168D01*
X1168267Y995013D01*
X1168159Y993713D01*
X1168267Y992414D01*
X1168592Y991259D01*
X1169025Y990393D01*
X1169675Y989672D01*
X1170541Y989383D01*
X1171407Y989672D01*
X1172057Y990393D01*
X1172490Y991259D01*
X1172815Y992414D01*
X1172923Y993713D01*
X1172815Y995013D01*
X1172490Y996168D01*
X1172057Y997034D01*
X1171407Y997755D01*
X1170541Y998044D01*
G01X1179202D02*
X1178336Y997755D01*
X1177686Y997034D01*
X1177253Y996168D01*
X1176928Y995013D01*
X1176820Y993713D01*
X1176928Y992414D01*
X1177253Y991259D01*
X1177686Y990393D01*
X1178336Y989672D01*
X1179202Y989383D01*
X1180068Y989672D01*
X1180718Y990393D01*
X1181151Y991259D01*
X1181476Y992414D01*
X1181584Y993713D01*
X1181476Y995013D01*
X1181151Y996168D01*
X1180718Y997034D01*
X1180068Y997755D01*
X1179202Y998044D01*
G01X1153769Y1022537D02*
X1156476Y1031198D01*
X1159183Y1022537D01*
G01X1158208Y1025568D02*
X1154744D01*
G01X1195470Y1134369D02*
X1194387Y1135813D01*
X1193846Y1137256D01*
Y1143030D01*
X1194387Y1144474D01*
X1195470Y1145917D01*
G01X1202507Y1137256D02*
Y1145917D01*
X1205105D01*
X1205971Y1145484D01*
X1206621Y1144474D01*
X1206837Y1143319D01*
X1206621Y1142164D01*
X1206079Y1141298D01*
X1205105Y1140865D01*
X1202507D01*
G01X1210626Y1137256D02*
X1213333Y1145917D01*
X1216040Y1137256D01*
G01X1215065Y1140287D02*
X1211601D01*
G01X1219612Y1137256D02*
Y1145917D01*
X1221777D01*
X1222644Y1145484D01*
X1223293Y1144907D01*
X1223835Y1144041D01*
X1224268Y1143030D01*
X1224376Y1141586D01*
X1224268Y1140143D01*
X1223835Y1139132D01*
X1223293Y1138266D01*
X1222644Y1137689D01*
X1221777Y1137256D01*
X1219612D01*
G01X1231196Y1134369D02*
X1232279Y1135813D01*
X1232820Y1137256D01*
Y1143030D01*
X1232279Y1144474D01*
X1231196Y1145917D01*
G01X1238775Y1134369D02*
X1237692Y1135813D01*
X1237151Y1137256D01*
Y1143030D01*
X1237692Y1144474D01*
X1238775Y1145917D01*
G01X1245487Y1137256D02*
Y1145917D01*
X1250467Y1137256D01*
Y1145917D01*
G01X1256638Y1137256D02*
X1255772Y1137400D01*
X1255014Y1137978D01*
X1254364Y1138844D01*
X1253931Y1139854D01*
X1253715Y1141009D01*
Y1142164D01*
X1253931Y1143319D01*
X1254364Y1144329D01*
X1255014Y1145195D01*
X1255772Y1145773D01*
X1256638Y1145917D01*
X1257504Y1145773D01*
X1258262Y1145195D01*
X1258912Y1144329D01*
X1259345Y1143319D01*
X1259561Y1142164D01*
Y1141009D01*
X1259345Y1139854D01*
X1258912Y1138844D01*
X1258262Y1137978D01*
X1257504Y1137400D01*
X1256638Y1137256D01*
G01X1273960Y1145917D02*
Y1137256D01*
G01X1271470Y1145917D02*
X1276450D01*
G01X1280456Y1137256D02*
Y1145917D01*
X1283162D01*
X1284028Y1145484D01*
X1284570Y1144907D01*
X1284786Y1143752D01*
X1284570Y1142597D01*
X1283920Y1141875D01*
X1283162Y1141442D01*
X1280456D01*
G01X1283162D02*
X1284786Y1137256D01*
G01X1288575D02*
X1291282Y1145917D01*
X1293989Y1137256D01*
G01X1293014Y1140287D02*
X1289550D01*
G01X1302325Y1145195D02*
X1301675Y1145628D01*
X1300917Y1145917D01*
X1300051D01*
X1299077Y1145484D01*
X1298319Y1144762D01*
X1297778Y1143896D01*
X1297344Y1142453D01*
X1297236Y1141153D01*
X1297453Y1139854D01*
X1297778Y1138988D01*
X1298427Y1138122D01*
X1299185Y1137545D01*
X1299943Y1137256D01*
X1300701D01*
X1301459Y1137545D01*
X1302108Y1137978D01*
X1302650Y1138555D01*
G01X1310769Y1137256D02*
X1306439D01*
Y1145917D01*
X1310769D01*
G01X1309037Y1141731D02*
X1306439D01*
G01X1323219Y1137256D02*
X1325926Y1145917D01*
X1328633Y1137256D01*
G01X1327658Y1140287D02*
X1324194D01*
G01X1334587Y1145917D02*
Y1137256D01*
G01X1332097Y1145917D02*
X1337077D01*
G01X1349202Y1137256D02*
X1351909Y1145917D01*
X1354616Y1137256D01*
G01X1353641Y1140287D02*
X1350177D01*
G01X1358405Y1145917D02*
Y1137256D01*
X1362735D01*
G01X1367066Y1145917D02*
Y1137256D01*
X1371396D01*
G01X1384388Y1145917D02*
Y1137256D01*
X1388718D01*
G01X1392507D02*
X1395214Y1145917D01*
X1397921Y1137256D01*
G01X1396946Y1140287D02*
X1393482D01*
G01X1403875Y1137256D02*
Y1141153D01*
X1401710Y1145917D01*
G01X1406040D02*
X1403875Y1141153D01*
G01X1414701Y1137256D02*
X1410371D01*
Y1145917D01*
X1414701D01*
G01X1412969Y1141731D02*
X1410371D01*
G01X1419032Y1137256D02*
Y1145917D01*
X1421738D01*
X1422604Y1145484D01*
X1423146Y1144907D01*
X1423362Y1143752D01*
X1423146Y1142597D01*
X1422496Y1141875D01*
X1421738Y1141442D01*
X1419032D01*
G01X1421738D02*
X1423362Y1137256D01*
G01X1427584Y1138411D02*
X1428451Y1137689D01*
X1429425Y1137256D01*
X1430291D01*
X1431157Y1137689D01*
X1431807Y1138411D01*
X1432132Y1139421D01*
X1431915Y1140432D01*
X1431374Y1141298D01*
X1430399Y1141875D01*
X1429100Y1142164D01*
X1428342Y1142741D01*
X1428017Y1143752D01*
X1428234Y1144762D01*
X1428775Y1145484D01*
X1429533Y1145917D01*
X1430291D01*
X1431049Y1145628D01*
X1431699Y1144907D01*
G01X1439060Y1134369D02*
X1440143Y1135813D01*
X1440684Y1137256D01*
Y1143030D01*
X1440143Y1144474D01*
X1439060Y1145917D01*
G01X1200721Y344069D02*
X1201010Y343203D01*
X1201731Y342553D01*
X1202597Y342120D01*
X1203752Y341795D01*
X1205052Y341687D01*
X1206351Y341795D01*
X1207506Y342120D01*
X1208372Y342553D01*
X1209093Y343203D01*
X1209382Y344069D01*
X1209093Y344935D01*
X1208372Y345585D01*
X1207506Y346018D01*
X1206351Y346343D01*
X1205052Y346451D01*
X1203752Y346343D01*
X1202597Y346018D01*
X1201731Y345585D01*
X1201010Y344935D01*
X1200721Y344069D01*
G01X1209671Y352730D02*
X1209526Y352513D01*
X1209238D01*
X1209093Y352730D01*
X1209238Y352947D01*
X1209526D01*
X1209671Y352730D01*
G01X1200721Y361391D02*
X1201010Y360525D01*
X1201731Y359875D01*
X1202597Y359442D01*
X1203752Y359117D01*
X1205052Y359009D01*
X1206351Y359117D01*
X1207506Y359442D01*
X1208372Y359875D01*
X1209093Y360525D01*
X1209382Y361391D01*
X1209093Y362257D01*
X1208372Y362907D01*
X1207506Y363340D01*
X1206351Y363665D01*
X1205052Y363773D01*
X1203752Y363665D01*
X1202597Y363340D01*
X1201731Y362907D01*
X1201010Y362257D01*
X1200721Y361391D01*
G01Y370052D02*
X1201010Y369186D01*
X1201731Y368536D01*
X1202597Y368103D01*
X1203752Y367778D01*
X1205052Y367670D01*
X1206351Y367778D01*
X1207506Y368103D01*
X1208372Y368536D01*
X1209093Y369186D01*
X1209382Y370052D01*
X1209093Y370918D01*
X1208372Y371568D01*
X1207506Y372001D01*
X1206351Y372326D01*
X1205052Y372434D01*
X1203752Y372326D01*
X1202597Y372001D01*
X1201731Y371568D01*
X1201010Y370918D01*
X1200721Y370052D01*
G01X1245774Y1030810D02*
X1246495Y1031568D01*
X1246784Y1032434D01*
X1246495Y1033301D01*
X1245629Y1034058D01*
X1244330Y1034600D01*
X1243031Y1034816D01*
X1241443D01*
X1240144Y1034600D01*
X1238989Y1034058D01*
X1238412Y1033409D01*
X1238123Y1032651D01*
X1238412Y1031785D01*
X1238989Y1031135D01*
X1239855Y1030702D01*
X1241010Y1030486D01*
X1242020Y1030702D01*
X1243031Y1031244D01*
X1243608Y1031893D01*
X1243753Y1032651D01*
X1243464Y1033517D01*
X1242742Y1034167D01*
X1241443Y1034816D01*
G01X1247073Y1041312D02*
X1246928Y1041095D01*
X1246640D01*
X1246495Y1041312D01*
X1246640Y1041529D01*
X1246928D01*
X1247073Y1041312D01*
G01X1245485Y1047591D02*
X1246207Y1048241D01*
X1246640Y1048999D01*
X1246784Y1049973D01*
X1246495Y1050947D01*
X1245918Y1051705D01*
X1244908Y1052247D01*
X1243753Y1052355D01*
X1242598Y1052138D01*
X1241876Y1051597D01*
X1241299Y1050839D01*
X1241154Y1050081D01*
X1241299Y1049323D01*
X1241876Y1048349D01*
X1238123Y1048674D01*
Y1051597D01*
G01Y1058634D02*
X1238412Y1057768D01*
X1239133Y1057118D01*
X1239999Y1056685D01*
X1241154Y1056360D01*
X1242454Y1056252D01*
X1243753Y1056360D01*
X1244908Y1056685D01*
X1245774Y1057118D01*
X1246495Y1057768D01*
X1246784Y1058634D01*
X1246495Y1059500D01*
X1245774Y1060150D01*
X1244908Y1060583D01*
X1243753Y1060908D01*
X1242454Y1061016D01*
X1241154Y1060908D01*
X1239999Y1060583D01*
X1239133Y1060150D01*
X1238412Y1059500D01*
X1238123Y1058634D01*
G01X1245052Y1038930D02*
X1246062Y1039580D01*
X1246640Y1040446D01*
X1246784Y1041420D01*
X1246640Y1042286D01*
X1245918Y1043153D01*
X1245052Y1043694D01*
X1244186Y1043802D01*
X1243175Y1043586D01*
X1242454Y1042828D01*
X1242165Y1042070D01*
Y1041095D01*
G01Y1042070D02*
X1241732Y1042719D01*
X1241010Y1043261D01*
X1240144Y1043477D01*
X1239278Y1043261D01*
X1238556Y1042719D01*
X1238123Y1041745D01*
X1238267Y1040771D01*
X1238845Y1039796D01*
G01X1243897Y1048566D02*
Y1051380D01*
G01X1284882Y-894995D02*
X1285876Y-894806D01*
X1287012Y-894238D01*
X1287723Y-893291D01*
X1288007Y-891965D01*
X1287723Y-890640D01*
X1286870Y-889503D01*
X1285592Y-888935D01*
X1284172D01*
X1283320Y-888557D01*
X1282609Y-887610D01*
X1282325Y-886284D01*
X1282752Y-884959D01*
X1283746Y-884012D01*
X1284882Y-883633D01*
X1286018Y-884012D01*
X1287012Y-884959D01*
X1287439Y-886284D01*
X1287154Y-887610D01*
X1286444Y-888557D01*
X1285592Y-888935D01*
X1284172D01*
X1282894Y-889503D01*
X1282041Y-890640D01*
X1281757Y-891965D01*
X1282041Y-893291D01*
X1282752Y-894238D01*
X1283888Y-894806D01*
X1284882Y-894995D01*
G01X1308053Y-606501D02*
X1307188Y-605851D01*
X1306754Y-605094D01*
X1306610Y-604227D01*
X1306899Y-603145D01*
X1307620Y-602387D01*
X1308486Y-602170D01*
X1309353Y-602279D01*
X1310074Y-602712D01*
X1311518Y-604877D01*
X1312528Y-605851D01*
X1313972Y-606501D01*
X1315271Y-606718D01*
Y-602170D01*
G01X1312384Y-597190D02*
Y-594376D01*
G01X1308053Y-619492D02*
X1307188Y-618842D01*
X1306754Y-618085D01*
X1306610Y-617218D01*
X1306899Y-616136D01*
X1307620Y-615378D01*
X1308486Y-615161D01*
X1309353Y-615270D01*
X1310074Y-615703D01*
X1311518Y-617868D01*
X1312528Y-618842D01*
X1313972Y-619492D01*
X1315271Y-619709D01*
Y-615161D01*
G01X1314261Y-610615D02*
X1314982Y-609857D01*
X1315271Y-608991D01*
X1314982Y-608124D01*
X1314116Y-607367D01*
X1312817Y-606825D01*
X1311518Y-606609D01*
X1309930D01*
X1308631Y-606825D01*
X1307476Y-607367D01*
X1306899Y-608016D01*
X1306610Y-608774D01*
X1306899Y-609640D01*
X1307476Y-610290D01*
X1308342Y-610723D01*
X1309497Y-610939D01*
X1310507Y-610723D01*
X1311518Y-610181D01*
X1312095Y-609532D01*
X1312240Y-608774D01*
X1311951Y-607908D01*
X1311229Y-607258D01*
X1309930Y-606609D01*
G01X1315560Y-600113D02*
X1315415Y-600330D01*
X1315127D01*
X1314982Y-600113D01*
X1315127Y-599896D01*
X1315415D01*
X1315560Y-600113D01*
G01X1315271Y-590153D02*
X1306610D01*
X1312817Y-594159D01*
Y-588745D01*
G01X1315271Y-582791D02*
X1315127Y-582033D01*
X1314694Y-581167D01*
X1313972Y-580626D01*
X1312961Y-580409D01*
X1311951Y-580626D01*
X1311085Y-581275D01*
X1310652Y-582250D01*
Y-583332D01*
X1310363Y-583982D01*
X1309641Y-584523D01*
X1308631Y-584740D01*
X1307620Y-584415D01*
X1306899Y-583657D01*
X1306610Y-582791D01*
X1306899Y-581925D01*
X1307620Y-581167D01*
X1308631Y-580842D01*
X1309641Y-581059D01*
X1310363Y-581600D01*
X1310652Y-582250D01*
Y-583332D01*
X1311085Y-584307D01*
X1311951Y-584956D01*
X1312961Y-585173D01*
X1313972Y-584956D01*
X1314694Y-584415D01*
X1315127Y-583549D01*
X1315271Y-582791D01*
G01X1315424Y1137256D02*
Y1143030D01*
G01Y1141586D02*
X1315858Y1142308D01*
X1316507Y1142886D01*
X1317373Y1143030D01*
X1318131Y1142886D01*
X1318781Y1142308D01*
X1319106Y1141298D01*
Y1137256D01*
G01X1302432Y1138266D02*
X1303190Y1137545D01*
X1304056Y1137256D01*
X1304923Y1137545D01*
X1305680Y1138411D01*
X1306222Y1139710D01*
X1306438Y1141009D01*
Y1142597D01*
X1306222Y1143896D01*
X1305680Y1145051D01*
X1305031Y1145628D01*
X1304273Y1145917D01*
X1303407Y1145628D01*
X1302757Y1145051D01*
X1302324Y1144185D01*
X1302108Y1143030D01*
X1302324Y1142020D01*
X1302866Y1141009D01*
X1303515Y1140432D01*
X1304273Y1140287D01*
X1305139Y1140576D01*
X1305789Y1141298D01*
X1306438Y1142597D01*
G01X1312934Y1136967D02*
X1312717Y1137112D01*
Y1137400D01*
X1312934Y1137545D01*
X1313151Y1137400D01*
Y1137112D01*
X1312934Y1136967D01*
G01X1319213Y1138555D02*
X1319863Y1137833D01*
X1320621Y1137400D01*
X1321595Y1137256D01*
X1322569Y1137545D01*
X1323327Y1138122D01*
X1323869Y1139132D01*
X1323977Y1140287D01*
X1323760Y1141442D01*
X1323219Y1142164D01*
X1322461Y1142741D01*
X1321703Y1142886D01*
X1320945Y1142741D01*
X1319971Y1142164D01*
X1320296Y1145917D01*
X1323219D01*
G01X1330256D02*
X1329390Y1145628D01*
X1328740Y1144907D01*
X1328307Y1144041D01*
X1327982Y1142886D01*
X1327874Y1141586D01*
X1327982Y1140287D01*
X1328307Y1139132D01*
X1328740Y1138266D01*
X1329390Y1137545D01*
X1330256Y1137256D01*
X1331122Y1137545D01*
X1331772Y1138266D01*
X1332205Y1139132D01*
X1332530Y1140287D01*
X1332638Y1141586D01*
X1332530Y1142886D01*
X1332205Y1144041D01*
X1331772Y1144907D01*
X1331122Y1145628D01*
X1330256Y1145917D01*
G01X1284882Y1282761D02*
X1285876Y1282950D01*
X1287012Y1283518D01*
X1287723Y1284465D01*
X1288007Y1285791D01*
X1287723Y1287116D01*
X1286870Y1288253D01*
X1285592Y1288821D01*
X1284172D01*
X1283320Y1289199D01*
X1282609Y1290146D01*
X1282325Y1291472D01*
X1282752Y1292797D01*
X1283746Y1293744D01*
X1284882Y1294123D01*
X1286018Y1293744D01*
X1287012Y1292797D01*
X1287439Y1291472D01*
X1287154Y1290146D01*
X1286444Y1289199D01*
X1285592Y1288821D01*
X1284172D01*
X1282894Y1288253D01*
X1282041Y1287116D01*
X1281757Y1285791D01*
X1282041Y1284465D01*
X1282752Y1283518D01*
X1283888Y1282950D01*
X1284882Y1282761D01*
G01X1367163Y-387907D02*
X1366080Y-386463D01*
X1365539Y-385020D01*
Y-379246D01*
X1366080Y-377802D01*
X1367163Y-376359D01*
G01X1373875Y-385020D02*
Y-376359D01*
X1378855Y-385020D01*
Y-376359D01*
G01X1385026Y-385020D02*
X1384160Y-384876D01*
X1383402Y-384298D01*
X1382752Y-383432D01*
X1382319Y-382422D01*
X1382103Y-381267D01*
Y-380112D01*
X1382319Y-378957D01*
X1382752Y-377947D01*
X1383402Y-377081D01*
X1384160Y-376503D01*
X1385026Y-376359D01*
X1385892Y-376503D01*
X1386650Y-377081D01*
X1387300Y-377947D01*
X1387733Y-378957D01*
X1387949Y-380112D01*
Y-381267D01*
X1387733Y-382422D01*
X1387300Y-383432D01*
X1386650Y-384298D01*
X1385892Y-384876D01*
X1385026Y-385020D01*
G01X1402348Y-376359D02*
Y-385020D01*
G01X1399858Y-376359D02*
X1404838D01*
G01X1408844Y-385020D02*
Y-376359D01*
X1411550D01*
X1412416Y-376792D01*
X1412958Y-377369D01*
X1413174Y-378524D01*
X1412958Y-379679D01*
X1412308Y-380401D01*
X1411550Y-380834D01*
X1408844D01*
G01X1411550D02*
X1413174Y-385020D01*
G01X1416963D02*
X1419670Y-376359D01*
X1422377Y-385020D01*
G01X1421402Y-381989D02*
X1417938D01*
G01X1430713Y-377081D02*
X1430063Y-376648D01*
X1429305Y-376359D01*
X1428439D01*
X1427465Y-376792D01*
X1426707Y-377514D01*
X1426166Y-378380D01*
X1425732Y-379823D01*
X1425624Y-381123D01*
X1425841Y-382422D01*
X1426166Y-383288D01*
X1426815Y-384154D01*
X1427573Y-384731D01*
X1428331Y-385020D01*
X1429089D01*
X1429847Y-384731D01*
X1430496Y-384298D01*
X1431038Y-383721D01*
G01X1439157Y-385020D02*
X1434827D01*
Y-376359D01*
X1439157D01*
G01X1437425Y-380545D02*
X1434827D01*
G01X1451607Y-385020D02*
X1454314Y-376359D01*
X1457021Y-385020D01*
G01X1456046Y-381989D02*
X1452582D01*
G01X1462975Y-376359D02*
Y-385020D01*
G01X1460485Y-376359D02*
X1465465D01*
G01X1477590Y-385020D02*
X1480297Y-376359D01*
X1483004Y-385020D01*
G01X1482029Y-381989D02*
X1478565D01*
G01X1486793Y-376359D02*
Y-385020D01*
X1491123D01*
G01X1495454Y-376359D02*
Y-385020D01*
X1499784D01*
G01X1512776Y-376359D02*
Y-385020D01*
X1517106D01*
G01X1520895D02*
X1523602Y-376359D01*
X1526309Y-385020D01*
G01X1525334Y-381989D02*
X1521870D01*
G01X1532263Y-385020D02*
Y-381123D01*
X1530098Y-376359D01*
G01X1534428D02*
X1532263Y-381123D01*
G01X1543089Y-385020D02*
X1538759D01*
Y-376359D01*
X1543089D01*
G01X1541357Y-380545D02*
X1538759D01*
G01X1547420Y-385020D02*
Y-376359D01*
X1550126D01*
X1550992Y-376792D01*
X1551534Y-377369D01*
X1551750Y-378524D01*
X1551534Y-379679D01*
X1550884Y-380401D01*
X1550126Y-380834D01*
X1547420D01*
G01X1550126D02*
X1551750Y-385020D01*
G01X1555972Y-383865D02*
X1556839Y-384587D01*
X1557813Y-385020D01*
X1558679D01*
X1559545Y-384587D01*
X1560195Y-383865D01*
X1560520Y-382855D01*
X1560303Y-381844D01*
X1559762Y-380978D01*
X1558787Y-380401D01*
X1557488Y-380112D01*
X1556730Y-379535D01*
X1556405Y-378524D01*
X1556622Y-377514D01*
X1557163Y-376792D01*
X1557921Y-376359D01*
X1558679D01*
X1559437Y-376648D01*
X1560087Y-377369D01*
G01X1567448Y-387907D02*
X1568531Y-386463D01*
X1569072Y-385020D01*
Y-379246D01*
X1568531Y-377802D01*
X1567448Y-376359D01*
G01X1330950Y211239D02*
X1329867Y212683D01*
X1329326Y214126D01*
Y219900D01*
X1329867Y221344D01*
X1330950Y222787D01*
G01X1337987Y214126D02*
Y222787D01*
X1340585D01*
X1341451Y222354D01*
X1342101Y221344D01*
X1342317Y220189D01*
X1342101Y219034D01*
X1341559Y218168D01*
X1340585Y217735D01*
X1337987D01*
G01X1346106Y214126D02*
X1348813Y222787D01*
X1351520Y214126D01*
G01X1350545Y217157D02*
X1347081D01*
G01X1355092Y214126D02*
Y222787D01*
X1357257D01*
X1358124Y222354D01*
X1358773Y221777D01*
X1359315Y220911D01*
X1359748Y219900D01*
X1359856Y218456D01*
X1359748Y217013D01*
X1359315Y216002D01*
X1358773Y215136D01*
X1358124Y214559D01*
X1357257Y214126D01*
X1355092D01*
G01X1366676Y211239D02*
X1367759Y212683D01*
X1368300Y214126D01*
Y219900D01*
X1367759Y221344D01*
X1366676Y222787D01*
G01X1374255Y211239D02*
X1373172Y212683D01*
X1372631Y214126D01*
Y219900D01*
X1373172Y221344D01*
X1374255Y222787D01*
G01X1380967Y214126D02*
Y222787D01*
X1385947Y214126D01*
Y222787D01*
G01X1392118Y214126D02*
X1391252Y214270D01*
X1390494Y214848D01*
X1389844Y215714D01*
X1389411Y216724D01*
X1389195Y217879D01*
Y219034D01*
X1389411Y220189D01*
X1389844Y221199D01*
X1390494Y222065D01*
X1391252Y222643D01*
X1392118Y222787D01*
X1392984Y222643D01*
X1393742Y222065D01*
X1394392Y221199D01*
X1394825Y220189D01*
X1395041Y219034D01*
Y217879D01*
X1394825Y216724D01*
X1394392Y215714D01*
X1393742Y214848D01*
X1392984Y214270D01*
X1392118Y214126D01*
G01X1409440Y222787D02*
Y214126D01*
G01X1406950Y222787D02*
X1411930D01*
G01X1415936Y214126D02*
Y222787D01*
X1418642D01*
X1419508Y222354D01*
X1420050Y221777D01*
X1420266Y220622D01*
X1420050Y219467D01*
X1419400Y218745D01*
X1418642Y218312D01*
X1415936D01*
G01X1418642D02*
X1420266Y214126D01*
G01X1424055D02*
X1426762Y222787D01*
X1429469Y214126D01*
G01X1428494Y217157D02*
X1425030D01*
G01X1437805Y222065D02*
X1437155Y222498D01*
X1436397Y222787D01*
X1435531D01*
X1434557Y222354D01*
X1433799Y221632D01*
X1433258Y220766D01*
X1432824Y219323D01*
X1432716Y218023D01*
X1432933Y216724D01*
X1433258Y215858D01*
X1433907Y214992D01*
X1434665Y214415D01*
X1435423Y214126D01*
X1436181D01*
X1436939Y214415D01*
X1437588Y214848D01*
X1438130Y215425D01*
G01X1446249Y214126D02*
X1441919D01*
Y222787D01*
X1446249D01*
G01X1444517Y218601D02*
X1441919D01*
G01X1458699Y214126D02*
X1461406Y222787D01*
X1464113Y214126D01*
G01X1463138Y217157D02*
X1459674D01*
G01X1470067Y222787D02*
Y214126D01*
G01X1467577Y222787D02*
X1472557D01*
G01X1484682Y214126D02*
X1487389Y222787D01*
X1490096Y214126D01*
G01X1489121Y217157D02*
X1485657D01*
G01X1493885Y222787D02*
Y214126D01*
X1498215D01*
G01X1502546Y222787D02*
Y214126D01*
X1506876D01*
G01X1519868Y222787D02*
Y214126D01*
X1524198D01*
G01X1527987D02*
X1530694Y222787D01*
X1533401Y214126D01*
G01X1532426Y217157D02*
X1528962D01*
G01X1539355Y214126D02*
Y218023D01*
X1537190Y222787D01*
G01X1541520D02*
X1539355Y218023D01*
G01X1550181Y214126D02*
X1545851D01*
Y222787D01*
X1550181D01*
G01X1548449Y218601D02*
X1545851D01*
G01X1554512Y214126D02*
Y222787D01*
X1557218D01*
X1558084Y222354D01*
X1558626Y221777D01*
X1558842Y220622D01*
X1558626Y219467D01*
X1557976Y218745D01*
X1557218Y218312D01*
X1554512D01*
G01X1557218D02*
X1558842Y214126D01*
G01X1563064Y215281D02*
X1563931Y214559D01*
X1564905Y214126D01*
X1565771D01*
X1566637Y214559D01*
X1567287Y215281D01*
X1567612Y216291D01*
X1567395Y217302D01*
X1566854Y218168D01*
X1565879Y218745D01*
X1564580Y219034D01*
X1563822Y219611D01*
X1563497Y220622D01*
X1563714Y221632D01*
X1564255Y222354D01*
X1565013Y222787D01*
X1565771D01*
X1566529Y222498D01*
X1567179Y221777D01*
G01X1584825Y214126D02*
X1580495D01*
Y222787D01*
X1584825D01*
G01X1583093Y218601D02*
X1580495D01*
G01X1589047Y214126D02*
X1593595Y222787D01*
G01X1589047D02*
X1593595Y214126D01*
G01X1602364Y222065D02*
X1601714Y222498D01*
X1600956Y222787D01*
X1600090D01*
X1599116Y222354D01*
X1598358Y221632D01*
X1597817Y220766D01*
X1597383Y219323D01*
X1597275Y218023D01*
X1597492Y216724D01*
X1597817Y215858D01*
X1598466Y214992D01*
X1599224Y214415D01*
X1599982Y214126D01*
X1600740D01*
X1601498Y214415D01*
X1602147Y214848D01*
X1602689Y215425D01*
G01X1610808Y214126D02*
X1606478D01*
Y222787D01*
X1610808D01*
G01X1609076Y218601D02*
X1606478D01*
G01X1615139Y214126D02*
Y222787D01*
X1617737D01*
X1618603Y222354D01*
X1619253Y221344D01*
X1619469Y220189D01*
X1619253Y219034D01*
X1618711Y218168D01*
X1617737Y217735D01*
X1615139D01*
G01X1625965Y222787D02*
Y214126D01*
G01X1623475Y222787D02*
X1628455D01*
G01X1643937Y218456D02*
X1646102D01*
Y215858D01*
X1645452Y214992D01*
X1644694Y214415D01*
X1643612Y214126D01*
X1642529Y214415D01*
X1641771Y214992D01*
X1641122Y215858D01*
X1640688Y216869D01*
X1640472Y218023D01*
Y219034D01*
X1640688Y219900D01*
X1641122Y220911D01*
X1641771Y221777D01*
X1642421Y222354D01*
X1643287Y222787D01*
X1644045D01*
X1644911Y222498D01*
X1645561Y221921D01*
G01X1649458Y214126D02*
Y222787D01*
X1654438Y214126D01*
Y222787D01*
G01X1658227Y214126D02*
Y222787D01*
X1660392D01*
X1661259Y222354D01*
X1661908Y221777D01*
X1662450Y220911D01*
X1662883Y219900D01*
X1662991Y218456D01*
X1662883Y217013D01*
X1662450Y216002D01*
X1661908Y215136D01*
X1661259Y214559D01*
X1660392Y214126D01*
X1658227D01*
G01X1669811Y211239D02*
X1670894Y212683D01*
X1671435Y214126D01*
Y219900D01*
X1670894Y221344D01*
X1669811Y222787D01*
G01X1406149Y-537102D02*
X1405066Y-535658D01*
X1404525Y-534215D01*
Y-528441D01*
X1405066Y-526997D01*
X1406149Y-525554D01*
G01X1412861Y-534215D02*
Y-525554D01*
X1417841Y-534215D01*
Y-525554D01*
G01X1421847Y-534215D02*
Y-525554D01*
X1424445D01*
X1425311Y-525987D01*
X1425961Y-526997D01*
X1426177Y-528152D01*
X1425961Y-529307D01*
X1425419Y-530173D01*
X1424445Y-530606D01*
X1421847D01*
G01X1432673Y-525554D02*
Y-534215D01*
G01X1430183Y-525554D02*
X1435163D01*
G01X1439060Y-534215D02*
Y-525554D01*
G01X1443608D02*
Y-534215D01*
G01Y-529885D02*
X1439060D01*
G01X1450536Y-537102D02*
X1451619Y-535658D01*
X1452160Y-534215D01*
Y-528441D01*
X1451619Y-526997D01*
X1450536Y-525554D01*
G01X1426502Y-534215D02*
Y-528441D01*
G01Y-529885D02*
X1426936Y-529163D01*
X1427585Y-528585D01*
X1428451Y-528441D01*
X1429209Y-528585D01*
X1429859Y-529163D01*
X1430184Y-530173D01*
Y-534215D01*
G01X1413294Y-526997D02*
X1413944Y-526132D01*
X1414701Y-525698D01*
X1415568Y-525554D01*
X1416650Y-525843D01*
X1417408Y-526564D01*
X1417625Y-527430D01*
X1417516Y-528297D01*
X1417083Y-529018D01*
X1414918Y-530462D01*
X1413944Y-531472D01*
X1413294Y-532916D01*
X1413077Y-534215D01*
X1417625D01*
G01X1424012Y-534504D02*
X1423795Y-534359D01*
Y-534071D01*
X1424012Y-533926D01*
X1424229Y-534071D01*
Y-534359D01*
X1424012Y-534504D01*
G01X1433972Y-534215D02*
Y-525554D01*
X1429966Y-531761D01*
X1435380D01*
G01X1441334Y-534215D02*
Y-525554D01*
X1440035Y-527286D01*
G01Y-534215D02*
X1442633D01*
G01X1402663Y-434789D02*
X1401580Y-433345D01*
X1401039Y-431902D01*
Y-426128D01*
X1401580Y-424684D01*
X1402663Y-423241D01*
G01X1409375Y-431902D02*
Y-423241D01*
X1414355Y-431902D01*
Y-423241D01*
G01X1418361Y-431902D02*
Y-423241D01*
X1420959D01*
X1421825Y-423674D01*
X1422475Y-424684D01*
X1422691Y-425839D01*
X1422475Y-426994D01*
X1421933Y-427860D01*
X1420959Y-428293D01*
X1418361D01*
G01X1429187Y-423241D02*
Y-431902D01*
G01X1426697Y-423241D02*
X1431677D01*
G01X1435574Y-431902D02*
Y-423241D01*
G01X1440122D02*
Y-431902D01*
G01Y-427572D02*
X1435574D01*
G01X1447050Y-434789D02*
X1448133Y-433345D01*
X1448674Y-431902D01*
Y-426128D01*
X1448133Y-424684D01*
X1447050Y-423241D01*
G01X1423016Y-431902D02*
Y-426128D01*
G01Y-427572D02*
X1423450Y-426850D01*
X1424099Y-426272D01*
X1424965Y-426128D01*
X1425723Y-426272D01*
X1426373Y-426850D01*
X1426698Y-427860D01*
Y-431902D01*
G01X1409808Y-424684D02*
X1410458Y-423819D01*
X1411215Y-423385D01*
X1412082Y-423241D01*
X1413164Y-423530D01*
X1413922Y-424251D01*
X1414139Y-425117D01*
X1414030Y-425984D01*
X1413597Y-426705D01*
X1411432Y-428149D01*
X1410458Y-429159D01*
X1409808Y-430603D01*
X1409591Y-431902D01*
X1414139D01*
G01X1420526Y-432191D02*
X1420309Y-432046D01*
Y-431758D01*
X1420526Y-431613D01*
X1420743Y-431758D01*
Y-432046D01*
X1420526Y-432191D01*
G01X1426805Y-430603D02*
X1427455Y-431325D01*
X1428213Y-431758D01*
X1429187Y-431902D01*
X1430161Y-431613D01*
X1430919Y-431036D01*
X1431461Y-430026D01*
X1431569Y-428871D01*
X1431352Y-427716D01*
X1430811Y-426994D01*
X1430053Y-426417D01*
X1429295Y-426272D01*
X1428537Y-426417D01*
X1427563Y-426994D01*
X1427888Y-423241D01*
X1430811D01*
G01X1435466Y-430603D02*
X1436116Y-431325D01*
X1436874Y-431758D01*
X1437848Y-431902D01*
X1438822Y-431613D01*
X1439580Y-431036D01*
X1440122Y-430026D01*
X1440230Y-428871D01*
X1440013Y-427716D01*
X1439472Y-426994D01*
X1438714Y-426417D01*
X1437956Y-426272D01*
X1437198Y-426417D01*
X1436224Y-426994D01*
X1436549Y-423241D01*
X1439472D01*
G01X1388256Y1008532D02*
X1387173Y1009976D01*
X1386632Y1011419D01*
Y1017193D01*
X1387173Y1018637D01*
X1388256Y1020080D01*
G01X1395293Y1011419D02*
Y1020080D01*
X1397891D01*
X1398757Y1019647D01*
X1399407Y1018637D01*
X1399623Y1017482D01*
X1399407Y1016327D01*
X1398865Y1015461D01*
X1397891Y1015028D01*
X1395293D01*
G01X1406119Y1020080D02*
Y1011419D01*
G01X1403629Y1020080D02*
X1408609D01*
G01X1412506Y1011419D02*
Y1020080D01*
G01X1417054D02*
Y1011419D01*
G01Y1015749D02*
X1412506D01*
G01X1423982Y1008532D02*
X1425065Y1009976D01*
X1425606Y1011419D01*
Y1017193D01*
X1425065Y1018637D01*
X1423982Y1020080D01*
G01X1404278Y1011419D02*
Y1017193D01*
G01Y1015749D02*
X1404712Y1016471D01*
X1405361Y1017049D01*
X1406227Y1017193D01*
X1406985Y1017049D01*
X1407635Y1016471D01*
X1407960Y1015461D01*
Y1011419D01*
G01X1390745Y1013151D02*
X1391395Y1012141D01*
X1392261Y1011563D01*
X1393235Y1011419D01*
X1394101Y1011563D01*
X1394968Y1012285D01*
X1395509Y1013151D01*
X1395617Y1014017D01*
X1395401Y1015028D01*
X1394643Y1015749D01*
X1393885Y1016038D01*
X1392910D01*
G01X1393885D02*
X1394534Y1016471D01*
X1395076Y1017193D01*
X1395292Y1018059D01*
X1395076Y1018925D01*
X1394534Y1019647D01*
X1393560Y1020080D01*
X1392586Y1019936D01*
X1391611Y1019358D01*
G01X1401788Y1011130D02*
X1401571Y1011275D01*
Y1011563D01*
X1401788Y1011708D01*
X1402005Y1011563D01*
Y1011275D01*
X1401788Y1011130D01*
G01X1408067Y1012718D02*
X1408717Y1011996D01*
X1409475Y1011563D01*
X1410449Y1011419D01*
X1411423Y1011708D01*
X1412181Y1012285D01*
X1412723Y1013295D01*
X1412831Y1014450D01*
X1412614Y1015605D01*
X1412073Y1016327D01*
X1411315Y1016904D01*
X1410557Y1017049D01*
X1409799Y1016904D01*
X1408825Y1016327D01*
X1409150Y1020080D01*
X1412073D01*
G01X1419110D02*
X1418244Y1019791D01*
X1417594Y1019070D01*
X1417161Y1018204D01*
X1416836Y1017049D01*
X1416728Y1015749D01*
X1416836Y1014450D01*
X1417161Y1013295D01*
X1417594Y1012429D01*
X1418244Y1011708D01*
X1419110Y1011419D01*
X1419976Y1011708D01*
X1420626Y1012429D01*
X1421059Y1013295D01*
X1421384Y1014450D01*
X1421492Y1015749D01*
X1421384Y1017049D01*
X1421059Y1018204D01*
X1420626Y1019070D01*
X1419976Y1019791D01*
X1419110Y1020080D01*
G01X1502136Y-893670D02*
X1503131Y-894616D01*
X1504267Y-894995D01*
X1505403Y-894616D01*
X1506397Y-893480D01*
X1507108Y-891776D01*
X1507392Y-890071D01*
Y-887989D01*
X1507108Y-886284D01*
X1506397Y-884769D01*
X1505545Y-884012D01*
X1504551Y-883633D01*
X1503415Y-884012D01*
X1502563Y-884769D01*
X1501994Y-885905D01*
X1501710Y-887421D01*
X1501994Y-888746D01*
X1502705Y-890071D01*
X1503557Y-890829D01*
X1504551Y-891018D01*
X1505687Y-890640D01*
X1506539Y-889693D01*
X1507392Y-887989D01*
G01X1465465Y-385020D02*
Y-379246D01*
G01Y-380690D02*
X1465899Y-379968D01*
X1466548Y-379390D01*
X1467414Y-379246D01*
X1468172Y-379390D01*
X1468822Y-379968D01*
X1469147Y-380978D01*
Y-385020D01*
G01X1454097D02*
X1454314Y-383144D01*
X1454639Y-381556D01*
X1455072Y-380112D01*
X1455613Y-378524D01*
X1456479Y-376359D01*
X1452149D01*
G01X1462975Y-385309D02*
X1462758Y-385164D01*
Y-384876D01*
X1462975Y-384731D01*
X1463192Y-384876D01*
Y-385164D01*
X1462975Y-385309D01*
G01X1471636Y-376359D02*
X1470770Y-376648D01*
X1470120Y-377369D01*
X1469687Y-378235D01*
X1469362Y-379390D01*
X1469254Y-380690D01*
X1469362Y-381989D01*
X1469687Y-383144D01*
X1470120Y-384010D01*
X1470770Y-384731D01*
X1471636Y-385020D01*
X1472502Y-384731D01*
X1473152Y-384010D01*
X1473585Y-383144D01*
X1473910Y-381989D01*
X1474018Y-380690D01*
X1473910Y-379390D01*
X1473585Y-378235D01*
X1473152Y-377369D01*
X1472502Y-376648D01*
X1471636Y-376359D01*
G01X1480297D02*
X1479431Y-376648D01*
X1478781Y-377369D01*
X1478348Y-378235D01*
X1478023Y-379390D01*
X1477915Y-380690D01*
X1478023Y-381989D01*
X1478348Y-383144D01*
X1478781Y-384010D01*
X1479431Y-384731D01*
X1480297Y-385020D01*
X1481163Y-384731D01*
X1481813Y-384010D01*
X1482246Y-383144D01*
X1482571Y-381989D01*
X1482679Y-380690D01*
X1482571Y-379390D01*
X1482246Y-378235D01*
X1481813Y-377369D01*
X1481163Y-376648D01*
X1480297Y-376359D01*
G01X1483059Y214126D02*
Y222787D01*
X1481760Y221055D01*
G01Y214126D02*
X1484358D01*
G01X1491720D02*
X1492478Y214270D01*
X1493344Y214703D01*
X1493885Y215425D01*
X1494102Y216436D01*
X1493885Y217446D01*
X1493236Y218312D01*
X1492261Y218745D01*
X1491179D01*
X1490529Y219034D01*
X1489988Y219756D01*
X1489771Y220766D01*
X1490096Y221777D01*
X1490854Y222498D01*
X1491720Y222787D01*
X1492586Y222498D01*
X1493344Y221777D01*
X1493669Y220766D01*
X1493452Y219756D01*
X1492911Y219034D01*
X1492261Y218745D01*
X1491179D01*
X1490204Y218312D01*
X1489555Y217446D01*
X1489338Y216436D01*
X1489555Y215425D01*
X1490096Y214703D01*
X1490962Y214270D01*
X1491720Y214126D01*
G01X1500381Y213837D02*
X1500164Y213982D01*
Y214270D01*
X1500381Y214415D01*
X1500598Y214270D01*
Y213982D01*
X1500381Y213837D01*
G01X1509042Y222787D02*
X1508176Y222498D01*
X1507526Y221777D01*
X1507093Y220911D01*
X1506768Y219756D01*
X1506660Y218456D01*
X1506768Y217157D01*
X1507093Y216002D01*
X1507526Y215136D01*
X1508176Y214415D01*
X1509042Y214126D01*
X1509908Y214415D01*
X1510558Y215136D01*
X1510991Y216002D01*
X1511316Y217157D01*
X1511424Y218456D01*
X1511316Y219756D01*
X1510991Y220911D01*
X1510558Y221777D01*
X1509908Y222498D01*
X1509042Y222787D01*
G01X1517703D02*
X1516837Y222498D01*
X1516187Y221777D01*
X1515754Y220911D01*
X1515429Y219756D01*
X1515321Y218456D01*
X1515429Y217157D01*
X1515754Y216002D01*
X1516187Y215136D01*
X1516837Y214415D01*
X1517703Y214126D01*
X1518569Y214415D01*
X1519219Y215136D01*
X1519652Y216002D01*
X1519977Y217157D01*
X1520085Y218456D01*
X1519977Y219756D01*
X1519652Y220911D01*
X1519219Y221777D01*
X1518569Y222498D01*
X1517703Y222787D01*
G01X1498540Y214126D02*
Y219900D01*
G01Y218456D02*
X1498974Y219178D01*
X1499623Y219756D01*
X1500489Y219900D01*
X1501247Y219756D01*
X1501897Y219178D01*
X1502222Y218168D01*
Y214126D01*
G01X1487969Y887021D02*
Y895682D01*
X1486670Y893950D01*
G01Y887021D02*
X1489268D01*
G01X1496630D02*
Y895682D01*
X1495331Y893950D01*
G01Y887021D02*
X1497929D01*
G01X1503450Y888031D02*
X1504208Y887310D01*
X1505074Y887021D01*
X1505941Y887310D01*
X1506698Y888176D01*
X1507240Y889475D01*
X1507456Y890774D01*
Y892362D01*
X1507240Y893661D01*
X1506698Y894816D01*
X1506049Y895393D01*
X1505291Y895682D01*
X1504425Y895393D01*
X1503775Y894816D01*
X1503342Y893950D01*
X1503126Y892795D01*
X1503342Y891785D01*
X1503884Y890774D01*
X1504533Y890197D01*
X1505291Y890052D01*
X1506157Y890341D01*
X1506807Y891063D01*
X1507456Y892362D01*
G01X1513952Y886732D02*
X1513735Y886877D01*
Y887165D01*
X1513952Y887310D01*
X1514169Y887165D01*
Y886877D01*
X1513952Y886732D01*
G01X1522613Y895682D02*
X1521747Y895393D01*
X1521097Y894672D01*
X1520664Y893806D01*
X1520339Y892651D01*
X1520231Y891351D01*
X1520339Y890052D01*
X1520664Y888897D01*
X1521097Y888031D01*
X1521747Y887310D01*
X1522613Y887021D01*
X1523479Y887310D01*
X1524129Y888031D01*
X1524562Y888897D01*
X1524887Y890052D01*
X1524995Y891351D01*
X1524887Y892651D01*
X1524562Y893806D01*
X1524129Y894672D01*
X1523479Y895393D01*
X1522613Y895682D01*
G01X1531274D02*
X1530408Y895393D01*
X1529758Y894672D01*
X1529325Y893806D01*
X1529000Y892651D01*
X1528892Y891351D01*
X1529000Y890052D01*
X1529325Y888897D01*
X1529758Y888031D01*
X1530408Y887310D01*
X1531274Y887021D01*
X1532140Y887310D01*
X1532790Y888031D01*
X1533223Y888897D01*
X1533548Y890052D01*
X1533656Y891351D01*
X1533548Y892651D01*
X1533223Y893806D01*
X1532790Y894672D01*
X1532140Y895393D01*
X1531274Y895682D01*
G01X1502136Y1284086D02*
X1503131Y1283140D01*
X1504267Y1282761D01*
X1505403Y1283140D01*
X1506397Y1284276D01*
X1507108Y1285980D01*
X1507392Y1287685D01*
Y1289767D01*
X1507108Y1291472D01*
X1506397Y1292987D01*
X1505545Y1293744D01*
X1504551Y1294123D01*
X1503415Y1293744D01*
X1502563Y1292987D01*
X1501994Y1291851D01*
X1501710Y1290335D01*
X1501994Y1289010D01*
X1502705Y1287685D01*
X1503557Y1286927D01*
X1504551Y1286738D01*
X1505687Y1287116D01*
X1506539Y1288063D01*
X1507392Y1289767D01*
G01X1540175Y143059D02*
X1539092Y144503D01*
X1538551Y145946D01*
Y151720D01*
X1539092Y153164D01*
X1540175Y154607D01*
G01X1547212Y145946D02*
Y154607D01*
X1549810D01*
X1550676Y154174D01*
X1551326Y153164D01*
X1551542Y152009D01*
X1551326Y150854D01*
X1550784Y149988D01*
X1549810Y149555D01*
X1547212D01*
G01X1555331Y145946D02*
X1558038Y154607D01*
X1560745Y145946D01*
G01X1559770Y148977D02*
X1556306D01*
G01X1564317Y145946D02*
Y154607D01*
X1566482D01*
X1567349Y154174D01*
X1567998Y153597D01*
X1568540Y152731D01*
X1568973Y151720D01*
X1569081Y150276D01*
X1568973Y148833D01*
X1568540Y147822D01*
X1567998Y146956D01*
X1567349Y146379D01*
X1566482Y145946D01*
X1564317D01*
G01X1575901Y143059D02*
X1576984Y144503D01*
X1577525Y145946D01*
Y151720D01*
X1576984Y153164D01*
X1575901Y154607D01*
G01X1583480Y143059D02*
X1582397Y144503D01*
X1581856Y145946D01*
Y151720D01*
X1582397Y153164D01*
X1583480Y154607D01*
G01X1590192Y145946D02*
Y154607D01*
X1595172Y145946D01*
Y154607D01*
G01X1601343Y145946D02*
X1600477Y146090D01*
X1599719Y146668D01*
X1599069Y147534D01*
X1598636Y148544D01*
X1598420Y149699D01*
Y150854D01*
X1598636Y152009D01*
X1599069Y153019D01*
X1599719Y153885D01*
X1600477Y154463D01*
X1601343Y154607D01*
X1602209Y154463D01*
X1602967Y153885D01*
X1603617Y153019D01*
X1604050Y152009D01*
X1604266Y150854D01*
Y149699D01*
X1604050Y148544D01*
X1603617Y147534D01*
X1602967Y146668D01*
X1602209Y146090D01*
X1601343Y145946D01*
G01X1618665Y154607D02*
Y145946D01*
G01X1616175Y154607D02*
X1621155D01*
G01X1625161Y145946D02*
Y154607D01*
X1627867D01*
X1628733Y154174D01*
X1629275Y153597D01*
X1629491Y152442D01*
X1629275Y151287D01*
X1628625Y150565D01*
X1627867Y150132D01*
X1625161D01*
G01X1627867D02*
X1629491Y145946D01*
G01X1633280D02*
X1635987Y154607D01*
X1638694Y145946D01*
G01X1637719Y148977D02*
X1634255D01*
G01X1647030Y153885D02*
X1646380Y154318D01*
X1645622Y154607D01*
X1644756D01*
X1643782Y154174D01*
X1643024Y153452D01*
X1642483Y152586D01*
X1642049Y151143D01*
X1641941Y149843D01*
X1642158Y148544D01*
X1642483Y147678D01*
X1643132Y146812D01*
X1643890Y146235D01*
X1644648Y145946D01*
X1645406D01*
X1646164Y146235D01*
X1646813Y146668D01*
X1647355Y147245D01*
G01X1655474Y145946D02*
X1651144D01*
Y154607D01*
X1655474D01*
G01X1653742Y150421D02*
X1651144D01*
G01X1667924Y145946D02*
X1670631Y154607D01*
X1673338Y145946D01*
G01X1672363Y148977D02*
X1668899D01*
G01X1679292Y154607D02*
Y145946D01*
G01X1676802Y154607D02*
X1681782D01*
G01X1693907Y145946D02*
X1696614Y154607D01*
X1699321Y145946D01*
G01X1698346Y148977D02*
X1694882D01*
G01X1703110Y154607D02*
Y145946D01*
X1707440D01*
G01X1711771Y154607D02*
Y145946D01*
X1716101D01*
G01X1729093Y154607D02*
Y145946D01*
X1733423D01*
G01X1737212D02*
X1739919Y154607D01*
X1742626Y145946D01*
G01X1741651Y148977D02*
X1738187D01*
G01X1748580Y145946D02*
Y149843D01*
X1746415Y154607D01*
G01X1750745D02*
X1748580Y149843D01*
G01X1759406Y145946D02*
X1755076D01*
Y154607D01*
X1759406D01*
G01X1757674Y150421D02*
X1755076D01*
G01X1763737Y145946D02*
Y154607D01*
X1766443D01*
X1767309Y154174D01*
X1767851Y153597D01*
X1768067Y152442D01*
X1767851Y151287D01*
X1767201Y150565D01*
X1766443Y150132D01*
X1763737D01*
G01X1766443D02*
X1768067Y145946D01*
G01X1772289Y147101D02*
X1773156Y146379D01*
X1774130Y145946D01*
X1774996D01*
X1775862Y146379D01*
X1776512Y147101D01*
X1776837Y148111D01*
X1776620Y149122D01*
X1776079Y149988D01*
X1775104Y150565D01*
X1773805Y150854D01*
X1773047Y151431D01*
X1772722Y152442D01*
X1772939Y153452D01*
X1773480Y154174D01*
X1774238Y154607D01*
X1774996D01*
X1775754Y154318D01*
X1776404Y153597D01*
G01X1783765Y143059D02*
X1784848Y144503D01*
X1785389Y145946D01*
Y151720D01*
X1784848Y153164D01*
X1783765Y154607D01*
G01X1553423Y234841D02*
X1552773Y235274D01*
X1552015Y235563D01*
X1551149D01*
X1550175Y235130D01*
X1549417Y234408D01*
X1548876Y233542D01*
X1548442Y232099D01*
X1548334Y230799D01*
X1548551Y229500D01*
X1548876Y228634D01*
X1549525Y227768D01*
X1550283Y227191D01*
X1551041Y226902D01*
X1551799D01*
X1552557Y227191D01*
X1553206Y227624D01*
X1553748Y228201D01*
G01X1559702Y226902D02*
X1558836Y227046D01*
X1558078Y227624D01*
X1557428Y228490D01*
X1556995Y229500D01*
X1556779Y230655D01*
Y231810D01*
X1556995Y232965D01*
X1557428Y233975D01*
X1558078Y234841D01*
X1558836Y235419D01*
X1559702Y235563D01*
X1560568Y235419D01*
X1561326Y234841D01*
X1561976Y233975D01*
X1562409Y232965D01*
X1562625Y231810D01*
Y230655D01*
X1562409Y229500D01*
X1561976Y228490D01*
X1561326Y227624D01*
X1560568Y227046D01*
X1559702Y226902D01*
G01X1565548D02*
Y235563D01*
X1568363Y228345D01*
X1571178Y235563D01*
Y226902D01*
G01X1574859D02*
Y235563D01*
X1577457D01*
X1578323Y235130D01*
X1578973Y234120D01*
X1579189Y232965D01*
X1578973Y231810D01*
X1578431Y230944D01*
X1577457Y230511D01*
X1574859D01*
G01X1585685Y226902D02*
X1584819Y227046D01*
X1584061Y227624D01*
X1583411Y228490D01*
X1582978Y229500D01*
X1582762Y230655D01*
Y231810D01*
X1582978Y232965D01*
X1583411Y233975D01*
X1584061Y234841D01*
X1584819Y235419D01*
X1585685Y235563D01*
X1586551Y235419D01*
X1587309Y234841D01*
X1587959Y233975D01*
X1588392Y232965D01*
X1588608Y231810D01*
Y230655D01*
X1588392Y229500D01*
X1587959Y228490D01*
X1587309Y227624D01*
X1586551Y227046D01*
X1585685Y226902D01*
G01X1591856D02*
Y235563D01*
X1596836Y226902D01*
Y235563D01*
G01X1605172Y226902D02*
X1600842D01*
Y235563D01*
X1605172D01*
G01X1603440Y231377D02*
X1600842D01*
G01X1609178Y226902D02*
Y235563D01*
X1614158Y226902D01*
Y235563D01*
G01X1620329D02*
Y226902D01*
G01X1617839Y235563D02*
X1622819D01*
G01X1635377Y228057D02*
X1636244Y227335D01*
X1637218Y226902D01*
X1638084D01*
X1638950Y227335D01*
X1639600Y228057D01*
X1639925Y229067D01*
X1639708Y230078D01*
X1639167Y230944D01*
X1638192Y231521D01*
X1636893Y231810D01*
X1636135Y232387D01*
X1635810Y233398D01*
X1636027Y234408D01*
X1636568Y235130D01*
X1637326Y235563D01*
X1638084D01*
X1638842Y235274D01*
X1639492Y234553D01*
G01X1645013Y235563D02*
X1647611D01*
G01X1646312D02*
Y226902D01*
G01X1645013D02*
X1647611D01*
G01X1652591D02*
Y235563D01*
X1654756D01*
X1655623Y235130D01*
X1656272Y234553D01*
X1656814Y233687D01*
X1657247Y232676D01*
X1657355Y231232D01*
X1657247Y229789D01*
X1656814Y228778D01*
X1656272Y227912D01*
X1655623Y227335D01*
X1654756Y226902D01*
X1652591D01*
G01X1665799D02*
X1661469D01*
Y235563D01*
X1665799D01*
G01X1664067Y231377D02*
X1661469D01*
G01X1544037Y1024424D02*
X1543893Y1025182D01*
X1543460Y1026048D01*
X1542738Y1026589D01*
X1541727Y1026806D01*
X1540717Y1026589D01*
X1539851Y1025940D01*
X1539418Y1024965D01*
Y1023883D01*
X1539129Y1023233D01*
X1538407Y1022692D01*
X1537397Y1022475D01*
X1536386Y1022800D01*
X1535665Y1023558D01*
X1535376Y1024424D01*
X1535665Y1025290D01*
X1536386Y1026048D01*
X1537397Y1026373D01*
X1538407Y1026156D01*
X1539129Y1025615D01*
X1539418Y1024965D01*
Y1023883D01*
X1539851Y1022908D01*
X1540717Y1022259D01*
X1541727Y1022042D01*
X1542738Y1022259D01*
X1543460Y1022800D01*
X1543893Y1023666D01*
X1544037Y1024424D01*
G01X1542738Y1030703D02*
X1543460Y1031353D01*
X1543893Y1032111D01*
X1544037Y1033085D01*
X1543748Y1034059D01*
X1543171Y1034817D01*
X1542161Y1035359D01*
X1541006Y1035467D01*
X1539851Y1035250D01*
X1539129Y1034709D01*
X1538552Y1033951D01*
X1538407Y1033193D01*
X1538552Y1032435D01*
X1539129Y1031461D01*
X1535376Y1031786D01*
Y1034709D01*
G01X1544326Y1041746D02*
X1544181Y1041529D01*
X1543893D01*
X1543748Y1041746D01*
X1543893Y1041963D01*
X1544181D01*
X1544326Y1041746D01*
G01X1535376Y1050407D02*
X1535665Y1049541D01*
X1536386Y1048891D01*
X1537252Y1048458D01*
X1538407Y1048133D01*
X1539707Y1048025D01*
X1541006Y1048133D01*
X1542161Y1048458D01*
X1543027Y1048891D01*
X1543748Y1049541D01*
X1544037Y1050407D01*
X1543748Y1051273D01*
X1543027Y1051923D01*
X1542161Y1052356D01*
X1541006Y1052681D01*
X1539707Y1052789D01*
X1538407Y1052681D01*
X1537252Y1052356D01*
X1536386Y1051923D01*
X1535665Y1051273D01*
X1535376Y1050407D01*
G01Y1059068D02*
X1535665Y1058202D01*
X1536386Y1057552D01*
X1537252Y1057119D01*
X1538407Y1056794D01*
X1539707Y1056686D01*
X1541006Y1056794D01*
X1542161Y1057119D01*
X1543027Y1057552D01*
X1543748Y1058202D01*
X1544037Y1059068D01*
X1543748Y1059934D01*
X1543027Y1060584D01*
X1542161Y1061017D01*
X1541006Y1061342D01*
X1539707Y1061450D01*
X1538407Y1061342D01*
X1537252Y1061017D01*
X1536386Y1060584D01*
X1535665Y1059934D01*
X1535376Y1059068D01*
G01X1580880Y-672172D02*
X1581747Y-672894D01*
X1582721Y-673327D01*
X1583587D01*
X1584453Y-672894D01*
X1585103Y-672172D01*
X1585428Y-671162D01*
X1585211Y-670151D01*
X1584670Y-669285D01*
X1583695Y-668708D01*
X1582396Y-668419D01*
X1581638Y-667842D01*
X1581313Y-666831D01*
X1581530Y-665821D01*
X1582071Y-665099D01*
X1582829Y-664666D01*
X1583587D01*
X1584345Y-664955D01*
X1584995Y-665676D01*
G01X1591815Y-673327D02*
X1590949Y-673183D01*
X1590191Y-672605D01*
X1589541Y-671739D01*
X1589108Y-670729D01*
X1588892Y-669574D01*
Y-668419D01*
X1589108Y-667264D01*
X1589541Y-666254D01*
X1590191Y-665388D01*
X1590949Y-664810D01*
X1591815Y-664666D01*
X1592681Y-664810D01*
X1593439Y-665388D01*
X1594089Y-666254D01*
X1594522Y-667264D01*
X1594738Y-668419D01*
Y-669574D01*
X1594522Y-670729D01*
X1594089Y-671739D01*
X1593439Y-672605D01*
X1592681Y-673183D01*
X1591815Y-673327D01*
G01X1598311Y-664666D02*
Y-673327D01*
X1602641D01*
G01X1606755D02*
Y-664666D01*
X1608920D01*
X1609787Y-665099D01*
X1610436Y-665676D01*
X1610978Y-666542D01*
X1611411Y-667553D01*
X1611519Y-668997D01*
X1611411Y-670440D01*
X1610978Y-671451D01*
X1610436Y-672317D01*
X1609787Y-672894D01*
X1608920Y-673327D01*
X1606755D01*
G01X1619963D02*
X1615633D01*
Y-664666D01*
X1619963D01*
G01X1618231Y-668852D02*
X1615633D01*
G01X1624294Y-673327D02*
Y-664666D01*
X1627000D01*
X1627866Y-665099D01*
X1628408Y-665676D01*
X1628624Y-666831D01*
X1628408Y-667986D01*
X1627758Y-668708D01*
X1627000Y-669141D01*
X1624294D01*
G01X1627000D02*
X1628624Y-673327D01*
G01X1641507Y-672172D02*
X1642374Y-672894D01*
X1643348Y-673327D01*
X1644214D01*
X1645080Y-672894D01*
X1645730Y-672172D01*
X1646055Y-671162D01*
X1645838Y-670151D01*
X1645297Y-669285D01*
X1644322Y-668708D01*
X1643023Y-668419D01*
X1642265Y-667842D01*
X1641940Y-666831D01*
X1642157Y-665821D01*
X1642698Y-665099D01*
X1643456Y-664666D01*
X1644214D01*
X1644972Y-664955D01*
X1645622Y-665676D01*
G01X1651143Y-664666D02*
X1653741D01*
G01X1652442D02*
Y-673327D01*
G01X1651143D02*
X1653741D01*
G01X1658721D02*
Y-664666D01*
X1660886D01*
X1661753Y-665099D01*
X1662402Y-665676D01*
X1662944Y-666542D01*
X1663377Y-667553D01*
X1663485Y-668997D01*
X1663377Y-670440D01*
X1662944Y-671451D01*
X1662402Y-672317D01*
X1661753Y-672894D01*
X1660886Y-673327D01*
X1658721D01*
G01X1671929D02*
X1667599D01*
Y-664666D01*
X1671929D01*
G01X1670197Y-668852D02*
X1667599D01*
G01X1582388Y481142D02*
X1583109Y481900D01*
X1583398Y482766D01*
X1583109Y483633D01*
X1582243Y484390D01*
X1580944Y484932D01*
X1579645Y485148D01*
X1578057D01*
X1576758Y484932D01*
X1575603Y484390D01*
X1575026Y483741D01*
X1574737Y482983D01*
X1575026Y482117D01*
X1575603Y481467D01*
X1576469Y481034D01*
X1577624Y480818D01*
X1578634Y481034D01*
X1579645Y481576D01*
X1580222Y482225D01*
X1580367Y482983D01*
X1580078Y483849D01*
X1579356Y484499D01*
X1578057Y485148D01*
G01X1582099Y489262D02*
X1582821Y489912D01*
X1583254Y490670D01*
X1583398Y491644D01*
X1583109Y492618D01*
X1582532Y493376D01*
X1581522Y493918D01*
X1580367Y494026D01*
X1579212Y493809D01*
X1578490Y493268D01*
X1577913Y492510D01*
X1577768Y491752D01*
X1577913Y490994D01*
X1578490Y490020D01*
X1574737Y490345D01*
Y493268D01*
G01X1583687Y500305D02*
X1583542Y500088D01*
X1583254D01*
X1583109Y500305D01*
X1583254Y500522D01*
X1583542D01*
X1583687Y500305D01*
G01X1574737Y508966D02*
X1575026Y508100D01*
X1575747Y507450D01*
X1576613Y507017D01*
X1577768Y506692D01*
X1579068Y506584D01*
X1580367Y506692D01*
X1581522Y507017D01*
X1582388Y507450D01*
X1583109Y508100D01*
X1583398Y508966D01*
X1583109Y509832D01*
X1582388Y510482D01*
X1581522Y510915D01*
X1580367Y511240D01*
X1579068Y511348D01*
X1577768Y511240D01*
X1576613Y510915D01*
X1575747Y510482D01*
X1575026Y509832D01*
X1574737Y508966D01*
G01Y517627D02*
X1575026Y516761D01*
X1575747Y516111D01*
X1576613Y515678D01*
X1577768Y515353D01*
X1579068Y515245D01*
X1580367Y515353D01*
X1581522Y515678D01*
X1582388Y516111D01*
X1583109Y516761D01*
X1583398Y517627D01*
X1583109Y518493D01*
X1582388Y519143D01*
X1581522Y519576D01*
X1580367Y519901D01*
X1579068Y520009D01*
X1577768Y519901D01*
X1576613Y519576D01*
X1575747Y519143D01*
X1575026Y518493D01*
X1574737Y517627D01*
G01X1660129Y145946D02*
Y151720D01*
G01Y150276D02*
X1660563Y150998D01*
X1661212Y151576D01*
X1662078Y151720D01*
X1662836Y151576D01*
X1663486Y150998D01*
X1663811Y149988D01*
Y145946D01*
G01X1647137Y146956D02*
X1647895Y146235D01*
X1648761Y145946D01*
X1649628Y146235D01*
X1650385Y147101D01*
X1650927Y148400D01*
X1651143Y149699D01*
Y151287D01*
X1650927Y152586D01*
X1650385Y153741D01*
X1649736Y154318D01*
X1648978Y154607D01*
X1648112Y154318D01*
X1647462Y153741D01*
X1647029Y152875D01*
X1646813Y151720D01*
X1647029Y150710D01*
X1647571Y149699D01*
X1648220Y149122D01*
X1648978Y148977D01*
X1649844Y149266D01*
X1650494Y149988D01*
X1651143Y151287D01*
G01X1657639Y145657D02*
X1657422Y145802D01*
Y146090D01*
X1657639Y146235D01*
X1657856Y146090D01*
Y145802D01*
X1657639Y145657D01*
G01X1663918Y147245D02*
X1664568Y146523D01*
X1665326Y146090D01*
X1666300Y145946D01*
X1667274Y146235D01*
X1668032Y146812D01*
X1668574Y147822D01*
X1668682Y148977D01*
X1668465Y150132D01*
X1667924Y150854D01*
X1667166Y151431D01*
X1666408Y151576D01*
X1665650Y151431D01*
X1664676Y150854D01*
X1665001Y154607D01*
X1667924D01*
G01X1674961D02*
X1674095Y154318D01*
X1673445Y153597D01*
X1673012Y152731D01*
X1672687Y151576D01*
X1672579Y150276D01*
X1672687Y148977D01*
X1673012Y147822D01*
X1673445Y146956D01*
X1674095Y146235D01*
X1674961Y145946D01*
X1675827Y146235D01*
X1676477Y146956D01*
X1676910Y147822D01*
X1677235Y148977D01*
X1677343Y150276D01*
X1677235Y151576D01*
X1676910Y152731D01*
X1676477Y153597D01*
X1675827Y154318D01*
X1674961Y154607D01*
G01X1637276Y576470D02*
X1637926Y575460D01*
X1638792Y574882D01*
X1639766Y574738D01*
X1640632Y574882D01*
X1641499Y575604D01*
X1642040Y576470D01*
X1642148Y577336D01*
X1641932Y578347D01*
X1641174Y579068D01*
X1640416Y579357D01*
X1639441D01*
G01X1640416D02*
X1641065Y579790D01*
X1641607Y580512D01*
X1641823Y581378D01*
X1641607Y582244D01*
X1641065Y582966D01*
X1640091Y583399D01*
X1639117Y583255D01*
X1638142Y582677D01*
G01X1646478Y575748D02*
X1647236Y575027D01*
X1648102Y574738D01*
X1648969Y575027D01*
X1649726Y575893D01*
X1650268Y577192D01*
X1650484Y578491D01*
Y580079D01*
X1650268Y581378D01*
X1649726Y582533D01*
X1649077Y583110D01*
X1648319Y583399D01*
X1647453Y583110D01*
X1646803Y582533D01*
X1646370Y581667D01*
X1646154Y580512D01*
X1646370Y579502D01*
X1646912Y578491D01*
X1647561Y577914D01*
X1648319Y577769D01*
X1649185Y578058D01*
X1649835Y578780D01*
X1650484Y580079D01*
G01X1656980Y574449D02*
X1656763Y574594D01*
Y574882D01*
X1656980Y575027D01*
X1657197Y574882D01*
Y574594D01*
X1656980Y574449D01*
G01X1663584Y578347D02*
X1664342Y579357D01*
X1664991Y579935D01*
X1665858Y580223D01*
X1666615Y579935D01*
X1667157Y579357D01*
X1667590Y578491D01*
X1667698Y577481D01*
X1667590Y576614D01*
X1667157Y575748D01*
X1666507Y575027D01*
X1665749Y574738D01*
X1664883Y575027D01*
X1664125Y575893D01*
X1663692Y577192D01*
X1663584Y578635D01*
X1663800Y580512D01*
X1664125Y581523D01*
X1664667Y582533D01*
X1665424Y583255D01*
X1666182Y583399D01*
X1666940Y583110D01*
X1667482Y582389D01*
G01X1674302Y574738D02*
X1675060Y574882D01*
X1675926Y575315D01*
X1676467Y576037D01*
X1676684Y577048D01*
X1676467Y578058D01*
X1675818Y578924D01*
X1674843Y579357D01*
X1673761D01*
X1673111Y579646D01*
X1672570Y580368D01*
X1672353Y581378D01*
X1672678Y582389D01*
X1673436Y583110D01*
X1674302Y583399D01*
X1675168Y583110D01*
X1675926Y582389D01*
X1676251Y581378D01*
X1676034Y580368D01*
X1675493Y579646D01*
X1674843Y579357D01*
X1673761D01*
X1672786Y578924D01*
X1672137Y578058D01*
X1671920Y577048D01*
X1672137Y576037D01*
X1672678Y575315D01*
X1673544Y574882D01*
X1674302Y574738D01*
G01X1721569Y-894995D02*
Y-883633D01*
X1719865Y-885905D01*
G01Y-894995D02*
X1723273D01*
G01X1732932Y-883633D02*
X1731796Y-884012D01*
X1730944Y-884959D01*
X1730375Y-886095D01*
X1729949Y-887610D01*
X1729807Y-889314D01*
X1729949Y-891018D01*
X1730375Y-892533D01*
X1730944Y-893670D01*
X1731796Y-894616D01*
X1732932Y-894995D01*
X1734068Y-894616D01*
X1734920Y-893670D01*
X1735489Y-892533D01*
X1735915Y-891018D01*
X1736057Y-889314D01*
X1735915Y-887610D01*
X1735489Y-886095D01*
X1734920Y-884959D01*
X1734068Y-884012D01*
X1732932Y-883633D01*
G01X1762859Y-752813D02*
X1761359Y-751813D01*
X1759609Y-751146D01*
X1757609D01*
X1755359Y-752146D01*
X1753609Y-753813D01*
X1752359Y-755813D01*
X1751359Y-759146D01*
X1751109Y-762146D01*
X1751609Y-765146D01*
X1752359Y-767146D01*
X1753859Y-769146D01*
X1755609Y-770479D01*
X1757359Y-771146D01*
X1759109D01*
X1760859Y-770479D01*
X1762359Y-769480D01*
X1763609Y-768147D01*
G01X1773859Y-771146D02*
Y-757813D01*
G01Y-760479D02*
X1775109Y-759146D01*
X1776359Y-758146D01*
X1778109Y-757813D01*
X1779359Y-758146D01*
X1780859Y-759146D01*
G01X1793609Y-762146D02*
X1801609D01*
X1800859Y-759813D01*
X1799609Y-758480D01*
X1797859Y-757813D01*
X1796109Y-758146D01*
X1794609Y-759146D01*
X1793609Y-761480D01*
X1793109Y-763480D01*
Y-765479D01*
X1793609Y-767480D01*
X1794859Y-769480D01*
X1796359Y-770813D01*
X1798109Y-771146D01*
X1799859Y-770479D01*
X1801609Y-768480D01*
G01X1821859Y-771146D02*
Y-757813D01*
G01Y-760146D02*
X1820859Y-758813D01*
X1819359Y-758146D01*
X1817609Y-757813D01*
X1815859Y-758480D01*
X1814359Y-759813D01*
X1813359Y-761813D01*
X1812859Y-764480D01*
X1813359Y-767146D01*
X1814359Y-769146D01*
X1815859Y-770479D01*
X1817609Y-771146D01*
X1819359Y-770813D01*
X1820859Y-769813D01*
X1821859Y-768480D01*
G01X1837359Y-751146D02*
Y-771146D01*
G01X1833859Y-757813D02*
X1840859D01*
G01X1853609Y-762146D02*
X1861609D01*
X1860859Y-759813D01*
X1859609Y-758480D01*
X1857859Y-757813D01*
X1856109Y-758146D01*
X1854609Y-759146D01*
X1853609Y-761480D01*
X1853109Y-763480D01*
Y-765479D01*
X1853609Y-767480D01*
X1854859Y-769480D01*
X1856359Y-770813D01*
X1858109Y-771146D01*
X1859859Y-770479D01*
X1861609Y-768480D01*
G01X1881859Y-751146D02*
Y-771146D01*
G01Y-768147D02*
X1880859Y-769813D01*
X1879359Y-770813D01*
X1877609Y-771146D01*
X1875609Y-770479D01*
X1874109Y-768813D01*
X1873109Y-766813D01*
X1872859Y-764480D01*
X1873109Y-762146D01*
X1874109Y-760146D01*
X1875609Y-758480D01*
X1877609Y-757813D01*
X1879359Y-758146D01*
X1880609Y-758813D01*
X1881859Y-760146D01*
G01X1748407Y-702238D02*
X1754657Y-722238D01*
X1760907Y-702238D01*
G01X1770907Y-713238D02*
X1778907D01*
X1778157Y-710905D01*
X1776907Y-709572D01*
X1775157Y-708905D01*
X1773407Y-709238D01*
X1771907Y-710238D01*
X1770907Y-712572D01*
X1770407Y-714572D01*
Y-716571D01*
X1770907Y-718572D01*
X1772157Y-720572D01*
X1773657Y-721905D01*
X1775407Y-722238D01*
X1777157Y-721571D01*
X1778907Y-719572D01*
G01X1791157Y-722238D02*
Y-708905D01*
G01Y-711571D02*
X1792407Y-710238D01*
X1793657Y-709238D01*
X1795407Y-708905D01*
X1796657Y-709238D01*
X1798157Y-710238D01*
G01X1810907Y-719905D02*
X1812157Y-721238D01*
X1813907Y-722238D01*
X1815407D01*
X1816907Y-721571D01*
X1817907Y-720572D01*
X1818407Y-719239D01*
X1818157Y-717238D01*
X1817157Y-716238D01*
X1812657Y-714238D01*
X1811657Y-711904D01*
X1812157Y-710238D01*
X1813157Y-709238D01*
X1814657Y-708905D01*
X1816157Y-709238D01*
X1817657Y-710238D01*
G01X1834657Y-708905D02*
Y-722238D01*
G01Y-703572D02*
X1834157Y-703238D01*
Y-702571D01*
X1834657Y-702238D01*
X1835157Y-702571D01*
Y-703238D01*
X1834657Y-703572D01*
G01X1854657Y-722238D02*
X1853157Y-721905D01*
X1851657Y-720572D01*
X1850657Y-718238D01*
X1850157Y-715572D01*
X1850657Y-712905D01*
X1851657Y-710571D01*
X1853157Y-709238D01*
X1854657Y-708905D01*
X1856157Y-709238D01*
X1857657Y-710571D01*
X1858657Y-712905D01*
X1858907Y-715572D01*
X1858657Y-718238D01*
X1857657Y-720572D01*
X1856157Y-721905D01*
X1854657Y-722238D01*
G01X1870407D02*
Y-708905D01*
G01Y-712238D02*
X1871407Y-710571D01*
X1872907Y-709238D01*
X1874907Y-708905D01*
X1876657Y-709238D01*
X1878157Y-710571D01*
X1878907Y-712905D01*
Y-722238D01*
G01X1752359Y-678225D02*
Y-658225D01*
X1758359D01*
X1760359Y-659225D01*
X1761859Y-661558D01*
X1762359Y-664225D01*
X1761859Y-666892D01*
X1760609Y-668892D01*
X1758359Y-669892D01*
X1752359D01*
G01X1782859Y-659892D02*
X1781359Y-658892D01*
X1779609Y-658225D01*
X1777609D01*
X1775359Y-659225D01*
X1773609Y-660892D01*
X1772359Y-662892D01*
X1771359Y-666225D01*
X1771109Y-669225D01*
X1771609Y-672225D01*
X1772359Y-674225D01*
X1773859Y-676225D01*
X1775609Y-677558D01*
X1777359Y-678225D01*
X1779109D01*
X1780859Y-677558D01*
X1782359Y-676559D01*
X1783609Y-675226D01*
G01X1799359Y-667558D02*
X1800359Y-666558D01*
X1801109Y-664892D01*
X1801609Y-662558D01*
X1801109Y-660558D01*
X1800109Y-659225D01*
X1798359Y-658225D01*
X1791609D01*
Y-678225D01*
X1799859D01*
X1801609Y-676892D01*
X1802609Y-674892D01*
X1803109Y-672558D01*
X1802609Y-670225D01*
X1801109Y-668225D01*
X1799359Y-667558D01*
X1791609D01*
G01X1831609Y-678225D02*
Y-658225D01*
X1843109Y-678225D01*
Y-658225D01*
G01X1857359Y-678225D02*
X1855859Y-677892D01*
X1854359Y-676559D01*
X1853359Y-674225D01*
X1852859Y-671559D01*
X1853359Y-668892D01*
X1854359Y-666558D01*
X1855859Y-665225D01*
X1857359Y-664892D01*
X1858859Y-665225D01*
X1860359Y-666558D01*
X1861359Y-668892D01*
X1861609Y-671559D01*
X1861359Y-674225D01*
X1860359Y-676559D01*
X1858859Y-677892D01*
X1857359Y-678225D01*
G01X1877359Y-678892D02*
X1876859Y-678558D01*
Y-677892D01*
X1877359Y-677558D01*
X1877859Y-677892D01*
Y-678558D01*
X1877359Y-678892D01*
G01X1718145Y541877D02*
X1718795Y542742D01*
X1719552Y543176D01*
X1720419Y543320D01*
X1721501Y543031D01*
X1722259Y542310D01*
X1722476Y541444D01*
X1722367Y540577D01*
X1721934Y539856D01*
X1719769Y538412D01*
X1718795Y537402D01*
X1718145Y535958D01*
X1717928Y534659D01*
X1722476D01*
G01X1727022Y535669D02*
X1727780Y534948D01*
X1728646Y534659D01*
X1729513Y534948D01*
X1730270Y535814D01*
X1730812Y537113D01*
X1731028Y538412D01*
Y540000D01*
X1730812Y541299D01*
X1730270Y542454D01*
X1729621Y543031D01*
X1728863Y543320D01*
X1727997Y543031D01*
X1727347Y542454D01*
X1726914Y541588D01*
X1726698Y540433D01*
X1726914Y539423D01*
X1727456Y538412D01*
X1728105Y537835D01*
X1728863Y537690D01*
X1729729Y537979D01*
X1730379Y538701D01*
X1731028Y540000D01*
G01X1737524Y534370D02*
X1737307Y534515D01*
Y534803D01*
X1737524Y534948D01*
X1737741Y534803D01*
Y534515D01*
X1737524Y534370D01*
G01X1743803Y535958D02*
X1744453Y535236D01*
X1745211Y534803D01*
X1746185Y534659D01*
X1747159Y534948D01*
X1747917Y535525D01*
X1748459Y536535D01*
X1748567Y537690D01*
X1748350Y538845D01*
X1747809Y539567D01*
X1747051Y540144D01*
X1746293Y540289D01*
X1745535Y540144D01*
X1744561Y539567D01*
X1744886Y543320D01*
X1747809D01*
G01X1754846D02*
X1753980Y543031D01*
X1753330Y542310D01*
X1752897Y541444D01*
X1752572Y540289D01*
X1752464Y538989D01*
X1752572Y537690D01*
X1752897Y536535D01*
X1753330Y535669D01*
X1753980Y534948D01*
X1754846Y534659D01*
X1755712Y534948D01*
X1756362Y535669D01*
X1756795Y536535D01*
X1757120Y537690D01*
X1757228Y538989D01*
X1757120Y540289D01*
X1756795Y541444D01*
X1756362Y542310D01*
X1755712Y543031D01*
X1754846Y543320D01*
G01X1740878Y818436D02*
X1732217D01*
X1733949Y817137D01*
G01X1740878D02*
Y819735D01*
G01X1739146Y824715D02*
X1740156Y825365D01*
X1740734Y826231D01*
X1740878Y827205D01*
X1740734Y828071D01*
X1740012Y828938D01*
X1739146Y829479D01*
X1738280Y829587D01*
X1737269Y829371D01*
X1736548Y828613D01*
X1736259Y827855D01*
Y826880D01*
G01Y827855D02*
X1735826Y828504D01*
X1735104Y829046D01*
X1734238Y829262D01*
X1733372Y829046D01*
X1732650Y828504D01*
X1732217Y827530D01*
X1732361Y826556D01*
X1732939Y825581D01*
G01X1739579Y833376D02*
X1740301Y834026D01*
X1740734Y834784D01*
X1740878Y835758D01*
X1740589Y836732D01*
X1740012Y837490D01*
X1739002Y838032D01*
X1737847Y838140D01*
X1736692Y837923D01*
X1735970Y837382D01*
X1735393Y836624D01*
X1735248Y835866D01*
X1735393Y835108D01*
X1735970Y834134D01*
X1732217Y834459D01*
Y837382D01*
G01X1741167Y844419D02*
X1741022Y844202D01*
X1740734D01*
X1740589Y844419D01*
X1740734Y844636D01*
X1741022D01*
X1741167Y844419D01*
G01X1732217Y853080D02*
X1732506Y852214D01*
X1733227Y851564D01*
X1734093Y851131D01*
X1735248Y850806D01*
X1736548Y850698D01*
X1737847Y850806D01*
X1739002Y851131D01*
X1739868Y851564D01*
X1740589Y852214D01*
X1740878Y853080D01*
X1740589Y853946D01*
X1739868Y854596D01*
X1739002Y855029D01*
X1737847Y855354D01*
X1736548Y855462D01*
X1735248Y855354D01*
X1734093Y855029D01*
X1733227Y854596D01*
X1732506Y853946D01*
X1732217Y853080D01*
G01Y861741D02*
X1732506Y860875D01*
X1733227Y860225D01*
X1734093Y859792D01*
X1735248Y859467D01*
X1736548Y859359D01*
X1737847Y859467D01*
X1739002Y859792D01*
X1739868Y860225D01*
X1740589Y860875D01*
X1740878Y861741D01*
X1740589Y862607D01*
X1739868Y863257D01*
X1739002Y863690D01*
X1737847Y864015D01*
X1736548Y864123D01*
X1735248Y864015D01*
X1734093Y863690D01*
X1733227Y863257D01*
X1732506Y862607D01*
X1732217Y861741D01*
G01X1701518Y1023990D02*
X1692857D01*
X1694589Y1022691D01*
G01X1701518D02*
Y1025289D01*
G01X1694300Y1030594D02*
X1693435Y1031244D01*
X1693001Y1032001D01*
X1692857Y1032868D01*
X1693146Y1033950D01*
X1693867Y1034708D01*
X1694733Y1034925D01*
X1695600Y1034816D01*
X1696321Y1034383D01*
X1697765Y1032218D01*
X1698775Y1031244D01*
X1700219Y1030594D01*
X1701518Y1030377D01*
Y1034925D01*
G01X1700219Y1038930D02*
X1700941Y1039580D01*
X1701374Y1040338D01*
X1701518Y1041312D01*
X1701229Y1042286D01*
X1700652Y1043044D01*
X1699642Y1043586D01*
X1698487Y1043694D01*
X1697332Y1043477D01*
X1696610Y1042936D01*
X1696033Y1042178D01*
X1695888Y1041420D01*
X1696033Y1040662D01*
X1696610Y1039688D01*
X1692857Y1040013D01*
Y1042936D01*
G01X1701807Y1049973D02*
X1701662Y1049756D01*
X1701374D01*
X1701229Y1049973D01*
X1701374Y1050190D01*
X1701662D01*
X1701807Y1049973D01*
G01X1692857Y1058634D02*
X1693146Y1057768D01*
X1693867Y1057118D01*
X1694733Y1056685D01*
X1695888Y1056360D01*
X1697188Y1056252D01*
X1698487Y1056360D01*
X1699642Y1056685D01*
X1700508Y1057118D01*
X1701229Y1057768D01*
X1701518Y1058634D01*
X1701229Y1059500D01*
X1700508Y1060150D01*
X1699642Y1060583D01*
X1698487Y1060908D01*
X1697188Y1061016D01*
X1695888Y1060908D01*
X1694733Y1060583D01*
X1693867Y1060150D01*
X1693146Y1059500D01*
X1692857Y1058634D01*
G01Y1067295D02*
X1693146Y1066429D01*
X1693867Y1065779D01*
X1694733Y1065346D01*
X1695888Y1065021D01*
X1697188Y1064913D01*
X1698487Y1065021D01*
X1699642Y1065346D01*
X1700508Y1065779D01*
X1701229Y1066429D01*
X1701518Y1067295D01*
X1701229Y1068161D01*
X1700508Y1068811D01*
X1699642Y1069244D01*
X1698487Y1069569D01*
X1697188Y1069677D01*
X1695888Y1069569D01*
X1694733Y1069244D01*
X1693867Y1068811D01*
X1693146Y1068161D01*
X1692857Y1067295D01*
G01X1721569Y1282761D02*
Y1294123D01*
X1719865Y1291851D01*
G01Y1282761D02*
X1723273D01*
G01X1732932Y1294123D02*
X1731796Y1293744D01*
X1730944Y1292797D01*
X1730375Y1291661D01*
X1729949Y1290146D01*
X1729807Y1288442D01*
X1729949Y1286738D01*
X1730375Y1285223D01*
X1730944Y1284086D01*
X1731796Y1283140D01*
X1732932Y1282761D01*
X1734068Y1283140D01*
X1734920Y1284086D01*
X1735489Y1285223D01*
X1735915Y1286738D01*
X1736057Y1288442D01*
X1735915Y1290146D01*
X1735489Y1291661D01*
X1734920Y1292797D01*
X1734068Y1293744D01*
X1732932Y1294123D01*
G01X1760803Y-634012D02*
Y-609012D01*
X1768993Y-629845D01*
X1777183Y-609012D01*
Y-634012D01*
G01X1794193D02*
X1792303Y-633595D01*
X1790413Y-631929D01*
X1789153Y-629012D01*
X1788523Y-625679D01*
X1789153Y-622346D01*
X1790413Y-619429D01*
X1792303Y-617762D01*
X1794193Y-617346D01*
X1796083Y-617762D01*
X1797973Y-619429D01*
X1799233Y-622346D01*
X1799548Y-625679D01*
X1799233Y-629012D01*
X1797973Y-631929D01*
X1796083Y-633595D01*
X1794193Y-634012D01*
G01X1825063Y-609012D02*
Y-634012D01*
G01Y-630263D02*
X1823803Y-632346D01*
X1821913Y-633595D01*
X1819708Y-634012D01*
X1817188Y-633179D01*
X1815298Y-631096D01*
X1814038Y-628596D01*
X1813723Y-625679D01*
X1814038Y-622762D01*
X1815298Y-620262D01*
X1817188Y-618179D01*
X1819708Y-617346D01*
X1821913Y-617762D01*
X1823488Y-618596D01*
X1825063Y-620262D01*
G01X1839868Y-622762D02*
X1849948D01*
X1849003Y-619845D01*
X1847428Y-618179D01*
X1845223Y-617346D01*
X1843018Y-617762D01*
X1841128Y-619012D01*
X1839868Y-621929D01*
X1839238Y-624429D01*
Y-626929D01*
X1839868Y-629429D01*
X1841443Y-631929D01*
X1843333Y-633595D01*
X1845538Y-634012D01*
X1847743Y-633179D01*
X1849948Y-630679D01*
G01X1869793Y-634012D02*
Y-609012D01*
G01X1780843Y-186493D02*
X1779760Y-185049D01*
X1779219Y-183606D01*
Y-177832D01*
X1779760Y-176388D01*
X1780843Y-174945D01*
G01X1787555Y-183606D02*
Y-174945D01*
X1792535Y-183606D01*
Y-174945D01*
G01X1798706Y-183606D02*
X1797840Y-183462D01*
X1797082Y-182884D01*
X1796432Y-182018D01*
X1795999Y-181008D01*
X1795783Y-179853D01*
Y-178698D01*
X1795999Y-177543D01*
X1796432Y-176533D01*
X1797082Y-175667D01*
X1797840Y-175089D01*
X1798706Y-174945D01*
X1799572Y-175089D01*
X1800330Y-175667D01*
X1800980Y-176533D01*
X1801413Y-177543D01*
X1801629Y-178698D01*
Y-179853D01*
X1801413Y-181008D01*
X1800980Y-182018D01*
X1800330Y-182884D01*
X1799572Y-183462D01*
X1798706Y-183606D01*
G01X1816028Y-174945D02*
Y-183606D01*
G01X1813538Y-174945D02*
X1818518D01*
G01X1822524Y-183606D02*
Y-174945D01*
X1825230D01*
X1826096Y-175378D01*
X1826638Y-175955D01*
X1826854Y-177110D01*
X1826638Y-178265D01*
X1825988Y-178987D01*
X1825230Y-179420D01*
X1822524D01*
G01X1825230D02*
X1826854Y-183606D01*
G01X1830643D02*
X1833350Y-174945D01*
X1836057Y-183606D01*
G01X1835082Y-180575D02*
X1831618D01*
G01X1844393Y-175667D02*
X1843743Y-175234D01*
X1842985Y-174945D01*
X1842119D01*
X1841145Y-175378D01*
X1840387Y-176100D01*
X1839846Y-176966D01*
X1839412Y-178409D01*
X1839304Y-179709D01*
X1839521Y-181008D01*
X1839846Y-181874D01*
X1840495Y-182740D01*
X1841253Y-183317D01*
X1842011Y-183606D01*
X1842769D01*
X1843527Y-183317D01*
X1844176Y-182884D01*
X1844718Y-182307D01*
G01X1852837Y-183606D02*
X1848507D01*
Y-174945D01*
X1852837D01*
G01X1851105Y-179131D02*
X1848507D01*
G01X1865287Y-183606D02*
X1867994Y-174945D01*
X1870701Y-183606D01*
G01X1869726Y-180575D02*
X1866262D01*
G01X1876655Y-174945D02*
Y-183606D01*
G01X1874165Y-174945D02*
X1879145D01*
G01X1891270Y-183606D02*
X1893977Y-174945D01*
X1896684Y-183606D01*
G01X1895709Y-180575D02*
X1892245D01*
G01X1900473Y-174945D02*
Y-183606D01*
X1904803D01*
G01X1909134Y-174945D02*
Y-183606D01*
X1913464D01*
G01X1926456Y-174945D02*
Y-183606D01*
X1930786D01*
G01X1934575D02*
X1937282Y-174945D01*
X1939989Y-183606D01*
G01X1939014Y-180575D02*
X1935550D01*
G01X1945943Y-183606D02*
Y-179709D01*
X1943778Y-174945D01*
G01X1948108D02*
X1945943Y-179709D01*
G01X1956769Y-183606D02*
X1952439D01*
Y-174945D01*
X1956769D01*
G01X1955037Y-179131D02*
X1952439D01*
G01X1961100Y-183606D02*
Y-174945D01*
X1963806D01*
X1964672Y-175378D01*
X1965214Y-175955D01*
X1965430Y-177110D01*
X1965214Y-178265D01*
X1964564Y-178987D01*
X1963806Y-179420D01*
X1961100D01*
G01X1963806D02*
X1965430Y-183606D01*
G01X1969652Y-182451D02*
X1970519Y-183173D01*
X1971493Y-183606D01*
X1972359D01*
X1973225Y-183173D01*
X1973875Y-182451D01*
X1974200Y-181441D01*
X1973983Y-180430D01*
X1973442Y-179564D01*
X1972467Y-178987D01*
X1971168Y-178698D01*
X1970410Y-178121D01*
X1970085Y-177110D01*
X1970302Y-176100D01*
X1970843Y-175378D01*
X1971601Y-174945D01*
X1972359D01*
X1973117Y-175234D01*
X1973767Y-175955D01*
G01X1981128Y-186493D02*
X1982211Y-185049D01*
X1982752Y-183606D01*
Y-177832D01*
X1982211Y-176388D01*
X1981128Y-174945D01*
G01X1783968Y103689D02*
X1782885Y105133D01*
X1782344Y106576D01*
Y112350D01*
X1782885Y113794D01*
X1783968Y115237D01*
G01X1791005Y106576D02*
Y115237D01*
X1793603D01*
X1794469Y114804D01*
X1795119Y113794D01*
X1795335Y112639D01*
X1795119Y111484D01*
X1794577Y110618D01*
X1793603Y110185D01*
X1791005D01*
G01X1799124Y106576D02*
X1801831Y115237D01*
X1804538Y106576D01*
G01X1803563Y109607D02*
X1800099D01*
G01X1808110Y106576D02*
Y115237D01*
X1810275D01*
X1811142Y114804D01*
X1811791Y114227D01*
X1812333Y113361D01*
X1812766Y112350D01*
X1812874Y110906D01*
X1812766Y109463D01*
X1812333Y108452D01*
X1811791Y107586D01*
X1811142Y107009D01*
X1810275Y106576D01*
X1808110D01*
G01X1819694Y103689D02*
X1820777Y105133D01*
X1821318Y106576D01*
Y112350D01*
X1820777Y113794D01*
X1819694Y115237D01*
G01X1827273Y103689D02*
X1826190Y105133D01*
X1825649Y106576D01*
Y112350D01*
X1826190Y113794D01*
X1827273Y115237D01*
G01X1833985Y106576D02*
Y115237D01*
X1838965Y106576D01*
Y115237D01*
G01X1845136Y106576D02*
X1844270Y106720D01*
X1843512Y107298D01*
X1842862Y108164D01*
X1842429Y109174D01*
X1842213Y110329D01*
Y111484D01*
X1842429Y112639D01*
X1842862Y113649D01*
X1843512Y114515D01*
X1844270Y115093D01*
X1845136Y115237D01*
X1846002Y115093D01*
X1846760Y114515D01*
X1847410Y113649D01*
X1847843Y112639D01*
X1848059Y111484D01*
Y110329D01*
X1847843Y109174D01*
X1847410Y108164D01*
X1846760Y107298D01*
X1846002Y106720D01*
X1845136Y106576D01*
G01X1862458Y115237D02*
Y106576D01*
G01X1859968Y115237D02*
X1864948D01*
G01X1868954Y106576D02*
Y115237D01*
X1871660D01*
X1872526Y114804D01*
X1873068Y114227D01*
X1873284Y113072D01*
X1873068Y111917D01*
X1872418Y111195D01*
X1871660Y110762D01*
X1868954D01*
G01X1871660D02*
X1873284Y106576D01*
G01X1877073D02*
X1879780Y115237D01*
X1882487Y106576D01*
G01X1881512Y109607D02*
X1878048D01*
G01X1890823Y114515D02*
X1890173Y114948D01*
X1889415Y115237D01*
X1888549D01*
X1887575Y114804D01*
X1886817Y114082D01*
X1886276Y113216D01*
X1885842Y111773D01*
X1885734Y110473D01*
X1885951Y109174D01*
X1886276Y108308D01*
X1886925Y107442D01*
X1887683Y106865D01*
X1888441Y106576D01*
X1889199D01*
X1889957Y106865D01*
X1890606Y107298D01*
X1891148Y107875D01*
G01X1899267Y106576D02*
X1894937D01*
Y115237D01*
X1899267D01*
G01X1897535Y111051D02*
X1894937D01*
G01X1911717Y106576D02*
X1914424Y115237D01*
X1917131Y106576D01*
G01X1916156Y109607D02*
X1912692D01*
G01X1923085Y115237D02*
Y106576D01*
G01X1920595Y115237D02*
X1925575D01*
G01X1937700Y106576D02*
X1940407Y115237D01*
X1943114Y106576D01*
G01X1942139Y109607D02*
X1938675D01*
G01X1946903Y115237D02*
Y106576D01*
X1951233D01*
G01X1955564Y115237D02*
Y106576D01*
X1959894D01*
G01X1972886Y115237D02*
Y106576D01*
X1977216D01*
G01X1981005D02*
X1983712Y115237D01*
X1986419Y106576D01*
G01X1985444Y109607D02*
X1981980D01*
G01X1992373Y106576D02*
Y110473D01*
X1990208Y115237D01*
G01X1994538D02*
X1992373Y110473D01*
G01X2003199Y106576D02*
X1998869D01*
Y115237D01*
X2003199D01*
G01X2001467Y111051D02*
X1998869D01*
G01X2007530Y106576D02*
Y115237D01*
X2010236D01*
X2011102Y114804D01*
X2011644Y114227D01*
X2011860Y113072D01*
X2011644Y111917D01*
X2010994Y111195D01*
X2010236Y110762D01*
X2007530D01*
G01X2010236D02*
X2011860Y106576D01*
G01X2016082Y107731D02*
X2016949Y107009D01*
X2017923Y106576D01*
X2018789D01*
X2019655Y107009D01*
X2020305Y107731D01*
X2020630Y108741D01*
X2020413Y109752D01*
X2019872Y110618D01*
X2018897Y111195D01*
X2017598Y111484D01*
X2016840Y112061D01*
X2016515Y113072D01*
X2016732Y114082D01*
X2017273Y114804D01*
X2018031Y115237D01*
X2018789D01*
X2019547Y114948D01*
X2020197Y114227D01*
G01X2027558Y103689D02*
X2028641Y105133D01*
X2029182Y106576D01*
Y112350D01*
X2028641Y113794D01*
X2027558Y115237D01*
G01X1805839Y565737D02*
X1797178D01*
X1798910Y564438D01*
G01X1805839D02*
Y567036D01*
G01X1804540Y572016D02*
X1805262Y572666D01*
X1805695Y573424D01*
X1805839Y574398D01*
X1805550Y575372D01*
X1804973Y576130D01*
X1803963Y576672D01*
X1802808Y576780D01*
X1801653Y576563D01*
X1800931Y576022D01*
X1800354Y575264D01*
X1800209Y574506D01*
X1800354Y573748D01*
X1800931Y572774D01*
X1797178Y573099D01*
Y576022D01*
G01X1805839Y583059D02*
X1797178D01*
X1798910Y581760D01*
G01X1805839D02*
Y584358D01*
G01X1806128Y591720D02*
X1805983Y591503D01*
X1805695D01*
X1805550Y591720D01*
X1805695Y591937D01*
X1805983D01*
X1806128Y591720D01*
G01X1804540Y597999D02*
X1805262Y598649D01*
X1805695Y599407D01*
X1805839Y600381D01*
X1805550Y601355D01*
X1804973Y602113D01*
X1803963Y602655D01*
X1802808Y602763D01*
X1801653Y602546D01*
X1800931Y602005D01*
X1800354Y601247D01*
X1800209Y600489D01*
X1800354Y599731D01*
X1800931Y598757D01*
X1797178Y599082D01*
Y602005D01*
G01Y609042D02*
X1797467Y608176D01*
X1798188Y607526D01*
X1799054Y607093D01*
X1800209Y606768D01*
X1801509Y606660D01*
X1802808Y606768D01*
X1803963Y607093D01*
X1804829Y607526D01*
X1805550Y608176D01*
X1805839Y609042D01*
X1805550Y609908D01*
X1804829Y610558D01*
X1803963Y610991D01*
X1802808Y611316D01*
X1801509Y611424D01*
X1800209Y611316D01*
X1799054Y610991D01*
X1798188Y610558D01*
X1797467Y609908D01*
X1797178Y609042D01*
G01X1785331Y790827D02*
X1786089Y790106D01*
X1786955Y789817D01*
X1787822Y790106D01*
X1788579Y790972D01*
X1789121Y792271D01*
X1789337Y793570D01*
Y795158D01*
X1789121Y796457D01*
X1788579Y797612D01*
X1787930Y798189D01*
X1787172Y798478D01*
X1786306Y798189D01*
X1785656Y797612D01*
X1785223Y796746D01*
X1785007Y795591D01*
X1785223Y794581D01*
X1785765Y793570D01*
X1786414Y792993D01*
X1787172Y792848D01*
X1788038Y793137D01*
X1788688Y793859D01*
X1789337Y795158D01*
G01X1797132Y789817D02*
Y798478D01*
X1793126Y792271D01*
X1798540D01*
G01X1804494Y789528D02*
X1804277Y789673D01*
Y789961D01*
X1804494Y790106D01*
X1804711Y789961D01*
Y789673D01*
X1804494Y789528D01*
G01X1810773Y791549D02*
X1811423Y790539D01*
X1812289Y789961D01*
X1813263Y789817D01*
X1814129Y789961D01*
X1814996Y790683D01*
X1815537Y791549D01*
X1815645Y792415D01*
X1815429Y793426D01*
X1814671Y794147D01*
X1813913Y794436D01*
X1812938D01*
G01X1813913D02*
X1814562Y794869D01*
X1815104Y795591D01*
X1815320Y796457D01*
X1815104Y797323D01*
X1814562Y798045D01*
X1813588Y798478D01*
X1812614Y798334D01*
X1811639Y797756D01*
G01X1821816Y789817D02*
Y798478D01*
X1820517Y796746D01*
G01Y789817D02*
X1823115D01*
G01X1795596Y1030486D02*
X1796246Y1029476D01*
X1797112Y1028898D01*
X1798086Y1028754D01*
X1798952Y1028898D01*
X1799819Y1029620D01*
X1800360Y1030486D01*
X1800468Y1031352D01*
X1800252Y1032363D01*
X1799494Y1033084D01*
X1798736Y1033373D01*
X1797761D01*
G01X1798736D02*
X1799385Y1033806D01*
X1799927Y1034528D01*
X1800143Y1035394D01*
X1799927Y1036260D01*
X1799385Y1036982D01*
X1798411Y1037415D01*
X1797437Y1037271D01*
X1796462Y1036693D01*
G01X1806639Y1028465D02*
X1806422Y1028610D01*
Y1028898D01*
X1806639Y1029043D01*
X1806856Y1028898D01*
Y1028610D01*
X1806639Y1028465D01*
G01X1812918Y1030053D02*
X1813568Y1029331D01*
X1814326Y1028898D01*
X1815300Y1028754D01*
X1816274Y1029043D01*
X1817032Y1029620D01*
X1817574Y1030630D01*
X1817682Y1031785D01*
X1817465Y1032940D01*
X1816924Y1033662D01*
X1816166Y1034239D01*
X1815408Y1034384D01*
X1814650Y1034239D01*
X1813676Y1033662D01*
X1814001Y1037415D01*
X1816924D01*
G01X1823961D02*
X1823095Y1037126D01*
X1822445Y1036405D01*
X1822012Y1035539D01*
X1821687Y1034384D01*
X1821579Y1033084D01*
X1821687Y1031785D01*
X1822012Y1030630D01*
X1822445Y1029764D01*
X1823095Y1029043D01*
X1823961Y1028754D01*
X1824827Y1029043D01*
X1825477Y1029764D01*
X1825910Y1030630D01*
X1826235Y1031785D01*
X1826343Y1033084D01*
X1826235Y1034384D01*
X1825910Y1035539D01*
X1825477Y1036405D01*
X1824827Y1037126D01*
X1823961Y1037415D01*
G01X1793107Y1025867D02*
X1792024Y1027311D01*
X1791483Y1028754D01*
Y1034528D01*
X1792024Y1035972D01*
X1793107Y1037415D01*
G01X1800144Y1028754D02*
Y1037415D01*
X1802742D01*
X1803608Y1036982D01*
X1804258Y1035972D01*
X1804474Y1034817D01*
X1804258Y1033662D01*
X1803716Y1032796D01*
X1802742Y1032363D01*
X1800144D01*
G01X1810970Y1037415D02*
Y1028754D01*
G01X1808480Y1037415D02*
X1813460D01*
G01X1817357Y1028754D02*
Y1037415D01*
G01X1821905D02*
Y1028754D01*
G01Y1033084D02*
X1817357D01*
G01X1828833Y1025867D02*
X1829916Y1027311D01*
X1830457Y1028754D01*
Y1034528D01*
X1829916Y1035972D01*
X1828833Y1037415D01*
G01X1809129Y1028754D02*
Y1034528D01*
G01Y1033084D02*
X1809563Y1033806D01*
X1810212Y1034384D01*
X1811078Y1034528D01*
X1811836Y1034384D01*
X1812486Y1033806D01*
X1812811Y1032796D01*
Y1028754D01*
G01X1788182Y1153985D02*
X1787099Y1155429D01*
X1786558Y1156872D01*
Y1162646D01*
X1787099Y1164090D01*
X1788182Y1165533D01*
G01X1795219Y1156872D02*
Y1165533D01*
X1797817D01*
X1798683Y1165100D01*
X1799333Y1164090D01*
X1799549Y1162935D01*
X1799333Y1161780D01*
X1798791Y1160914D01*
X1797817Y1160481D01*
X1795219D01*
G01X1803338Y1156872D02*
X1806045Y1165533D01*
X1808752Y1156872D01*
G01X1807777Y1159903D02*
X1804313D01*
G01X1812324Y1156872D02*
Y1165533D01*
X1814489D01*
X1815356Y1165100D01*
X1816005Y1164523D01*
X1816547Y1163657D01*
X1816980Y1162646D01*
X1817088Y1161202D01*
X1816980Y1159759D01*
X1816547Y1158748D01*
X1816005Y1157882D01*
X1815356Y1157305D01*
X1814489Y1156872D01*
X1812324D01*
G01X1823908Y1153985D02*
X1824991Y1155429D01*
X1825532Y1156872D01*
Y1162646D01*
X1824991Y1164090D01*
X1823908Y1165533D01*
G01X1831487Y1153985D02*
X1830404Y1155429D01*
X1829863Y1156872D01*
Y1162646D01*
X1830404Y1164090D01*
X1831487Y1165533D01*
G01X1838199Y1156872D02*
Y1165533D01*
X1843179Y1156872D01*
Y1165533D01*
G01X1849350Y1156872D02*
X1848484Y1157016D01*
X1847726Y1157594D01*
X1847076Y1158460D01*
X1846643Y1159470D01*
X1846427Y1160625D01*
Y1161780D01*
X1846643Y1162935D01*
X1847076Y1163945D01*
X1847726Y1164811D01*
X1848484Y1165389D01*
X1849350Y1165533D01*
X1850216Y1165389D01*
X1850974Y1164811D01*
X1851624Y1163945D01*
X1852057Y1162935D01*
X1852273Y1161780D01*
Y1160625D01*
X1852057Y1159470D01*
X1851624Y1158460D01*
X1850974Y1157594D01*
X1850216Y1157016D01*
X1849350Y1156872D01*
G01X1866672Y1165533D02*
Y1156872D01*
G01X1864182Y1165533D02*
X1869162D01*
G01X1873168Y1156872D02*
Y1165533D01*
X1875874D01*
X1876740Y1165100D01*
X1877282Y1164523D01*
X1877498Y1163368D01*
X1877282Y1162213D01*
X1876632Y1161491D01*
X1875874Y1161058D01*
X1873168D01*
G01X1875874D02*
X1877498Y1156872D01*
G01X1881287D02*
X1883994Y1165533D01*
X1886701Y1156872D01*
G01X1885726Y1159903D02*
X1882262D01*
G01X1895037Y1164811D02*
X1894387Y1165244D01*
X1893629Y1165533D01*
X1892763D01*
X1891789Y1165100D01*
X1891031Y1164378D01*
X1890490Y1163512D01*
X1890056Y1162069D01*
X1889948Y1160769D01*
X1890165Y1159470D01*
X1890490Y1158604D01*
X1891139Y1157738D01*
X1891897Y1157161D01*
X1892655Y1156872D01*
X1893413D01*
X1894171Y1157161D01*
X1894820Y1157594D01*
X1895362Y1158171D01*
G01X1903481Y1156872D02*
X1899151D01*
Y1165533D01*
X1903481D01*
G01X1901749Y1161347D02*
X1899151D01*
G01X1915931Y1156872D02*
X1918638Y1165533D01*
X1921345Y1156872D01*
G01X1920370Y1159903D02*
X1916906D01*
G01X1927299Y1165533D02*
Y1156872D01*
G01X1924809Y1165533D02*
X1929789D01*
G01X1941914Y1156872D02*
X1944621Y1165533D01*
X1947328Y1156872D01*
G01X1946353Y1159903D02*
X1942889D01*
G01X1951117Y1165533D02*
Y1156872D01*
X1955447D01*
G01X1959778Y1165533D02*
Y1156872D01*
X1964108D01*
G01X1977100Y1165533D02*
Y1156872D01*
X1981430D01*
G01X1985219D02*
X1987926Y1165533D01*
X1990633Y1156872D01*
G01X1989658Y1159903D02*
X1986194D01*
G01X1996587Y1156872D02*
Y1160769D01*
X1994422Y1165533D01*
G01X1998752D02*
X1996587Y1160769D01*
G01X2007413Y1156872D02*
X2003083D01*
Y1165533D01*
X2007413D01*
G01X2005681Y1161347D02*
X2003083D01*
G01X2011744Y1156872D02*
Y1165533D01*
X2014450D01*
X2015316Y1165100D01*
X2015858Y1164523D01*
X2016074Y1163368D01*
X2015858Y1162213D01*
X2015208Y1161491D01*
X2014450Y1161058D01*
X2011744D01*
G01X2014450D02*
X2016074Y1156872D01*
G01X2020296Y1158027D02*
X2021163Y1157305D01*
X2022137Y1156872D01*
X2023003D01*
X2023869Y1157305D01*
X2024519Y1158027D01*
X2024844Y1159037D01*
X2024627Y1160048D01*
X2024086Y1160914D01*
X2023111Y1161491D01*
X2021812Y1161780D01*
X2021054Y1162357D01*
X2020729Y1163368D01*
X2020946Y1164378D01*
X2021487Y1165100D01*
X2022245Y1165533D01*
X2023003D01*
X2023761Y1165244D01*
X2024411Y1164523D01*
G01X2031772Y1153985D02*
X2032855Y1155429D01*
X2033396Y1156872D01*
Y1162646D01*
X2032855Y1164090D01*
X2031772Y1165533D01*
G01X1877954Y-183606D02*
Y-174945D01*
X1873948Y-181152D01*
X1879362D01*
G01X1883909Y-180719D02*
X1886723D01*
G01X1865937Y-179997D02*
X1866695Y-178987D01*
X1867344Y-178409D01*
X1868211Y-178121D01*
X1868968Y-178409D01*
X1869510Y-178987D01*
X1869943Y-179853D01*
X1870051Y-180863D01*
X1869943Y-181730D01*
X1869510Y-182596D01*
X1868860Y-183317D01*
X1868102Y-183606D01*
X1867236Y-183317D01*
X1866478Y-182451D01*
X1866045Y-181152D01*
X1865937Y-179709D01*
X1866153Y-177832D01*
X1866478Y-176821D01*
X1867020Y-175811D01*
X1867777Y-175089D01*
X1868535Y-174945D01*
X1869293Y-175234D01*
X1869835Y-175955D01*
G01X1876655Y-183895D02*
X1876438Y-183750D01*
Y-183462D01*
X1876655Y-183317D01*
X1876872Y-183462D01*
Y-183750D01*
X1876655Y-183895D01*
G01X1885316Y-174945D02*
X1884450Y-175234D01*
X1883800Y-175955D01*
X1883367Y-176821D01*
X1883042Y-177976D01*
X1882934Y-179276D01*
X1883042Y-180575D01*
X1883367Y-181730D01*
X1883800Y-182596D01*
X1884450Y-183317D01*
X1885316Y-183606D01*
X1886182Y-183317D01*
X1886832Y-182596D01*
X1887265Y-181730D01*
X1887590Y-180575D01*
X1887698Y-179276D01*
X1887590Y-177976D01*
X1887265Y-176821D01*
X1886832Y-175955D01*
X1886182Y-175234D01*
X1885316Y-174945D01*
G01X1893977D02*
X1893111Y-175234D01*
X1892461Y-175955D01*
X1892028Y-176821D01*
X1891703Y-177976D01*
X1891595Y-179276D01*
X1891703Y-180575D01*
X1892028Y-181730D01*
X1892461Y-182596D01*
X1893111Y-183317D01*
X1893977Y-183606D01*
X1894843Y-183317D01*
X1895493Y-182596D01*
X1895926Y-181730D01*
X1896251Y-180575D01*
X1896359Y-179276D01*
X1896251Y-177976D01*
X1895926Y-176821D01*
X1895493Y-175955D01*
X1894843Y-175234D01*
X1893977Y-174945D01*
G01X1863163Y747471D02*
Y756132D01*
X1859157Y749925D01*
X1864571D01*
G01X1869118Y750358D02*
X1871932D01*
G01X1864354Y747471D02*
Y753245D01*
G01Y751801D02*
X1864788Y752523D01*
X1865437Y753101D01*
X1866303Y753245D01*
X1867061Y753101D01*
X1867711Y752523D01*
X1868036Y751513D01*
Y747471D01*
G01X1850821Y749203D02*
X1851471Y748193D01*
X1852337Y747615D01*
X1853311Y747471D01*
X1854177Y747615D01*
X1855044Y748337D01*
X1855585Y749203D01*
X1855693Y750069D01*
X1855477Y751080D01*
X1854719Y751801D01*
X1853961Y752090D01*
X1852986D01*
G01X1853961D02*
X1854610Y752523D01*
X1855152Y753245D01*
X1855368Y754111D01*
X1855152Y754977D01*
X1854610Y755699D01*
X1853636Y756132D01*
X1852662Y755988D01*
X1851687Y755410D01*
G01X1861864Y747182D02*
X1861647Y747327D01*
Y747615D01*
X1861864Y747760D01*
X1862081Y747615D01*
Y747327D01*
X1861864Y747182D01*
G01X1870525Y756132D02*
X1869659Y755843D01*
X1869009Y755122D01*
X1868576Y754256D01*
X1868251Y753101D01*
X1868143Y751801D01*
X1868251Y750502D01*
X1868576Y749347D01*
X1869009Y748481D01*
X1869659Y747760D01*
X1870525Y747471D01*
X1871391Y747760D01*
X1872041Y748481D01*
X1872474Y749347D01*
X1872799Y750502D01*
X1872907Y751801D01*
X1872799Y753101D01*
X1872474Y754256D01*
X1872041Y755122D01*
X1871391Y755843D01*
X1870525Y756132D01*
G01X1879186D02*
X1878320Y755843D01*
X1877670Y755122D01*
X1877237Y754256D01*
X1876912Y753101D01*
X1876804Y751801D01*
X1876912Y750502D01*
X1877237Y749347D01*
X1877670Y748481D01*
X1878320Y747760D01*
X1879186Y747471D01*
X1880052Y747760D01*
X1880702Y748481D01*
X1881135Y749347D01*
X1881460Y750502D01*
X1881568Y751801D01*
X1881460Y753101D01*
X1881135Y754256D01*
X1880702Y755122D01*
X1880052Y755843D01*
X1879186Y756132D01*
G01X1844001Y744584D02*
X1842918Y746028D01*
X1842377Y747471D01*
Y753245D01*
X1842918Y754689D01*
X1844001Y756132D01*
G01X1850713Y747471D02*
Y756132D01*
X1855693Y747471D01*
Y756132D01*
G01X1859699Y747471D02*
Y756132D01*
X1862297D01*
X1863163Y755699D01*
X1863813Y754689D01*
X1864029Y753534D01*
X1863813Y752379D01*
X1863271Y751513D01*
X1862297Y751080D01*
X1859699D01*
G01X1870525Y756132D02*
Y747471D01*
G01X1868035Y756132D02*
X1873015D01*
G01X1876912Y747471D02*
Y756132D01*
G01X1881460D02*
Y747471D01*
G01Y751801D02*
X1876912D01*
G01X1888388Y744584D02*
X1889471Y746028D01*
X1890012Y747471D01*
Y753245D01*
X1889471Y754689D01*
X1888388Y756132D01*
G01X1941996Y-894995D02*
Y-883633D01*
X1940292Y-885905D01*
G01Y-894995D02*
X1943700D01*
G01X1953359D02*
Y-883633D01*
X1951655Y-885905D01*
G01Y-894995D02*
X1955063D01*
G01X1930537Y-802681D02*
X1934947Y-827681D01*
X1939987Y-802681D01*
X1945027Y-827681D01*
X1949437Y-802681D01*
G01X1965187Y-811015D02*
Y-827681D01*
G01Y-804348D02*
X1964557Y-803931D01*
Y-803098D01*
X1965187Y-802681D01*
X1965817Y-803098D01*
Y-803931D01*
X1965187Y-804348D01*
G01X1985662Y-824765D02*
X1987237Y-826431D01*
X1989442Y-827681D01*
X1991332D01*
X1993222Y-826848D01*
X1994482Y-825598D01*
X1995112Y-823932D01*
X1994797Y-821431D01*
X1993537Y-820181D01*
X1987867Y-817682D01*
X1986607Y-814764D01*
X1987237Y-812681D01*
X1988497Y-811431D01*
X1990387Y-811015D01*
X1992277Y-811431D01*
X1994167Y-812681D01*
G01X2015587Y-802681D02*
Y-827681D01*
G01X2011177Y-811015D02*
X2019997D01*
G01X2036377Y-827681D02*
Y-811015D01*
G01Y-814347D02*
X2037952Y-812681D01*
X2039527Y-811431D01*
X2041732Y-811015D01*
X2043307Y-811431D01*
X2045197Y-812681D01*
G01X2065987Y-827681D02*
X2064097Y-827264D01*
X2062207Y-825598D01*
X2060947Y-822681D01*
X2060317Y-819348D01*
X2060947Y-816015D01*
X2062207Y-813098D01*
X2064097Y-811431D01*
X2065987Y-811015D01*
X2067877Y-811431D01*
X2069767Y-813098D01*
X2071027Y-816015D01*
X2071342Y-819348D01*
X2071027Y-822681D01*
X2069767Y-825598D01*
X2067877Y-827264D01*
X2065987Y-827681D01*
G01X2085832D02*
Y-811015D01*
G01Y-815181D02*
X2087092Y-813098D01*
X2088982Y-811431D01*
X2091502Y-811015D01*
X2093707Y-811431D01*
X2095597Y-813098D01*
X2096542Y-816015D01*
Y-827681D01*
G01X2148517Y-804765D02*
X2146627Y-803514D01*
X2144422Y-802681D01*
X2141902D01*
X2139067Y-803931D01*
X2136862Y-806014D01*
X2135287Y-808515D01*
X2134027Y-812681D01*
X2133712Y-816431D01*
X2134342Y-820181D01*
X2135287Y-822681D01*
X2137177Y-825182D01*
X2139382Y-826848D01*
X2141587Y-827681D01*
X2143792D01*
X2145997Y-826848D01*
X2147887Y-825598D01*
X2149462Y-823932D01*
G01X2166787Y-827681D02*
X2164897Y-827264D01*
X2163007Y-825598D01*
X2161747Y-822681D01*
X2161117Y-819348D01*
X2161747Y-816015D01*
X2163007Y-813098D01*
X2164897Y-811431D01*
X2166787Y-811015D01*
X2168677Y-811431D01*
X2170567Y-813098D01*
X2171827Y-816015D01*
X2172142Y-819348D01*
X2171827Y-822681D01*
X2170567Y-825598D01*
X2168677Y-827264D01*
X2166787Y-827681D01*
G01X2187577D02*
Y-811015D01*
G01Y-814347D02*
X2189152Y-812681D01*
X2190727Y-811431D01*
X2192932Y-811015D01*
X2194507Y-811431D01*
X2196397Y-812681D01*
G01X2211517Y-836014D02*
Y-811015D01*
G01Y-814764D02*
X2213092Y-812681D01*
X2214667Y-811431D01*
X2217187Y-811015D01*
X2219392Y-811431D01*
X2221597Y-813514D01*
X2222542Y-816431D01*
X2222857Y-819348D01*
X2222542Y-822265D01*
X2221597Y-825182D01*
X2219707Y-826848D01*
X2217187Y-827681D01*
X2214982Y-827264D01*
X2212777Y-826015D01*
X2211517Y-824348D01*
G01X2242387Y-827681D02*
X2240497Y-827264D01*
X2238607Y-825598D01*
X2237347Y-822681D01*
X2236717Y-819348D01*
X2237347Y-816015D01*
X2238607Y-813098D01*
X2240497Y-811431D01*
X2242387Y-811015D01*
X2244277Y-811431D01*
X2246167Y-813098D01*
X2247427Y-816015D01*
X2247742Y-819348D01*
X2247427Y-822681D01*
X2246167Y-825598D01*
X2244277Y-827264D01*
X2242387Y-827681D01*
G01X2263177D02*
Y-811015D01*
G01Y-814347D02*
X2264752Y-812681D01*
X2266327Y-811431D01*
X2268532Y-811015D01*
X2270107Y-811431D01*
X2271997Y-812681D01*
G01X2298457Y-827681D02*
Y-811015D01*
G01Y-813931D02*
X2297197Y-812265D01*
X2295307Y-811431D01*
X2293102Y-811015D01*
X2290897Y-811848D01*
X2289007Y-813514D01*
X2287747Y-816015D01*
X2287117Y-819348D01*
X2287747Y-822681D01*
X2289007Y-825182D01*
X2290897Y-826848D01*
X2293102Y-827681D01*
X2295307Y-827264D01*
X2297197Y-826015D01*
X2298457Y-824348D01*
G01X2317987Y-802681D02*
Y-827681D01*
G01X2313577Y-811015D02*
X2322397D01*
G01X2343187D02*
Y-827681D01*
G01Y-804348D02*
X2342557Y-803931D01*
Y-803098D01*
X2343187Y-802681D01*
X2343817Y-803098D01*
Y-803931D01*
X2343187Y-804348D01*
G01X2368387Y-827681D02*
X2366497Y-827264D01*
X2364607Y-825598D01*
X2363347Y-822681D01*
X2362717Y-819348D01*
X2363347Y-816015D01*
X2364607Y-813098D01*
X2366497Y-811431D01*
X2368387Y-811015D01*
X2370277Y-811431D01*
X2372167Y-813098D01*
X2373427Y-816015D01*
X2373742Y-819348D01*
X2373427Y-822681D01*
X2372167Y-825598D01*
X2370277Y-827264D01*
X2368387Y-827681D01*
G01X2388232D02*
Y-811015D01*
G01Y-815181D02*
X2389492Y-813098D01*
X2391382Y-811431D01*
X2393902Y-811015D01*
X2396107Y-811431D01*
X2397997Y-813098D01*
X2398942Y-816015D01*
Y-827681D01*
G01X1879145Y-183606D02*
Y-177832D01*
G01Y-179276D02*
X1879579Y-178554D01*
X1880228Y-177976D01*
X1881094Y-177832D01*
X1881852Y-177976D01*
X1882502Y-178554D01*
X1882827Y-179564D01*
Y-183606D01*
G01X1903922Y106576D02*
Y112350D01*
G01Y110906D02*
X1904356Y111628D01*
X1905005Y112206D01*
X1905871Y112350D01*
X1906629Y112206D01*
X1907279Y111628D01*
X1907604Y110618D01*
Y106576D01*
G01X1890930Y107586D02*
X1891688Y106865D01*
X1892554Y106576D01*
X1893421Y106865D01*
X1894178Y107731D01*
X1894720Y109030D01*
X1894936Y110329D01*
Y111917D01*
X1894720Y113216D01*
X1894178Y114371D01*
X1893529Y114948D01*
X1892771Y115237D01*
X1891905Y114948D01*
X1891255Y114371D01*
X1890822Y113505D01*
X1890606Y112350D01*
X1890822Y111340D01*
X1891364Y110329D01*
X1892013Y109752D01*
X1892771Y109607D01*
X1893637Y109896D01*
X1894287Y110618D01*
X1894936Y111917D01*
G01X1901432Y106287D02*
X1901215Y106432D01*
Y106720D01*
X1901432Y106865D01*
X1901649Y106720D01*
Y106432D01*
X1901432Y106287D01*
G01X1907711Y107875D02*
X1908361Y107153D01*
X1909119Y106720D01*
X1910093Y106576D01*
X1911067Y106865D01*
X1911825Y107442D01*
X1912367Y108452D01*
X1912475Y109607D01*
X1912258Y110762D01*
X1911717Y111484D01*
X1910959Y112061D01*
X1910201Y112206D01*
X1909443Y112061D01*
X1908469Y111484D01*
X1908794Y115237D01*
X1911717D01*
G01X1918754D02*
X1917888Y114948D01*
X1917238Y114227D01*
X1916805Y113361D01*
X1916480Y112206D01*
X1916372Y110906D01*
X1916480Y109607D01*
X1916805Y108452D01*
X1917238Y107586D01*
X1917888Y106865D01*
X1918754Y106576D01*
X1919620Y106865D01*
X1920270Y107586D01*
X1920703Y108452D01*
X1921028Y109607D01*
X1921136Y110906D01*
X1921028Y112206D01*
X1920703Y113361D01*
X1920270Y114227D01*
X1919620Y114948D01*
X1918754Y115237D01*
G01X1938777Y1104607D02*
X1937694Y1106051D01*
X1937153Y1107494D01*
Y1113268D01*
X1937694Y1114712D01*
X1938777Y1116155D01*
G01X1945489Y1107494D02*
Y1116155D01*
X1950469Y1107494D01*
Y1116155D01*
G01X1956640Y1107494D02*
X1955774Y1107638D01*
X1955016Y1108216D01*
X1954366Y1109082D01*
X1953933Y1110092D01*
X1953717Y1111247D01*
Y1112402D01*
X1953933Y1113557D01*
X1954366Y1114567D01*
X1955016Y1115433D01*
X1955774Y1116011D01*
X1956640Y1116155D01*
X1957506Y1116011D01*
X1958264Y1115433D01*
X1958914Y1114567D01*
X1959347Y1113557D01*
X1959563Y1112402D01*
Y1111247D01*
X1959347Y1110092D01*
X1958914Y1109082D01*
X1958264Y1108216D01*
X1957506Y1107638D01*
X1956640Y1107494D01*
G01X1973962Y1116155D02*
Y1107494D01*
G01X1971472Y1116155D02*
X1976452D01*
G01X1980458Y1107494D02*
Y1116155D01*
X1983164D01*
X1984030Y1115722D01*
X1984572Y1115145D01*
X1984788Y1113990D01*
X1984572Y1112835D01*
X1983922Y1112113D01*
X1983164Y1111680D01*
X1980458D01*
G01X1983164D02*
X1984788Y1107494D01*
G01X1988577D02*
X1991284Y1116155D01*
X1993991Y1107494D01*
G01X1993016Y1110525D02*
X1989552D01*
G01X2002327Y1115433D02*
X2001677Y1115866D01*
X2000919Y1116155D01*
X2000053D01*
X1999079Y1115722D01*
X1998321Y1115000D01*
X1997780Y1114134D01*
X1997346Y1112691D01*
X1997238Y1111391D01*
X1997455Y1110092D01*
X1997780Y1109226D01*
X1998429Y1108360D01*
X1999187Y1107783D01*
X1999945Y1107494D01*
X2000703D01*
X2001461Y1107783D01*
X2002110Y1108216D01*
X2002652Y1108793D01*
G01X2010771Y1107494D02*
X2006441D01*
Y1116155D01*
X2010771D01*
G01X2009039Y1111969D02*
X2006441D01*
G01X2023221Y1107494D02*
X2025928Y1116155D01*
X2028635Y1107494D01*
G01X2027660Y1110525D02*
X2024196D01*
G01X2034589Y1116155D02*
Y1107494D01*
G01X2032099Y1116155D02*
X2037079D01*
G01X2049204Y1107494D02*
X2051911Y1116155D01*
X2054618Y1107494D01*
G01X2053643Y1110525D02*
X2050179D01*
G01X2058407Y1116155D02*
Y1107494D01*
X2062737D01*
G01X2067068Y1116155D02*
Y1107494D01*
X2071398D01*
G01X2084390Y1116155D02*
Y1107494D01*
X2088720D01*
G01X2092509D02*
X2095216Y1116155D01*
X2097923Y1107494D01*
G01X2096948Y1110525D02*
X2093484D01*
G01X2103877Y1107494D02*
Y1111391D01*
X2101712Y1116155D01*
G01X2106042D02*
X2103877Y1111391D01*
G01X2114703Y1107494D02*
X2110373D01*
Y1116155D01*
X2114703D01*
G01X2112971Y1111969D02*
X2110373D01*
G01X2119034Y1107494D02*
Y1116155D01*
X2121740D01*
X2122606Y1115722D01*
X2123148Y1115145D01*
X2123364Y1113990D01*
X2123148Y1112835D01*
X2122498Y1112113D01*
X2121740Y1111680D01*
X2119034D01*
G01X2121740D02*
X2123364Y1107494D01*
G01X2127586Y1108649D02*
X2128453Y1107927D01*
X2129427Y1107494D01*
X2130293D01*
X2131159Y1107927D01*
X2131809Y1108649D01*
X2132134Y1109659D01*
X2131917Y1110670D01*
X2131376Y1111536D01*
X2130401Y1112113D01*
X2129102Y1112402D01*
X2128344Y1112979D01*
X2128019Y1113990D01*
X2128236Y1115000D01*
X2128777Y1115722D01*
X2129535Y1116155D01*
X2130293D01*
X2131051Y1115866D01*
X2131701Y1115145D01*
G01X2139062Y1104607D02*
X2140145Y1106051D01*
X2140686Y1107494D01*
Y1113268D01*
X2140145Y1114712D01*
X2139062Y1116155D01*
G01X1895144Y1157882D02*
X1895902Y1157161D01*
X1896768Y1156872D01*
X1897635Y1157161D01*
X1898392Y1158027D01*
X1898934Y1159326D01*
X1899150Y1160625D01*
Y1162213D01*
X1898934Y1163512D01*
X1898392Y1164667D01*
X1897743Y1165244D01*
X1896985Y1165533D01*
X1896119Y1165244D01*
X1895469Y1164667D01*
X1895036Y1163801D01*
X1894820Y1162646D01*
X1895036Y1161636D01*
X1895578Y1160625D01*
X1896227Y1160048D01*
X1896985Y1159903D01*
X1897851Y1160192D01*
X1898501Y1160914D01*
X1899150Y1162213D01*
G01X1905646Y1156583D02*
X1905429Y1156728D01*
Y1157016D01*
X1905646Y1157161D01*
X1905863Y1157016D01*
Y1156728D01*
X1905646Y1156583D01*
G01X1911925Y1158171D02*
X1912575Y1157449D01*
X1913333Y1157016D01*
X1914307Y1156872D01*
X1915281Y1157161D01*
X1916039Y1157738D01*
X1916581Y1158748D01*
X1916689Y1159903D01*
X1916472Y1161058D01*
X1915931Y1161780D01*
X1915173Y1162357D01*
X1914415Y1162502D01*
X1913657Y1162357D01*
X1912683Y1161780D01*
X1913008Y1165533D01*
X1915931D01*
G01X1922968D02*
X1922102Y1165244D01*
X1921452Y1164523D01*
X1921019Y1163657D01*
X1920694Y1162502D01*
X1920586Y1161202D01*
X1920694Y1159903D01*
X1921019Y1158748D01*
X1921452Y1157882D01*
X1922102Y1157161D01*
X1922968Y1156872D01*
X1923834Y1157161D01*
X1924484Y1157882D01*
X1924917Y1158748D01*
X1925242Y1159903D01*
X1925350Y1161202D01*
X1925242Y1162502D01*
X1924917Y1163657D01*
X1924484Y1164523D01*
X1923834Y1165244D01*
X1922968Y1165533D01*
G01X1908136Y1156872D02*
Y1162646D01*
G01Y1161202D02*
X1908570Y1161924D01*
X1909219Y1162502D01*
X1910085Y1162646D01*
X1910843Y1162502D01*
X1911493Y1161924D01*
X1911818Y1160914D01*
Y1156872D01*
G01X1941996Y1282761D02*
Y1294123D01*
X1940292Y1291851D01*
G01Y1282761D02*
X1943700D01*
G01X1953359D02*
Y1294123D01*
X1951655Y1291851D01*
G01Y1282761D02*
X1955063D01*
G01X1959813Y-769172D02*
X1957813Y-768839D01*
X1956063Y-767506D01*
X1954563Y-765506D01*
X1953563Y-763172D01*
X1953063Y-760505D01*
Y-757839D01*
X1953563Y-755172D01*
X1954563Y-752838D01*
X1956063Y-750839D01*
X1957813Y-749505D01*
X1959813Y-749172D01*
X1961813Y-749505D01*
X1963563Y-750839D01*
X1965063Y-752838D01*
X1966063Y-755172D01*
X1966563Y-757839D01*
Y-760505D01*
X1966063Y-763172D01*
X1965063Y-765506D01*
X1963563Y-767506D01*
X1961813Y-768839D01*
X1959813Y-769172D01*
G01X1961813Y-763839D02*
X1964813Y-769172D01*
G01X1974313Y-749172D02*
Y-763505D01*
X1975313Y-766506D01*
X1977313Y-768505D01*
X1979813Y-769172D01*
X1982313Y-768505D01*
X1984313Y-766506D01*
X1985313Y-763505D01*
Y-749172D01*
G01X1996813D02*
X2002813D01*
G01X1999813D02*
Y-769172D01*
G01X1996813D02*
X2002813D01*
G01X2014063D02*
Y-749172D01*
X2025563Y-769172D01*
Y-749172D01*
G01X2045313Y-750839D02*
X2043813Y-749839D01*
X2042063Y-749172D01*
X2040063D01*
X2037813Y-750172D01*
X2036063Y-751839D01*
X2034813Y-753839D01*
X2033813Y-757172D01*
X2033563Y-760172D01*
X2034063Y-763172D01*
X2034813Y-765172D01*
X2036313Y-767172D01*
X2038063Y-768505D01*
X2039813Y-769172D01*
X2041563D01*
X2043313Y-768505D01*
X2044813Y-767506D01*
X2046063Y-766173D01*
G01X2059813Y-769172D02*
Y-760172D01*
X2054813Y-749172D01*
G01X2064813D02*
X2059813Y-760172D01*
G01X1979590Y-727132D02*
Y-707132D01*
X1976590Y-711132D01*
G01Y-727132D02*
X1982590D01*
G01X1957879Y-616971D02*
X1959139Y-615722D01*
X1960084Y-613639D01*
X1960714Y-610721D01*
X1960084Y-608222D01*
X1958824Y-606555D01*
X1956619Y-605305D01*
X1948114D01*
Y-630305D01*
X1958509D01*
X1960714Y-628639D01*
X1961974Y-626138D01*
X1962604Y-623222D01*
X1961974Y-620306D01*
X1960084Y-617805D01*
X1957879Y-616971D01*
X1948114D01*
G01X1976149Y-630305D02*
Y-613639D01*
G01Y-616971D02*
X1977724Y-615305D01*
X1979299Y-614055D01*
X1981504Y-613639D01*
X1983079Y-614055D01*
X1984969Y-615305D01*
G01X1999144Y-637805D02*
X2001034Y-638638D01*
X2003554Y-637805D01*
X2005129Y-636139D01*
X2006389Y-634055D01*
X2008279Y-627389D01*
X2012374Y-613639D01*
G01X2002294D02*
X2008279Y-627389D01*
G01X2035999Y-615722D02*
X2033794Y-614055D01*
X2031904Y-613639D01*
X2029384Y-614472D01*
X2027494Y-616138D01*
X2026234Y-619055D01*
X2025919Y-621972D01*
X2026234Y-624889D01*
X2027494Y-627389D01*
X2029384Y-629472D01*
X2031904Y-630305D01*
X2034109Y-629472D01*
X2035999Y-627806D01*
G01X2051434Y-619055D02*
X2061514D01*
X2060569Y-616138D01*
X2058994Y-614472D01*
X2056789Y-613639D01*
X2054584Y-614055D01*
X2052694Y-615305D01*
X2051434Y-618222D01*
X2050804Y-620722D01*
Y-623222D01*
X2051434Y-625722D01*
X2053009Y-628222D01*
X2054899Y-629888D01*
X2057104Y-630305D01*
X2059309Y-629472D01*
X2061514Y-626972D01*
G01X2113489Y-607389D02*
X2111599Y-606138D01*
X2109394Y-605305D01*
X2106874D01*
X2104039Y-606555D01*
X2101834Y-608638D01*
X2100259Y-611139D01*
X2098999Y-615305D01*
X2098684Y-619055D01*
X2099314Y-622805D01*
X2100259Y-625305D01*
X2102149Y-627806D01*
X2104354Y-629472D01*
X2106559Y-630305D01*
X2108764D01*
X2110969Y-629472D01*
X2112859Y-628222D01*
X2114434Y-626556D01*
G01X2137429Y-630305D02*
Y-613639D01*
G01Y-616555D02*
X2136169Y-614889D01*
X2134279Y-614055D01*
X2132074Y-613639D01*
X2129869Y-614472D01*
X2127979Y-616138D01*
X2126719Y-618639D01*
X2126089Y-621972D01*
X2126719Y-625305D01*
X2127979Y-627806D01*
X2129869Y-629472D01*
X2132074Y-630305D01*
X2134279Y-629888D01*
X2136169Y-628639D01*
X2137429Y-626972D01*
G01X2151604Y-630305D02*
Y-613639D01*
G01Y-617805D02*
X2152864Y-615722D01*
X2154754Y-614055D01*
X2157274Y-613639D01*
X2159479Y-614055D01*
X2161369Y-615722D01*
X2162314Y-618639D01*
Y-630305D01*
G01X2175544Y-637805D02*
X2177434Y-638638D01*
X2179954Y-637805D01*
X2181529Y-636139D01*
X2182789Y-634055D01*
X2184679Y-627389D01*
X2188774Y-613639D01*
G01X2178694D02*
X2184679Y-627389D01*
G01X2207359Y-630305D02*
X2205469Y-629888D01*
X2203579Y-628222D01*
X2202319Y-625305D01*
X2201689Y-621972D01*
X2202319Y-618639D01*
X2203579Y-615722D01*
X2205469Y-614055D01*
X2207359Y-613639D01*
X2209249Y-614055D01*
X2211139Y-615722D01*
X2212399Y-618639D01*
X2212714Y-621972D01*
X2212399Y-625305D01*
X2211139Y-628222D01*
X2209249Y-629888D01*
X2207359Y-630305D01*
G01X2227204D02*
Y-613639D01*
G01Y-617805D02*
X2228464Y-615722D01*
X2230354Y-614055D01*
X2232874Y-613639D01*
X2235079Y-614055D01*
X2236969Y-615722D01*
X2237914Y-618639D01*
Y-630305D01*
G01X2276344Y-626972D02*
X2278864Y-629055D01*
X2281699Y-630305D01*
X2284219D01*
X2286739Y-629055D01*
X2288629Y-626972D01*
X2289574Y-624055D01*
X2288944Y-621139D01*
X2287369Y-618639D01*
X2284534Y-616971D01*
X2280754Y-616138D01*
X2278549Y-614472D01*
X2277604Y-611555D01*
X2278234Y-608638D01*
X2279809Y-606555D01*
X2282014Y-605305D01*
X2284219D01*
X2286424Y-606138D01*
X2288314Y-608222D01*
G01X2315089Y-607389D02*
X2313199Y-606138D01*
X2310994Y-605305D01*
X2308474D01*
X2305639Y-606555D01*
X2303434Y-608638D01*
X2301859Y-611139D01*
X2300599Y-615305D01*
X2300284Y-619055D01*
X2300914Y-622805D01*
X2301859Y-625305D01*
X2303749Y-627806D01*
X2305954Y-629472D01*
X2308159Y-630305D01*
X2310364D01*
X2312569Y-629472D01*
X2314459Y-628222D01*
X2316034Y-626556D01*
G01X2340289Y-607389D02*
X2338399Y-606138D01*
X2336194Y-605305D01*
X2333674D01*
X2330839Y-606555D01*
X2328634Y-608638D01*
X2327059Y-611139D01*
X2325799Y-615305D01*
X2325484Y-619055D01*
X2326114Y-622805D01*
X2327059Y-625305D01*
X2328949Y-627806D01*
X2331154Y-629472D01*
X2333359Y-630305D01*
X2335564D01*
X2337769Y-629472D01*
X2339659Y-628222D01*
X2341234Y-626556D01*
G01X1965560Y-676250D02*
Y-656250D01*
X1962560Y-660250D01*
G01Y-676250D02*
X1968560D01*
G01X1980810Y-667917D02*
X1982560Y-665583D01*
X1984060Y-664250D01*
X1986060Y-663584D01*
X1987810Y-664250D01*
X1989060Y-665583D01*
X1990060Y-667583D01*
X1990310Y-669917D01*
X1990060Y-671917D01*
X1989060Y-673917D01*
X1987560Y-675583D01*
X1985810Y-676250D01*
X1983810Y-675583D01*
X1982060Y-673584D01*
X1981060Y-670583D01*
X1980810Y-667250D01*
X1981310Y-662917D01*
X1982060Y-660583D01*
X1983310Y-658250D01*
X1985060Y-656583D01*
X1986810Y-656250D01*
X1988560Y-656917D01*
X1989810Y-658583D01*
G01X2000060Y-672250D02*
X2001560Y-674584D01*
X2003560Y-675917D01*
X2005810Y-676250D01*
X2007810Y-675917D01*
X2009810Y-674250D01*
X2011060Y-672250D01*
X2011310Y-670250D01*
X2010810Y-667917D01*
X2009060Y-666250D01*
X2007310Y-665583D01*
X2005060D01*
G01X2007310D02*
X2008810Y-664583D01*
X2010060Y-662917D01*
X2010560Y-660917D01*
X2010060Y-658917D01*
X2008810Y-657250D01*
X2006560Y-656250D01*
X2004310Y-656583D01*
X2002060Y-657917D01*
G01X2025560Y-676250D02*
Y-656250D01*
X2022560Y-660250D01*
G01Y-676250D02*
X2028560D01*
G01X2040810Y-667917D02*
X2042560Y-665583D01*
X2044060Y-664250D01*
X2046060Y-663584D01*
X2047810Y-664250D01*
X2049060Y-665583D01*
X2050060Y-667583D01*
X2050310Y-669917D01*
X2050060Y-671917D01*
X2049060Y-673917D01*
X2047560Y-675583D01*
X2045810Y-676250D01*
X2043810Y-675583D01*
X2042060Y-673584D01*
X2041060Y-670583D01*
X2040810Y-667250D01*
X2041310Y-662917D01*
X2042060Y-660583D01*
X2043310Y-658250D01*
X2045060Y-656583D01*
X2046810Y-656250D01*
X2048560Y-656917D01*
X2049810Y-658583D01*
G01X1990878Y626963D02*
X1982217D01*
X1983949Y625664D01*
G01X1990878D02*
Y628262D01*
G01X1989868Y633783D02*
X1990589Y634541D01*
X1990878Y635407D01*
X1990589Y636274D01*
X1989723Y637031D01*
X1988424Y637573D01*
X1987125Y637789D01*
X1985537D01*
X1984238Y637573D01*
X1983083Y637031D01*
X1982506Y636382D01*
X1982217Y635624D01*
X1982506Y634758D01*
X1983083Y634108D01*
X1983949Y633675D01*
X1985104Y633459D01*
X1986114Y633675D01*
X1987125Y634217D01*
X1987702Y634866D01*
X1987847Y635624D01*
X1987558Y636490D01*
X1986836Y637140D01*
X1985537Y637789D01*
G01X1990878Y644285D02*
X1990734Y645043D01*
X1990301Y645909D01*
X1989579Y646450D01*
X1988568Y646667D01*
X1987558Y646450D01*
X1986692Y645801D01*
X1986259Y644826D01*
Y643744D01*
X1985970Y643094D01*
X1985248Y642553D01*
X1984238Y642336D01*
X1983227Y642661D01*
X1982506Y643419D01*
X1982217Y644285D01*
X1982506Y645151D01*
X1983227Y645909D01*
X1984238Y646234D01*
X1985248Y646017D01*
X1985970Y645476D01*
X1986259Y644826D01*
Y643744D01*
X1986692Y642769D01*
X1987558Y642120D01*
X1988568Y641903D01*
X1989579Y642120D01*
X1990301Y642661D01*
X1990734Y643527D01*
X1990878Y644285D01*
G01X1991167Y652946D02*
X1991022Y652729D01*
X1990734D01*
X1990589Y652946D01*
X1990734Y653163D01*
X1991022D01*
X1991167Y652946D01*
G01X1989579Y659225D02*
X1990301Y659875D01*
X1990734Y660633D01*
X1990878Y661607D01*
X1990589Y662581D01*
X1990012Y663339D01*
X1989002Y663881D01*
X1987847Y663989D01*
X1986692Y663772D01*
X1985970Y663231D01*
X1985393Y662473D01*
X1985248Y661715D01*
X1985393Y660957D01*
X1985970Y659983D01*
X1982217Y660308D01*
Y663231D01*
G01Y670268D02*
X1982506Y669402D01*
X1983227Y668752D01*
X1984093Y668319D01*
X1985248Y667994D01*
X1986548Y667886D01*
X1987847Y667994D01*
X1989002Y668319D01*
X1989868Y668752D01*
X1990589Y669402D01*
X1990878Y670268D01*
X1990589Y671134D01*
X1989868Y671784D01*
X1989002Y672217D01*
X1987847Y672542D01*
X1986548Y672650D01*
X1985248Y672542D01*
X1984093Y672217D01*
X1983227Y671784D01*
X1982506Y671134D01*
X1982217Y670268D01*
G01X1991534Y1029729D02*
X1990669Y1030379D01*
X1990235Y1031136D01*
X1990091Y1032003D01*
X1990380Y1033085D01*
X1991101Y1033843D01*
X1991967Y1034060D01*
X1992834Y1033951D01*
X1993555Y1033518D01*
X1994999Y1031353D01*
X1996009Y1030379D01*
X1997453Y1029729D01*
X1998752Y1029512D01*
Y1034060D01*
G01X1990091Y1040447D02*
X1990380Y1039581D01*
X1991101Y1038931D01*
X1991967Y1038498D01*
X1993122Y1038173D01*
X1994422Y1038065D01*
X1995721Y1038173D01*
X1996876Y1038498D01*
X1997742Y1038931D01*
X1998463Y1039581D01*
X1998752Y1040447D01*
X1998463Y1041313D01*
X1997742Y1041963D01*
X1996876Y1042396D01*
X1995721Y1042721D01*
X1994422Y1042829D01*
X1993122Y1042721D01*
X1991967Y1042396D01*
X1991101Y1041963D01*
X1990380Y1041313D01*
X1990091Y1040447D01*
G01Y1049108D02*
X1990380Y1048242D01*
X1991101Y1047592D01*
X1991967Y1047159D01*
X1993122Y1046834D01*
X1994422Y1046726D01*
X1995721Y1046834D01*
X1996876Y1047159D01*
X1997742Y1047592D01*
X1998463Y1048242D01*
X1998752Y1049108D01*
X1998463Y1049974D01*
X1997742Y1050624D01*
X1996876Y1051057D01*
X1995721Y1051382D01*
X1994422Y1051490D01*
X1993122Y1051382D01*
X1991967Y1051057D01*
X1991101Y1050624D01*
X1990380Y1049974D01*
X1990091Y1049108D01*
G01X1999041Y1057769D02*
X1998896Y1057552D01*
X1998608D01*
X1998463Y1057769D01*
X1998608Y1057986D01*
X1998896D01*
X1999041Y1057769D01*
G01X1997453Y1064048D02*
X1998175Y1064698D01*
X1998608Y1065456D01*
X1998752Y1066430D01*
X1998463Y1067404D01*
X1997886Y1068162D01*
X1996876Y1068704D01*
X1995721Y1068812D01*
X1994566Y1068595D01*
X1993844Y1068054D01*
X1993267Y1067296D01*
X1993122Y1066538D01*
X1993267Y1065780D01*
X1993844Y1064806D01*
X1990091Y1065131D01*
Y1068054D01*
G01Y1075091D02*
X1990380Y1074225D01*
X1991101Y1073575D01*
X1991967Y1073142D01*
X1993122Y1072817D01*
X1994422Y1072709D01*
X1995721Y1072817D01*
X1996876Y1073142D01*
X1997742Y1073575D01*
X1998463Y1074225D01*
X1998752Y1075091D01*
X1998463Y1075957D01*
X1997742Y1076607D01*
X1996876Y1077040D01*
X1995721Y1077365D01*
X1994422Y1077473D01*
X1993122Y1077365D01*
X1991967Y1077040D01*
X1991101Y1076607D01*
X1990380Y1075957D01*
X1990091Y1075091D01*
G01X1997020Y1046726D02*
X1998030Y1047376D01*
X1998608Y1048242D01*
X1998752Y1049216D01*
X1998608Y1050082D01*
X1997886Y1050949D01*
X1997020Y1051490D01*
X1996154Y1051598D01*
X1995143Y1051382D01*
X1994422Y1050624D01*
X1994133Y1049866D01*
Y1048891D01*
G01Y1049866D02*
X1993700Y1050515D01*
X1992978Y1051057D01*
X1992112Y1051273D01*
X1991246Y1051057D01*
X1990524Y1050515D01*
X1990091Y1049541D01*
X1990235Y1048567D01*
X1990813Y1047592D01*
G01X1995865Y1056362D02*
Y1059176D01*
G01X2014305Y81972D02*
X2013222Y83416D01*
X2012681Y84859D01*
Y90633D01*
X2013222Y92077D01*
X2014305Y93520D01*
G01X2021342Y84859D02*
Y93520D01*
X2023940D01*
X2024806Y93087D01*
X2025456Y92077D01*
X2025672Y90922D01*
X2025456Y89767D01*
X2024914Y88901D01*
X2023940Y88468D01*
X2021342D01*
G01X2029461Y84859D02*
X2032168Y93520D01*
X2034875Y84859D01*
G01X2033900Y87890D02*
X2030436D01*
G01X2038447Y84859D02*
Y93520D01*
X2040612D01*
X2041479Y93087D01*
X2042128Y92510D01*
X2042670Y91644D01*
X2043103Y90633D01*
X2043211Y89189D01*
X2043103Y87746D01*
X2042670Y86735D01*
X2042128Y85869D01*
X2041479Y85292D01*
X2040612Y84859D01*
X2038447D01*
G01X2050031Y81972D02*
X2051114Y83416D01*
X2051655Y84859D01*
Y90633D01*
X2051114Y92077D01*
X2050031Y93520D01*
G01X2057610Y81972D02*
X2056527Y83416D01*
X2055986Y84859D01*
Y90633D01*
X2056527Y92077D01*
X2057610Y93520D01*
G01X2064322Y84859D02*
Y93520D01*
X2069302Y84859D01*
Y93520D01*
G01X2075473Y84859D02*
X2074607Y85003D01*
X2073849Y85581D01*
X2073199Y86447D01*
X2072766Y87457D01*
X2072550Y88612D01*
Y89767D01*
X2072766Y90922D01*
X2073199Y91932D01*
X2073849Y92798D01*
X2074607Y93376D01*
X2075473Y93520D01*
X2076339Y93376D01*
X2077097Y92798D01*
X2077747Y91932D01*
X2078180Y90922D01*
X2078396Y89767D01*
Y88612D01*
X2078180Y87457D01*
X2077747Y86447D01*
X2077097Y85581D01*
X2076339Y85003D01*
X2075473Y84859D01*
G01X2092795Y93520D02*
Y84859D01*
G01X2090305Y93520D02*
X2095285D01*
G01X2099291Y84859D02*
Y93520D01*
X2101997D01*
X2102863Y93087D01*
X2103405Y92510D01*
X2103621Y91355D01*
X2103405Y90200D01*
X2102755Y89478D01*
X2101997Y89045D01*
X2099291D01*
G01X2101997D02*
X2103621Y84859D01*
G01X2107410D02*
X2110117Y93520D01*
X2112824Y84859D01*
G01X2111849Y87890D02*
X2108385D01*
G01X2121160Y92798D02*
X2120510Y93231D01*
X2119752Y93520D01*
X2118886D01*
X2117912Y93087D01*
X2117154Y92365D01*
X2116613Y91499D01*
X2116179Y90056D01*
X2116071Y88756D01*
X2116288Y87457D01*
X2116613Y86591D01*
X2117262Y85725D01*
X2118020Y85148D01*
X2118778Y84859D01*
X2119536D01*
X2120294Y85148D01*
X2120943Y85581D01*
X2121485Y86158D01*
G01X2129604Y84859D02*
X2125274D01*
Y93520D01*
X2129604D01*
G01X2127872Y89334D02*
X2125274D01*
G01X2142054Y84859D02*
X2144761Y93520D01*
X2147468Y84859D01*
G01X2146493Y87890D02*
X2143029D01*
G01X2153422Y93520D02*
Y84859D01*
G01X2150932Y93520D02*
X2155912D01*
G01X2168037Y84859D02*
X2170744Y93520D01*
X2173451Y84859D01*
G01X2172476Y87890D02*
X2169012D01*
G01X2177240Y93520D02*
Y84859D01*
X2181570D01*
G01X2185901Y93520D02*
Y84859D01*
X2190231D01*
G01X2203223Y93520D02*
Y84859D01*
X2207553D01*
G01X2211342D02*
X2214049Y93520D01*
X2216756Y84859D01*
G01X2215781Y87890D02*
X2212317D01*
G01X2222710Y84859D02*
Y88756D01*
X2220545Y93520D01*
G01X2224875D02*
X2222710Y88756D01*
G01X2233536Y84859D02*
X2229206D01*
Y93520D01*
X2233536D01*
G01X2231804Y89334D02*
X2229206D01*
G01X2237867Y84859D02*
Y93520D01*
X2240573D01*
X2241439Y93087D01*
X2241981Y92510D01*
X2242197Y91355D01*
X2241981Y90200D01*
X2241331Y89478D01*
X2240573Y89045D01*
X2237867D01*
G01X2240573D02*
X2242197Y84859D01*
G01X2246419Y86014D02*
X2247286Y85292D01*
X2248260Y84859D01*
X2249126D01*
X2249992Y85292D01*
X2250642Y86014D01*
X2250967Y87024D01*
X2250750Y88035D01*
X2250209Y88901D01*
X2249234Y89478D01*
X2247935Y89767D01*
X2247177Y90344D01*
X2246852Y91355D01*
X2247069Y92365D01*
X2247610Y93087D01*
X2248368Y93520D01*
X2249126D01*
X2249884Y93231D01*
X2250534Y92510D01*
G01X2268180Y84859D02*
X2263850D01*
Y93520D01*
X2268180D01*
G01X2266448Y89334D02*
X2263850D01*
G01X2272402Y84859D02*
X2276950Y93520D01*
G01X2272402D02*
X2276950Y84859D01*
G01X2285719Y92798D02*
X2285069Y93231D01*
X2284311Y93520D01*
X2283445D01*
X2282471Y93087D01*
X2281713Y92365D01*
X2281172Y91499D01*
X2280738Y90056D01*
X2280630Y88756D01*
X2280847Y87457D01*
X2281172Y86591D01*
X2281821Y85725D01*
X2282579Y85148D01*
X2283337Y84859D01*
X2284095D01*
X2284853Y85148D01*
X2285502Y85581D01*
X2286044Y86158D01*
G01X2294163Y84859D02*
X2289833D01*
Y93520D01*
X2294163D01*
G01X2292431Y89334D02*
X2289833D01*
G01X2298494Y84859D02*
Y93520D01*
X2301092D01*
X2301958Y93087D01*
X2302608Y92077D01*
X2302824Y90922D01*
X2302608Y89767D01*
X2302066Y88901D01*
X2301092Y88468D01*
X2298494D01*
G01X2309320Y93520D02*
Y84859D01*
G01X2306830Y93520D02*
X2311810D01*
G01X2327292Y89189D02*
X2329457D01*
Y86591D01*
X2328807Y85725D01*
X2328049Y85148D01*
X2326967Y84859D01*
X2325884Y85148D01*
X2325126Y85725D01*
X2324477Y86591D01*
X2324043Y87602D01*
X2323827Y88756D01*
Y89767D01*
X2324043Y90633D01*
X2324477Y91644D01*
X2325126Y92510D01*
X2325776Y93087D01*
X2326642Y93520D01*
X2327400D01*
X2328266Y93231D01*
X2328916Y92654D01*
G01X2332813Y84859D02*
Y93520D01*
X2337793Y84859D01*
Y93520D01*
G01X2341582Y84859D02*
Y93520D01*
X2343747D01*
X2344614Y93087D01*
X2345263Y92510D01*
X2345805Y91644D01*
X2346238Y90633D01*
X2346346Y89189D01*
X2346238Y87746D01*
X2345805Y86735D01*
X2345263Y85869D01*
X2344614Y85292D01*
X2343747Y84859D01*
X2341582D01*
G01X2353166Y81972D02*
X2354249Y83416D01*
X2354790Y84859D01*
Y90633D01*
X2354249Y92077D01*
X2353166Y93520D01*
G01X2028936Y325555D02*
X2028071Y326205D01*
X2027637Y326962D01*
X2027493Y327829D01*
X2027782Y328911D01*
X2028503Y329669D01*
X2029369Y329886D01*
X2030236Y329777D01*
X2030957Y329344D01*
X2032401Y327179D01*
X2033411Y326205D01*
X2034855Y325555D01*
X2036154Y325338D01*
Y329886D01*
G01Y336273D02*
X2027493D01*
X2029225Y334974D01*
G01X2036154D02*
Y337572D01*
G01X2027493Y344934D02*
X2027782Y344068D01*
X2028503Y343418D01*
X2029369Y342985D01*
X2030524Y342660D01*
X2031824Y342552D01*
X2033123Y342660D01*
X2034278Y342985D01*
X2035144Y343418D01*
X2035865Y344068D01*
X2036154Y344934D01*
X2035865Y345800D01*
X2035144Y346450D01*
X2034278Y346883D01*
X2033123Y347208D01*
X2031824Y347316D01*
X2030524Y347208D01*
X2029369Y346883D01*
X2028503Y346450D01*
X2027782Y345800D01*
X2027493Y344934D01*
G01X2036443Y353595D02*
X2036298Y353378D01*
X2036010D01*
X2035865Y353595D01*
X2036010Y353812D01*
X2036298D01*
X2036443Y353595D01*
G01X2027493Y362256D02*
X2027782Y361390D01*
X2028503Y360740D01*
X2029369Y360307D01*
X2030524Y359982D01*
X2031824Y359874D01*
X2033123Y359982D01*
X2034278Y360307D01*
X2035144Y360740D01*
X2035865Y361390D01*
X2036154Y362256D01*
X2035865Y363122D01*
X2035144Y363772D01*
X2034278Y364205D01*
X2033123Y364530D01*
X2031824Y364638D01*
X2030524Y364530D01*
X2029369Y364205D01*
X2028503Y363772D01*
X2027782Y363122D01*
X2027493Y362256D01*
G01Y370917D02*
X2027782Y370051D01*
X2028503Y369401D01*
X2029369Y368968D01*
X2030524Y368643D01*
X2031824Y368535D01*
X2033123Y368643D01*
X2034278Y368968D01*
X2035144Y369401D01*
X2035865Y370051D01*
X2036154Y370917D01*
X2035865Y371783D01*
X2035144Y372433D01*
X2034278Y372866D01*
X2033123Y373191D01*
X2031824Y373299D01*
X2030524Y373191D01*
X2029369Y372866D01*
X2028503Y372433D01*
X2027782Y371783D01*
X2027493Y370917D01*
G01X2035888Y1107494D02*
Y1116155D01*
X2031882Y1109948D01*
X2037296D01*
G01X2041843Y1110381D02*
X2044657D01*
G01X2037079Y1107494D02*
Y1113268D01*
G01Y1111824D02*
X2037513Y1112546D01*
X2038162Y1113124D01*
X2039028Y1113268D01*
X2039786Y1113124D01*
X2040436Y1112546D01*
X2040761Y1111536D01*
Y1107494D01*
G01X2023871Y1111103D02*
X2024629Y1112113D01*
X2025278Y1112691D01*
X2026145Y1112979D01*
X2026902Y1112691D01*
X2027444Y1112113D01*
X2027877Y1111247D01*
X2027985Y1110237D01*
X2027877Y1109370D01*
X2027444Y1108504D01*
X2026794Y1107783D01*
X2026036Y1107494D01*
X2025170Y1107783D01*
X2024412Y1108649D01*
X2023979Y1109948D01*
X2023871Y1111391D01*
X2024087Y1113268D01*
X2024412Y1114279D01*
X2024954Y1115289D01*
X2025711Y1116011D01*
X2026469Y1116155D01*
X2027227Y1115866D01*
X2027769Y1115145D01*
G01X2034589Y1107205D02*
X2034372Y1107350D01*
Y1107638D01*
X2034589Y1107783D01*
X2034806Y1107638D01*
Y1107350D01*
X2034589Y1107205D01*
G01X2043250Y1116155D02*
X2042384Y1115866D01*
X2041734Y1115145D01*
X2041301Y1114279D01*
X2040976Y1113124D01*
X2040868Y1111824D01*
X2040976Y1110525D01*
X2041301Y1109370D01*
X2041734Y1108504D01*
X2042384Y1107783D01*
X2043250Y1107494D01*
X2044116Y1107783D01*
X2044766Y1108504D01*
X2045199Y1109370D01*
X2045524Y1110525D01*
X2045632Y1111824D01*
X2045524Y1113124D01*
X2045199Y1114279D01*
X2044766Y1115145D01*
X2044116Y1115866D01*
X2043250Y1116155D01*
G01X2051911D02*
X2051045Y1115866D01*
X2050395Y1115145D01*
X2049962Y1114279D01*
X2049637Y1113124D01*
X2049529Y1111824D01*
X2049637Y1110525D01*
X2049962Y1109370D01*
X2050395Y1108504D01*
X2051045Y1107783D01*
X2051911Y1107494D01*
X2052777Y1107783D01*
X2053427Y1108504D01*
X2053860Y1109370D01*
X2054185Y1110525D01*
X2054293Y1111824D01*
X2054185Y1113124D01*
X2053860Y1114279D01*
X2053427Y1115145D01*
X2052777Y1115866D01*
X2051911Y1116155D01*
G01X2086232Y618635D02*
X2086882Y617913D01*
X2087640Y617480D01*
X2088614Y617336D01*
X2089588Y617625D01*
X2090346Y618202D01*
X2090888Y619212D01*
X2090996Y620367D01*
X2090779Y621522D01*
X2090238Y622244D01*
X2089480Y622821D01*
X2088722Y622966D01*
X2087964Y622821D01*
X2086990Y622244D01*
X2087315Y625997D01*
X2090238D01*
G01X2097275D02*
X2096409Y625708D01*
X2095759Y624987D01*
X2095326Y624121D01*
X2095001Y622966D01*
X2094893Y621666D01*
X2095001Y620367D01*
X2095326Y619212D01*
X2095759Y618346D01*
X2096409Y617625D01*
X2097275Y617336D01*
X2098141Y617625D01*
X2098791Y618346D01*
X2099224Y619212D01*
X2099549Y620367D01*
X2099657Y621666D01*
X2099549Y622966D01*
X2099224Y624121D01*
X2098791Y624987D01*
X2098141Y625708D01*
X2097275Y625997D01*
G01X2105936Y617047D02*
X2105719Y617192D01*
Y617480D01*
X2105936Y617625D01*
X2106153Y617480D01*
Y617192D01*
X2105936Y617047D01*
G01X2112215Y618635D02*
X2112865Y617913D01*
X2113623Y617480D01*
X2114597Y617336D01*
X2115571Y617625D01*
X2116329Y618202D01*
X2116871Y619212D01*
X2116979Y620367D01*
X2116762Y621522D01*
X2116221Y622244D01*
X2115463Y622821D01*
X2114705Y622966D01*
X2113947Y622821D01*
X2112973Y622244D01*
X2113298Y625997D01*
X2116221D01*
G01X2123258D02*
X2122392Y625708D01*
X2121742Y624987D01*
X2121309Y624121D01*
X2120984Y622966D01*
X2120876Y621666D01*
X2120984Y620367D01*
X2121309Y619212D01*
X2121742Y618346D01*
X2122392Y617625D01*
X2123258Y617336D01*
X2124124Y617625D01*
X2124774Y618346D01*
X2125207Y619212D01*
X2125532Y620367D01*
X2125640Y621666D01*
X2125532Y622966D01*
X2125207Y624121D01*
X2124774Y624987D01*
X2124124Y625708D01*
X2123258Y625997D01*
G01X2127551Y918242D02*
Y926903D01*
X2126252Y925171D01*
G01Y918242D02*
X2128850D01*
G01X2134155Y925460D02*
X2134805Y926325D01*
X2135562Y926759D01*
X2136429Y926903D01*
X2137511Y926614D01*
X2138269Y925893D01*
X2138486Y925027D01*
X2138377Y924160D01*
X2137944Y923439D01*
X2135779Y921995D01*
X2134805Y920985D01*
X2134155Y919541D01*
X2133938Y918242D01*
X2138486D01*
G01X2142816Y921851D02*
X2143574Y922861D01*
X2144223Y923439D01*
X2145090Y923727D01*
X2145847Y923439D01*
X2146389Y922861D01*
X2146822Y921995D01*
X2146930Y920985D01*
X2146822Y920118D01*
X2146389Y919252D01*
X2145739Y918531D01*
X2144981Y918242D01*
X2144115Y918531D01*
X2143357Y919397D01*
X2142924Y920696D01*
X2142816Y922139D01*
X2143032Y924016D01*
X2143357Y925027D01*
X2143899Y926037D01*
X2144656Y926759D01*
X2145414Y926903D01*
X2146172Y926614D01*
X2146714Y925893D01*
G01X2153534Y917953D02*
X2153317Y918098D01*
Y918386D01*
X2153534Y918531D01*
X2153751Y918386D01*
Y918098D01*
X2153534Y917953D01*
G01X2160354Y919252D02*
X2161112Y918531D01*
X2161978Y918242D01*
X2162845Y918531D01*
X2163602Y919397D01*
X2164144Y920696D01*
X2164360Y921995D01*
Y923583D01*
X2164144Y924882D01*
X2163602Y926037D01*
X2162953Y926614D01*
X2162195Y926903D01*
X2161329Y926614D01*
X2160679Y926037D01*
X2160246Y925171D01*
X2160030Y924016D01*
X2160246Y923006D01*
X2160788Y921995D01*
X2161437Y921418D01*
X2162195Y921273D01*
X2163061Y921562D01*
X2163711Y922284D01*
X2164360Y923583D01*
G01X2168474Y919974D02*
X2169124Y918964D01*
X2169990Y918386D01*
X2170964Y918242D01*
X2171830Y918386D01*
X2172697Y919108D01*
X2173238Y919974D01*
X2173346Y920840D01*
X2173130Y921851D01*
X2172372Y922572D01*
X2171614Y922861D01*
X2170639D01*
G01X2171614D02*
X2172263Y923294D01*
X2172805Y924016D01*
X2173021Y924882D01*
X2172805Y925748D01*
X2172263Y926470D01*
X2171289Y926903D01*
X2170315Y926759D01*
X2169340Y926181D01*
G01X2127551Y935958D02*
Y944619D01*
X2126252Y942887D01*
G01Y935958D02*
X2128850D01*
G01X2133830Y937690D02*
X2134480Y936680D01*
X2135346Y936102D01*
X2136320Y935958D01*
X2137186Y936102D01*
X2138053Y936824D01*
X2138594Y937690D01*
X2138702Y938556D01*
X2138486Y939567D01*
X2137728Y940288D01*
X2136970Y940577D01*
X2135995D01*
G01X2136970D02*
X2137619Y941010D01*
X2138161Y941732D01*
X2138377Y942598D01*
X2138161Y943464D01*
X2137619Y944186D01*
X2136645Y944619D01*
X2135671Y944475D01*
X2134696Y943897D01*
G01X2144873Y935958D02*
Y944619D01*
X2143574Y942887D01*
G01Y935958D02*
X2146172D01*
G01X2153534Y935669D02*
X2153317Y935814D01*
Y936102D01*
X2153534Y936247D01*
X2153751Y936102D01*
Y935814D01*
X2153534Y935669D01*
G01X2163494Y935958D02*
Y944619D01*
X2159488Y938412D01*
X2164902D01*
G01X2168474Y937690D02*
X2169124Y936680D01*
X2169990Y936102D01*
X2170964Y935958D01*
X2171830Y936102D01*
X2172697Y936824D01*
X2173238Y937690D01*
X2173346Y938556D01*
X2173130Y939567D01*
X2172372Y940288D01*
X2171614Y940577D01*
X2170639D01*
G01X2171614D02*
X2172263Y941010D01*
X2172805Y941732D01*
X2173021Y942598D01*
X2172805Y943464D01*
X2172263Y944186D01*
X2171289Y944619D01*
X2170315Y944475D01*
X2169340Y943897D01*
G01X2127551Y953675D02*
Y962336D01*
X2126252Y960604D01*
G01Y953675D02*
X2128850D01*
G01X2133830Y955407D02*
X2134480Y954397D01*
X2135346Y953819D01*
X2136320Y953675D01*
X2137186Y953819D01*
X2138053Y954541D01*
X2138594Y955407D01*
X2138702Y956273D01*
X2138486Y957284D01*
X2137728Y958005D01*
X2136970Y958294D01*
X2135995D01*
G01X2136970D02*
X2137619Y958727D01*
X2138161Y959449D01*
X2138377Y960315D01*
X2138161Y961181D01*
X2137619Y961903D01*
X2136645Y962336D01*
X2135671Y962192D01*
X2134696Y961614D01*
G01X2142491Y954974D02*
X2143141Y954252D01*
X2143899Y953819D01*
X2144873Y953675D01*
X2145847Y953964D01*
X2146605Y954541D01*
X2147147Y955551D01*
X2147255Y956706D01*
X2147038Y957861D01*
X2146497Y958583D01*
X2145739Y959160D01*
X2144981Y959305D01*
X2144223Y959160D01*
X2143249Y958583D01*
X2143574Y962336D01*
X2146497D01*
G01X2153534Y953386D02*
X2153317Y953531D01*
Y953819D01*
X2153534Y953964D01*
X2153751Y953819D01*
Y953531D01*
X2153534Y953386D01*
G01X2160354Y954685D02*
X2161112Y953964D01*
X2161978Y953675D01*
X2162845Y953964D01*
X2163602Y954830D01*
X2164144Y956129D01*
X2164360Y957428D01*
Y959016D01*
X2164144Y960315D01*
X2163602Y961470D01*
X2162953Y962047D01*
X2162195Y962336D01*
X2161329Y962047D01*
X2160679Y961470D01*
X2160246Y960604D01*
X2160030Y959449D01*
X2160246Y958439D01*
X2160788Y957428D01*
X2161437Y956851D01*
X2162195Y956706D01*
X2163061Y956995D01*
X2163711Y957717D01*
X2164360Y959016D01*
G01X2168474Y955407D02*
X2169124Y954397D01*
X2169990Y953819D01*
X2170964Y953675D01*
X2171830Y953819D01*
X2172697Y954541D01*
X2173238Y955407D01*
X2173346Y956273D01*
X2173130Y957284D01*
X2172372Y958005D01*
X2171614Y958294D01*
X2170639D01*
G01X2171614D02*
X2172263Y958727D01*
X2172805Y959449D01*
X2173021Y960315D01*
X2172805Y961181D01*
X2172263Y961903D01*
X2171289Y962336D01*
X2170315Y962192D01*
X2169340Y961614D01*
G01X2110555Y1022590D02*
X2111422Y1021868D01*
X2112396Y1021435D01*
X2113262D01*
X2114128Y1021868D01*
X2114778Y1022590D01*
X2115103Y1023600D01*
X2114886Y1024611D01*
X2114345Y1025477D01*
X2113370Y1026054D01*
X2112071Y1026343D01*
X2111313Y1026920D01*
X2110988Y1027931D01*
X2111205Y1028941D01*
X2111746Y1029663D01*
X2112504Y1030096D01*
X2113262D01*
X2114020Y1029807D01*
X2114670Y1029086D01*
G01X2123655Y1021435D02*
X2119325D01*
Y1030096D01*
X2123655D01*
G01X2121923Y1025910D02*
X2119325D01*
G01X2132316Y1021435D02*
X2127986D01*
Y1030096D01*
X2132316D01*
G01X2130584Y1025910D02*
X2127986D01*
G01X2145091Y1021435D02*
Y1030096D01*
X2147256D01*
X2148123Y1029663D01*
X2148772Y1029086D01*
X2149314Y1028220D01*
X2149747Y1027209D01*
X2149855Y1025765D01*
X2149747Y1024322D01*
X2149314Y1023311D01*
X2148772Y1022445D01*
X2148123Y1021868D01*
X2147256Y1021435D01*
X2145091D01*
G01X2158299D02*
X2153969D01*
Y1030096D01*
X2158299D01*
G01X2156567Y1025910D02*
X2153969D01*
G01X2164795Y1030096D02*
Y1021435D01*
G01X2162305Y1030096D02*
X2167285D01*
G01X2170749Y1021435D02*
X2173456Y1030096D01*
X2176163Y1021435D01*
G01X2175188Y1024466D02*
X2171724D01*
G01X2180818Y1030096D02*
X2183416D01*
G01X2182117D02*
Y1021435D01*
G01X2180818D02*
X2183416D01*
G01X2188613Y1030096D02*
Y1021435D01*
X2192943D01*
G01X2159771Y-894995D02*
Y-883633D01*
X2158067Y-885905D01*
G01Y-894995D02*
X2161475D01*
G01X2168435Y-885527D02*
X2169288Y-884391D01*
X2170282Y-883822D01*
X2171418Y-883633D01*
X2172838Y-884012D01*
X2173833Y-884959D01*
X2174117Y-886095D01*
X2173975Y-887231D01*
X2173406Y-888178D01*
X2170566Y-890071D01*
X2169288Y-891397D01*
X2168435Y-893291D01*
X2168151Y-894995D01*
X2174117D01*
G01X2181895Y84859D02*
Y90633D01*
G01Y89189D02*
X2182329Y89911D01*
X2182978Y90489D01*
X2183844Y90633D01*
X2184602Y90489D01*
X2185252Y89911D01*
X2185577Y88901D01*
Y84859D01*
G01X2166414D02*
Y93520D01*
X2165115Y91788D01*
G01Y84859D02*
X2167713D01*
G01X2175075D02*
X2175833Y85003D01*
X2176699Y85436D01*
X2177240Y86158D01*
X2177457Y87169D01*
X2177240Y88179D01*
X2176591Y89045D01*
X2175616Y89478D01*
X2174534D01*
X2173884Y89767D01*
X2173343Y90489D01*
X2173126Y91499D01*
X2173451Y92510D01*
X2174209Y93231D01*
X2175075Y93520D01*
X2175941Y93231D01*
X2176699Y92510D01*
X2177024Y91499D01*
X2176807Y90489D01*
X2176266Y89767D01*
X2175616Y89478D01*
X2174534D01*
X2173559Y89045D01*
X2172910Y88179D01*
X2172693Y87169D01*
X2172910Y86158D01*
X2173451Y85436D01*
X2174317Y85003D01*
X2175075Y84859D01*
G01X2183736Y84570D02*
X2183519Y84715D01*
Y85003D01*
X2183736Y85148D01*
X2183953Y85003D01*
Y84715D01*
X2183736Y84570D01*
G01X2192397Y93520D02*
X2191531Y93231D01*
X2190881Y92510D01*
X2190448Y91644D01*
X2190123Y90489D01*
X2190015Y89189D01*
X2190123Y87890D01*
X2190448Y86735D01*
X2190881Y85869D01*
X2191531Y85148D01*
X2192397Y84859D01*
X2193263Y85148D01*
X2193913Y85869D01*
X2194346Y86735D01*
X2194671Y87890D01*
X2194779Y89189D01*
X2194671Y90489D01*
X2194346Y91644D01*
X2193913Y92510D01*
X2193263Y93231D01*
X2192397Y93520D01*
G01X2201058D02*
X2200192Y93231D01*
X2199542Y92510D01*
X2199109Y91644D01*
X2198784Y90489D01*
X2198676Y89189D01*
X2198784Y87890D01*
X2199109Y86735D01*
X2199542Y85869D01*
X2200192Y85148D01*
X2201058Y84859D01*
X2201924Y85148D01*
X2202574Y85869D01*
X2203007Y86735D01*
X2203332Y87890D01*
X2203440Y89189D01*
X2203332Y90489D01*
X2203007Y91644D01*
X2202574Y92510D01*
X2201924Y93231D01*
X2201058Y93520D01*
G01X2159771Y1282761D02*
Y1294123D01*
X2158067Y1291851D01*
G01Y1282761D02*
X2161475D01*
G01X2168435Y1292229D02*
X2169288Y1293365D01*
X2170282Y1293934D01*
X2171418Y1294123D01*
X2172838Y1293744D01*
X2173833Y1292797D01*
X2174117Y1291661D01*
X2173975Y1290525D01*
X2173406Y1289578D01*
X2170566Y1287685D01*
X2169288Y1286359D01*
X2168435Y1284465D01*
X2168151Y1282761D01*
X2174117D01*
G01X2207238Y1026054D02*
X2207671Y1026487D01*
X2207996Y1027209D01*
X2208213Y1028220D01*
X2207996Y1029086D01*
X2207563Y1029663D01*
X2206805Y1030096D01*
X2203882D01*
Y1021435D01*
X2207455D01*
X2208213Y1022012D01*
X2208646Y1022878D01*
X2208862Y1023889D01*
X2208646Y1024899D01*
X2207996Y1025765D01*
X2207238Y1026054D01*
X2203882D01*
G01X2271944Y-704534D02*
Y-724534D01*
G01X2266194Y-704534D02*
X2277694D01*
G01X2287694Y-724534D02*
Y-704534D01*
G01Y-714200D02*
X2288944Y-712534D01*
X2290194Y-711534D01*
X2292194Y-711201D01*
X2293694Y-711534D01*
X2295444Y-712867D01*
X2296194Y-714868D01*
Y-724534D01*
G01X2311944Y-711201D02*
Y-724534D01*
G01Y-705868D02*
X2311444Y-705534D01*
Y-704867D01*
X2311944Y-704534D01*
X2312444Y-704867D01*
Y-705534D01*
X2311944Y-705868D01*
G01X2335944Y-712867D02*
X2334194Y-711534D01*
X2332694Y-711201D01*
X2330694Y-711868D01*
X2329194Y-713201D01*
X2328194Y-715534D01*
X2327944Y-717868D01*
X2328194Y-720201D01*
X2329194Y-722201D01*
X2330694Y-723867D01*
X2332694Y-724534D01*
X2334444Y-723867D01*
X2335944Y-722534D01*
G01X2347694Y-724534D02*
Y-704534D01*
G01X2355694Y-711201D02*
X2347694Y-718867D01*
G01X2350944Y-715867D02*
X2356194Y-724534D01*
G01X2367694D02*
Y-711201D01*
G01Y-714534D02*
X2368694Y-712867D01*
X2370194Y-711534D01*
X2372194Y-711201D01*
X2373944Y-711534D01*
X2375444Y-712867D01*
X2376194Y-715201D01*
Y-724534D01*
G01X2388194Y-715534D02*
X2396194D01*
X2395444Y-713201D01*
X2394194Y-711868D01*
X2392444Y-711201D01*
X2390694Y-711534D01*
X2389194Y-712534D01*
X2388194Y-714868D01*
X2387694Y-716868D01*
Y-718867D01*
X2388194Y-720868D01*
X2389444Y-722868D01*
X2390944Y-724201D01*
X2392694Y-724534D01*
X2394444Y-723867D01*
X2396194Y-721868D01*
G01X2408194Y-722201D02*
X2409444Y-723534D01*
X2411194Y-724534D01*
X2412694D01*
X2414194Y-723867D01*
X2415194Y-722868D01*
X2415694Y-721535D01*
X2415444Y-719534D01*
X2414444Y-718534D01*
X2409944Y-716534D01*
X2408944Y-714200D01*
X2409444Y-712534D01*
X2410444Y-711534D01*
X2411944Y-711201D01*
X2413444Y-711534D01*
X2414944Y-712534D01*
G01X2428194Y-722201D02*
X2429444Y-723534D01*
X2431194Y-724534D01*
X2432694D01*
X2434194Y-723867D01*
X2435194Y-722868D01*
X2435694Y-721535D01*
X2435444Y-719534D01*
X2434444Y-718534D01*
X2429944Y-716534D01*
X2428944Y-714200D01*
X2429444Y-712534D01*
X2430444Y-711534D01*
X2431944Y-711201D01*
X2433444Y-711534D01*
X2434944Y-712534D01*
G01X2315096Y-771146D02*
Y-751146D01*
X2320096D01*
X2322096Y-752146D01*
X2323596Y-753479D01*
X2324846Y-755479D01*
X2325846Y-757813D01*
X2326096Y-761146D01*
X2325846Y-764480D01*
X2324846Y-766813D01*
X2323596Y-768813D01*
X2322096Y-770146D01*
X2320096Y-771146D01*
X2315096D01*
G01X2345096D02*
Y-757813D01*
G01Y-760146D02*
X2344096Y-758813D01*
X2342596Y-758146D01*
X2340846Y-757813D01*
X2339096Y-758480D01*
X2337596Y-759813D01*
X2336596Y-761813D01*
X2336096Y-764480D01*
X2336596Y-767146D01*
X2337596Y-769146D01*
X2339096Y-770479D01*
X2340846Y-771146D01*
X2342596Y-770813D01*
X2344096Y-769813D01*
X2345096Y-768480D01*
G01X2360596Y-751146D02*
Y-771146D01*
G01X2357096Y-757813D02*
X2364096D01*
G01X2376846Y-762146D02*
X2384846D01*
X2384096Y-759813D01*
X2382846Y-758480D01*
X2381096Y-757813D01*
X2379346Y-758146D01*
X2377846Y-759146D01*
X2376846Y-761480D01*
X2376346Y-763480D01*
Y-765479D01*
X2376846Y-767480D01*
X2378096Y-769480D01*
X2379596Y-770813D01*
X2381346Y-771146D01*
X2383096Y-770479D01*
X2384846Y-768480D01*
G01X2379441Y-894995D02*
Y-883633D01*
X2377737Y-885905D01*
G01Y-894995D02*
X2381145D01*
G01X2387679Y-892723D02*
X2388531Y-894048D01*
X2389668Y-894806D01*
X2390946Y-894995D01*
X2392082Y-894806D01*
X2393219Y-893859D01*
X2393929Y-892723D01*
X2394071Y-891586D01*
X2393787Y-890261D01*
X2392792Y-889314D01*
X2391798Y-888935D01*
X2390520D01*
G01X2391798D02*
X2392650Y-888367D01*
X2393361Y-887421D01*
X2393645Y-886284D01*
X2393361Y-885148D01*
X2392650Y-884201D01*
X2391372Y-883633D01*
X2390094Y-883822D01*
X2388816Y-884580D01*
G01X2379441Y1282761D02*
Y1294123D01*
X2377737Y1291851D01*
G01Y1282761D02*
X2381145D01*
G01X2387679Y1285033D02*
X2388531Y1283708D01*
X2389668Y1282950D01*
X2390946Y1282761D01*
X2392082Y1282950D01*
X2393219Y1283897D01*
X2393929Y1285033D01*
X2394071Y1286170D01*
X2393787Y1287495D01*
X2392792Y1288442D01*
X2391798Y1288821D01*
X2390520D01*
G01X2391798D02*
X2392650Y1289389D01*
X2393361Y1290335D01*
X2393645Y1291472D01*
X2393361Y1292608D01*
X2392650Y1293555D01*
X2391372Y1294123D01*
X2390094Y1293934D01*
X2388816Y1293176D01*
G01X2463599Y-752635D02*
X2465099Y-750636D01*
X2466849Y-749635D01*
X2468849Y-749302D01*
X2471349Y-749969D01*
X2473099Y-751635D01*
X2473599Y-753635D01*
X2473349Y-755636D01*
X2472349Y-757302D01*
X2467349Y-760635D01*
X2465099Y-762969D01*
X2463599Y-766303D01*
X2463099Y-769302D01*
X2473599D01*
G01X2488349Y-749302D02*
X2486349Y-749969D01*
X2484849Y-751635D01*
X2483849Y-753635D01*
X2483099Y-756302D01*
X2482849Y-759302D01*
X2483099Y-762302D01*
X2483849Y-764969D01*
X2484849Y-766969D01*
X2486349Y-768635D01*
X2488349Y-769302D01*
X2490349Y-768635D01*
X2491849Y-766969D01*
X2492849Y-764969D01*
X2493599Y-762302D01*
X2493849Y-759302D01*
X2493599Y-756302D01*
X2492849Y-753635D01*
X2491849Y-751635D01*
X2490349Y-749969D01*
X2488349Y-749302D01*
G01X2508349Y-769302D02*
Y-749302D01*
X2505349Y-753302D01*
G01Y-769302D02*
X2511349D01*
G01X2527849D02*
X2528349Y-764969D01*
X2529099Y-761302D01*
X2530099Y-757969D01*
X2531349Y-754302D01*
X2533349Y-749302D01*
X2523349D01*
G01X2545099Y-762636D02*
X2551599D01*
G01X2568349Y-749302D02*
X2566349Y-749969D01*
X2564849Y-751635D01*
X2563849Y-753635D01*
X2563099Y-756302D01*
X2562849Y-759302D01*
X2563099Y-762302D01*
X2563849Y-764969D01*
X2564849Y-766969D01*
X2566349Y-768635D01*
X2568349Y-769302D01*
X2570349Y-768635D01*
X2571849Y-766969D01*
X2572849Y-764969D01*
X2573599Y-762302D01*
X2573849Y-759302D01*
X2573599Y-756302D01*
X2572849Y-753635D01*
X2571849Y-751635D01*
X2570349Y-749969D01*
X2568349Y-749302D01*
G01X2583599Y-760969D02*
X2585349Y-758635D01*
X2586849Y-757302D01*
X2588849Y-756636D01*
X2590599Y-757302D01*
X2591849Y-758635D01*
X2592849Y-760635D01*
X2593099Y-762969D01*
X2592849Y-764969D01*
X2591849Y-766969D01*
X2590349Y-768635D01*
X2588599Y-769302D01*
X2586599Y-768635D01*
X2584849Y-766636D01*
X2583849Y-763635D01*
X2583599Y-760302D01*
X2584099Y-755969D01*
X2584849Y-753635D01*
X2586099Y-751302D01*
X2587849Y-749635D01*
X2589599Y-749302D01*
X2591349Y-749969D01*
X2592599Y-751635D01*
G01X2605099Y-762636D02*
X2611599D01*
G01X2628349Y-749302D02*
X2626349Y-749969D01*
X2624849Y-751635D01*
X2623849Y-753635D01*
X2623099Y-756302D01*
X2622849Y-759302D01*
X2623099Y-762302D01*
X2623849Y-764969D01*
X2624849Y-766969D01*
X2626349Y-768635D01*
X2628349Y-769302D01*
X2630349Y-768635D01*
X2631849Y-766969D01*
X2632849Y-764969D01*
X2633599Y-762302D01*
X2633849Y-759302D01*
X2633599Y-756302D01*
X2632849Y-753635D01*
X2631849Y-751635D01*
X2630349Y-749969D01*
X2628349Y-749302D01*
G01X2643599Y-760969D02*
X2645349Y-758635D01*
X2646849Y-757302D01*
X2648849Y-756636D01*
X2650599Y-757302D01*
X2651849Y-758635D01*
X2652849Y-760635D01*
X2653099Y-762969D01*
X2652849Y-764969D01*
X2651849Y-766969D01*
X2650349Y-768635D01*
X2648599Y-769302D01*
X2646599Y-768635D01*
X2644849Y-766636D01*
X2643849Y-763635D01*
X2643599Y-760302D01*
X2644099Y-755969D01*
X2644849Y-753635D01*
X2646099Y-751302D01*
X2647849Y-749635D01*
X2649599Y-749302D01*
X2651349Y-749969D01*
X2652599Y-751635D01*
G01X2495908Y-720464D02*
Y-700464D01*
X2492908Y-704464D01*
G01Y-720464D02*
X2498908D01*
G01X2515908Y-721131D02*
X2515408Y-720797D01*
Y-720131D01*
X2515908Y-719797D01*
X2516408Y-720131D01*
Y-720797D01*
X2515908Y-721131D01*
G01X2531158Y-712131D02*
X2532908Y-709797D01*
X2534408Y-708464D01*
X2536408Y-707798D01*
X2538158Y-708464D01*
X2539408Y-709797D01*
X2540408Y-711797D01*
X2540658Y-714131D01*
X2540408Y-716131D01*
X2539408Y-718131D01*
X2537908Y-719797D01*
X2536158Y-720464D01*
X2534158Y-719797D01*
X2532408Y-717798D01*
X2531408Y-714797D01*
X2531158Y-711464D01*
X2531658Y-707131D01*
X2532408Y-704797D01*
X2533658Y-702464D01*
X2535408Y-700797D01*
X2537158Y-700464D01*
X2538908Y-701131D01*
X2540158Y-702797D01*
G01X2548408Y-720464D02*
Y-707131D01*
G01Y-710798D02*
X2549158Y-709131D01*
X2550408Y-707798D01*
X2552158Y-707131D01*
X2553908Y-707798D01*
X2555158Y-709131D01*
X2555908Y-710798D01*
Y-720464D01*
G01Y-710798D02*
X2556658Y-709131D01*
X2557908Y-707798D01*
X2559658Y-707131D01*
X2561408Y-707798D01*
X2562658Y-709131D01*
X2563408Y-711131D01*
Y-720464D01*
G01X2568408D02*
Y-707131D01*
G01Y-710798D02*
X2569158Y-709131D01*
X2570408Y-707798D01*
X2572158Y-707131D01*
X2573908Y-707798D01*
X2575158Y-709131D01*
X2575908Y-710798D01*
Y-720464D01*
G01Y-710798D02*
X2576658Y-709131D01*
X2577908Y-707798D01*
X2579658Y-707131D01*
X2581408Y-707798D01*
X2582658Y-709131D01*
X2583408Y-711131D01*
Y-720464D01*
G01X2599110Y-894995D02*
Y-883633D01*
X2597406Y-885905D01*
G01Y-894995D02*
X2600814D01*
G01X2612177D02*
Y-883633D01*
X2606922Y-891776D01*
X2614024D01*
G01X2599110Y1282761D02*
Y1294123D01*
X2597406Y1291851D01*
G01Y1282761D02*
X2600814D01*
G01X2612177D02*
Y1294123D01*
X2606922Y1285980D01*
X2614024D01*
G01X2724851Y-775313D02*
X2725562Y-776449D01*
X2726414Y-777206D01*
X2727408Y-777585D01*
X2728544Y-777206D01*
X2729396Y-776449D01*
X2730249Y-775313D01*
X2730533Y-773798D01*
Y-766223D01*
G01X2725988Y-550341D02*
X2729396D01*
G01X2727692D02*
Y-561703D01*
G01X2725988D02*
X2729396D01*
G01X2724709Y-346011D02*
Y-334649D01*
G01X2730675D02*
Y-346011D01*
G01Y-340330D02*
X2724709D01*
G01X2728544Y-124448D02*
X2731385D01*
Y-127857D01*
X2730533Y-128993D01*
X2729538Y-129750D01*
X2728118Y-130129D01*
X2726698Y-129750D01*
X2725704Y-128993D01*
X2724851Y-127857D01*
X2724283Y-126531D01*
X2723999Y-125016D01*
Y-123691D01*
X2724283Y-122555D01*
X2724851Y-121229D01*
X2725704Y-120093D01*
X2726556Y-119335D01*
X2727692Y-118767D01*
X2728686D01*
X2729822Y-119146D01*
X2730675Y-119903D01*
G01X2724614Y85943D02*
Y97305D01*
X2730012D01*
G01X2728023Y91813D02*
X2724614D01*
G01X2730533Y302014D02*
X2724851D01*
Y313376D01*
X2730533D01*
G01X2728260Y307884D02*
X2724851D01*
G01X2724567Y517706D02*
Y529068D01*
X2727408D01*
X2728544Y528500D01*
X2729396Y527742D01*
X2730107Y526606D01*
X2730675Y525280D01*
X2730817Y523387D01*
X2730675Y521493D01*
X2730107Y520168D01*
X2729396Y519031D01*
X2728544Y518274D01*
X2727408Y517706D01*
X2724567D01*
G01X2730817Y744193D02*
X2729964Y744761D01*
X2728970Y745140D01*
X2727834D01*
X2726556Y744572D01*
X2725562Y743625D01*
X2724851Y742489D01*
X2724283Y740595D01*
X2724141Y738891D01*
X2724425Y737187D01*
X2724851Y736050D01*
X2725704Y734914D01*
X2726698Y734157D01*
X2727692Y733778D01*
X2728686D01*
X2729680Y734157D01*
X2730533Y734725D01*
X2731243Y735482D01*
G01X2728828Y955530D02*
X2729396Y956098D01*
X2729822Y957044D01*
X2730107Y958370D01*
X2729822Y959506D01*
X2729254Y960264D01*
X2728260Y960832D01*
X2724425D01*
Y949470D01*
X2729112D01*
X2730107Y950227D01*
X2730675Y951364D01*
X2730959Y952689D01*
X2730675Y954015D01*
X2729822Y955151D01*
X2728828Y955530D01*
X2724425D01*
G01X2724141Y1165352D02*
X2727692Y1176714D01*
X2731243Y1165352D01*
G01X2729964Y1169329D02*
X2725419D01*
G01X-387730Y-898782D02*
Y1297911D01*
G01X2736876Y-898782D02*
X-387730D01*
G01X-368793Y-879845D02*
Y1278974D01*
G01X2717939Y-879845D02*
X-368793D01*
G01X-387730Y-663963D02*
X-368793D01*
G01X-387730Y-448081D02*
X-368793D01*
G01X-387730D02*
X-368793D01*
G01X-387730Y-232199D02*
X-368793D01*
G01X-387730D02*
X-368793D01*
G01X-387730Y-16317D02*
X-368793D01*
G01X-387730D02*
X-368793D01*
G01X-387730Y199565D02*
X-368793D01*
G01X-387730D02*
X-368793D01*
G01X-387730D02*
X-368793D01*
G01X-387730Y415446D02*
X-368793D01*
G01X-387730D02*
X-368793D01*
G01X-387730Y631328D02*
X-368793D01*
G01X-387730D02*
X-368793D01*
G01X-387730Y847210D02*
X-368793D01*
G01X-387730D02*
X-368793D01*
G01X-387730Y1063092D02*
X-368793D01*
G01Y1278974D02*
X2717939D01*
G01X-387730Y1297911D02*
X2736876D01*
G01X-143442Y-879845D02*
Y-898782D01*
G01Y1297911D02*
Y1278974D01*
G01X11063Y-102362D02*
X-48725D01*
G01X3937Y0D02*
X-48725D01*
G01X3937Y570866D02*
X-48725D01*
G01X20103Y-86244D02*
G03I-4291J0D01*
G01X0Y-87362D02*
G03X15000Y-102362I15000J0D01*
G01X0Y-11811D02*
Y-87362D01*
G01X3937Y-7874D02*
G03X0Y-11811I0J-3937D01*
G01X15748Y-7874D02*
X3937D01*
G01X0Y7874D02*
G03X7874Y0I7874J0D01*
G01X818897D02*
X7874D01*
G01X0Y7874D02*
Y562992D01*
G01Y566929D02*
Y617965D01*
G01X7874Y570866D02*
G03X0Y562992I0J-7874D01*
G01X7874Y570866D02*
X326781D01*
G01X76227Y-879845D02*
Y-898782D01*
G01X312004Y-102362D02*
X15000D01*
G01X287400Y-7874D02*
X46456D01*
G01Y0D02*
G03Y-7874I0J-3937D01*
G01X15748D02*
G03Y0I0J3937D01*
G01X19685Y486755D02*
G03Y548127I17716J30686D01*
G01X40452Y499724D02*
G03I-3051J0D01*
G01X41535Y535157D02*
G03I-4134J0D01*
G01X44685Y517441D02*
G03I-7284J0D01*
G01X19685Y548127D02*
Y486755D01*
G01X76227Y1297911D02*
Y1278974D01*
G01X128968Y-28740D02*
X126409Y-31299D01*
G01X127984Y-23425D02*
X128968Y-22441D01*
G01X106472D02*
X105488Y-23425D01*
G01X108547Y-13977D02*
X106972Y-15551D01*
G01X128968Y-12992D02*
X102928D01*
G01X108547Y-13977D02*
X123586D01*
G01X128968Y-15551D02*
X102928D01*
G01X125425Y-16536D02*
X106472D01*
G01X105488Y-23425D02*
X103913D01*
G01X127984D02*
X126409D01*
G01X106472Y-24410D02*
X102928D01*
G01X128968D02*
X125425D01*
G01X128968Y-28740D02*
X102928D01*
G01X126409Y-31299D02*
X105488D01*
G01X138484Y62697D02*
Y-48032D01*
G01X128968Y-28740D02*
Y62697D01*
G01X127984Y-15551D02*
Y-23425D01*
G01X125425Y-24410D02*
Y-15551D01*
G01X123586Y-13977D02*
Y57775D01*
G01X122956Y-6890D02*
Y-31299D01*
G01X122678Y-6890D02*
Y-31299D01*
G01X122111Y-6299D02*
Y-31299D01*
G01X117247D02*
Y-6299D01*
G01X114885Y-31299D02*
Y-6299D01*
G01X110021D02*
Y-31299D01*
G01X109455Y-6890D02*
Y-31299D01*
G01X109176Y-6890D02*
Y-31299D01*
G01X108547Y-13977D02*
Y57775D01*
G01X165452Y-48032D02*
X138484D01*
G01X106472Y-15551D02*
Y-24410D01*
G01X103913Y-15551D02*
Y-23425D01*
G01X102928Y62697D02*
Y-28740D01*
G01X123586Y-13977D02*
X125161Y-15551D01*
G01X126409Y-23425D02*
X125425Y-22441D01*
G01X102928D02*
X103913Y-23425D01*
G01X105488Y-31299D02*
X102928Y-28740D01*
G01X109326Y-257D02*
X109570Y-296D01*
G01X109107Y-145D02*
X109326Y-257D01*
G01X108933Y29D02*
X109107Y-145D01*
G01X108821Y248D02*
X108933Y29D01*
G01X108783Y491D02*
X108821Y248D01*
G01X110211Y55021D02*
X110405Y48917D01*
G01X109165Y592D02*
X109126Y835D01*
G01X109277Y372D02*
X109165Y592D01*
G01X109451Y198D02*
X109277Y372D01*
G01X109670Y87D02*
X109451Y198D01*
G01X109913Y48D02*
X109670Y87D01*
G01X122463Y31212D02*
X122219Y31251D01*
G01X122682Y31100D02*
X122463Y31212D01*
G01X122856Y30927D02*
X122682Y31100D01*
G01X122967Y30708D02*
X122856Y30927D01*
G01X123006Y30464D02*
X122967Y30708D01*
G01X109326Y23759D02*
X109570Y23720D01*
G01X109107Y23870D02*
X109326Y23759D01*
G01X108933Y24044D02*
X109107Y23870D01*
G01X108821Y24264D02*
X108933Y24044D01*
G01X108783Y24507D02*
X108821Y24264D01*
G01X122806Y5571D02*
X122563Y5610D01*
G01X123025Y5460D02*
X122806Y5571D01*
G01X123199Y5286D02*
X123025Y5460D01*
G01X123311Y5066D02*
X123199Y5286D01*
G01X123350Y4823D02*
X123311Y5066D01*
G01X122806Y31556D02*
X122563Y31594D01*
G01X123025Y31444D02*
X122806Y31556D01*
G01X123199Y31270D02*
X123025Y31444D01*
G01X123311Y31051D02*
X123199Y31270D01*
G01X123350Y30807D02*
X123311Y31051D01*
G01X115125Y33526D02*
X115137Y33105D01*
G01X115119Y33954D02*
X115125Y33526D01*
G01X115116Y34388D02*
X115119Y33954D01*
G01X117007Y44624D02*
X116996Y45044D01*
G01X117014Y44195D02*
X117007Y44624D01*
G01X117016Y43762D02*
X117014Y44195D01*
G01X115125Y44624D02*
X115137Y45044D01*
G01X115119Y44196D02*
X115125Y44624D01*
G01X115116Y43762D02*
X115119Y44196D01*
G01X110086Y38765D02*
X110097Y38145D01*
G01X110086Y39385D02*
Y38765D01*
G01X110097Y40004D02*
X110086Y39385D01*
G01X122046D02*
X122035Y40004D01*
G01X122046Y38765D02*
Y39385D01*
G01X122035Y38145D02*
X122046Y38765D01*
G01X117014Y33954D02*
X117016Y34388D01*
G01X117007Y33526D02*
X117014Y33954D01*
G01X116996Y33105D02*
X117007Y33526D01*
G01X122667Y-6773D02*
X122678Y-6890D01*
G01X122634Y-6663D02*
X122667Y-6773D01*
G01X122582Y-6562D02*
X122634Y-6663D01*
G01X122512Y-6472D02*
X122582Y-6562D01*
G01X122425Y-6398D02*
X122512Y-6472D01*
G01X122327Y-6344D02*
X122425Y-6398D01*
G01X122221Y-6311D02*
X122327Y-6344D01*
G01X122111Y-6299D02*
X122221Y-6311D01*
G01X122967Y4723D02*
X123006Y4479D01*
G01X122856Y4942D02*
X122967Y4723D01*
G01X122682Y5116D02*
X122856Y4942D01*
G01X122462Y5228D02*
X122682Y5116D01*
G01X122219Y5266D02*
X122462Y5228D01*
G01X109165Y24608D02*
X109126Y24851D01*
G01X109277Y24388D02*
X109165Y24608D01*
G01X109451Y24214D02*
X109277Y24388D01*
G01X109670Y24102D02*
X109451Y24214D01*
G01X109913Y24064D02*
X109670Y24102D01*
G01Y31212D02*
X109913Y31251D01*
G01X109451Y31100D02*
X109670Y31212D01*
G01X109277Y30926D02*
X109451Y31100D01*
G01X109165Y30707D02*
X109277Y30926D01*
G01X109126Y30464D02*
X109165Y30707D01*
G01X122462Y24102D02*
X122219Y24064D01*
G01X122682Y24214D02*
X122462Y24102D01*
G01X122856Y24388D02*
X122682Y24214D01*
G01X122967Y24608D02*
X122856Y24388D01*
G01X123006Y24851D02*
X122967Y24608D01*
G01X122462Y87D02*
X122219Y48D01*
G01X122682Y198D02*
X122462Y87D01*
G01X122856Y372D02*
X122682Y198D01*
G01X122967Y592D02*
X122856Y372D01*
G01X123006Y835D02*
X122967Y592D01*
G01X109165Y4723D02*
X109126Y4479D01*
G01X109277Y4942D02*
X109165Y4723D01*
G01X109450Y5116D02*
X109277Y4942D01*
G01X109669Y5228D02*
X109450Y5116D01*
G01X109913Y5266D02*
X109669Y5228D01*
G01X123311Y248D02*
X123350Y491D01*
G01X123199Y29D02*
X123311Y248D01*
G01X123025Y-145D02*
X123199Y29D01*
G01X122806Y-257D02*
X123025Y-145D01*
G01X122563Y-296D02*
X122806Y-257D01*
G01X108821Y5066D02*
X108783Y4823D01*
G01X108933Y5286D02*
X108821Y5066D01*
G01X109107Y5460D02*
X108933Y5286D01*
G01X109326Y5571D02*
X109107Y5460D01*
G01X109570Y5610D02*
X109326Y5571D01*
G01X109466Y-6773D02*
X109455Y-6890D01*
G01X109498Y-6663D02*
X109466Y-6773D01*
G01X109550Y-6562D02*
X109498Y-6663D01*
G01X109621Y-6472D02*
X109550Y-6562D01*
G01X109708Y-6398D02*
X109621Y-6472D01*
G01X109805Y-6344D02*
X109708Y-6398D01*
G01X109911Y-6311D02*
X109805Y-6344D01*
G01X110021Y-6299D02*
X109911Y-6311D01*
G01X110945Y40022D02*
X111379Y40025D01*
G01X110516Y40015D02*
X110945Y40022D01*
G01X110097Y40004D02*
X110516Y40015D01*
G01X115756Y45055D02*
X116066Y45056D01*
G01X115446Y45051D02*
X115756Y45055D01*
G01X115137Y45044D02*
X115446Y45051D01*
G01X121615Y38134D02*
X122035Y38145D01*
G01X121186Y38127D02*
X121615Y38134D01*
G01X120753Y38125D02*
X121186Y38127D01*
G01X116686Y33099D02*
X116996Y33105D01*
G01X116376Y33094D02*
X116686Y33099D01*
G01X116066Y33093D02*
X116376Y33094D01*
G01X115756D02*
X116066Y33093D01*
G01X115446Y33098D02*
X115756Y33094D01*
G01X115137Y33105D02*
X115446Y33098D01*
G01X116376Y45055D02*
X116066Y45056D01*
G01X116686Y45051D02*
X116376Y45055D01*
G01X116996Y45044D02*
X116686Y45051D01*
G01X110946Y38127D02*
X111379Y38125D01*
G01X110517Y38134D02*
X110946Y38127D01*
G01X110097Y38145D02*
X110517Y38134D01*
G01X121186Y40022D02*
X120753Y40025D01*
G01X121615Y40015D02*
X121186Y40022D01*
G01X122035Y40004D02*
X121615Y40015D01*
G01X123311Y24264D02*
X123350Y24507D01*
G01X123199Y24045D02*
X123311Y24264D01*
G01X123025Y23870D02*
X123199Y24045D01*
G01X122806Y23759D02*
X123025Y23870D01*
G01X122563Y23720D02*
X122806Y23759D01*
G01X108821Y31051D02*
X108783Y30807D01*
G01X108933Y31270D02*
X108821Y31051D01*
G01X109107Y31444D02*
X108933Y31270D01*
G01X109326Y31556D02*
X109107Y31444D01*
G01X109570Y31594D02*
X109326Y31556D01*
G01X102316Y42608D02*
G03X103891Y41033I1575J0D01*
G01X135633Y46771D02*
G03I-1968J0D01*
G01X128547D02*
G03I-1969J0D01*
G01X121460D02*
G03I-1969J0D01*
G01X114373D02*
G03I-1968J0D01*
G01X107287D02*
G03I-1969J0D01*
G01X106893Y39478D02*
G03X105318Y41053I-1575J0D01*
G01X113980Y39478D02*
G03X110830I-1575J0D01*
G01X121066D02*
G03X117917I-1575J0D01*
G01X128153D02*
G03X125003I-1575J0D01*
G01X135239D02*
G03X132090I-1575J0D01*
G01X119698Y39075D02*
G03I-3632J0D01*
G01X119757D02*
G03I-3691J0D01*
G01X120735Y40021D02*
G03X117013Y43743I-4669J-947D01*
G01Y34406D02*
G03X120735Y38128I-947J4669D01*
G01X111397D02*
G03X115120Y34406I4669J947D01*
G01Y43743D02*
G03X111397Y40021I946J-4669D01*
G01X121082Y39055D02*
G03I-5019J0D01*
G01X121332Y39075D02*
G03I-5266J0D01*
G01X125049D02*
G03I-8983J0D01*
G01X120927Y14427D02*
G03Y14706I-139J139D01*
G01X115927Y9706D02*
G03X116205I139J139D01*
G01X111205Y14706D02*
G03Y14427I140J-140D01*
G01X116205Y19427D02*
G03X115927I-139J-139D01*
G01X110788Y15123D02*
G03Y14010I557J-557D01*
G01X115509Y9288D02*
G03X116623I557J557D01*
G01X121345Y14010D02*
G03Y15123I-557J556D01*
G01X116623Y19845D02*
G03X115509I-557J-557D01*
G01X120807Y14567D02*
G03I-4744J0D01*
G01X123940D02*
G03I-7874J0D01*
G01X122956Y-6890D02*
G03X122365Y-6299I-591J0D01*
G01X109767D02*
G03X109176Y-6890I0J-591D01*
G01X120266Y38125D02*
X118206Y36935D01*
G01X117136Y38005D02*
X118166Y38600D01*
G01X114996Y40144D02*
X113966Y39550D01*
G01X111866Y40025D02*
X113927Y41214D01*
G01X123350Y4823D02*
X123006Y4479D01*
G01X122219Y5266D02*
X122563Y5610D01*
G01X109913Y48D02*
X109570Y-296D01*
G01X108783Y491D02*
X109126Y835D01*
G01X121345Y14010D02*
X116623Y9288D01*
G01X120927Y14427D02*
X116205Y9706D01*
G01X120927Y14706D02*
X121345Y15123D01*
G01X115927Y9706D02*
X115509Y9288D01*
G01X116066Y12992D02*
X117641Y14567D01*
G01X116066Y16141D02*
X114491Y14567D01*
G01X111205Y14427D02*
X110788Y14010D01*
G01X116623Y19845D02*
X116205Y19427D01*
G01X115927D02*
X111205Y14706D01*
G01X110788Y15123D02*
X115509Y19845D01*
G01X123350Y30807D02*
X123006Y30464D01*
G01X122219Y31251D02*
X122563Y31594D01*
G01X109913Y24064D02*
X109570Y23720D01*
G01X108783Y24507D02*
X109126Y24851D01*
G01X113927Y36935D02*
X118206Y41214D01*
G01X139117Y25611D02*
X137799Y23327D01*
G01X132100Y25730D02*
X130712Y23327D01*
G01X125013Y25730D02*
X123625Y23327D01*
G01X111866Y38125D02*
X120266Y40025D01*
G01X117926Y25730D02*
X116539Y23327D01*
G01X125830Y39921D02*
X125043Y38557D01*
G01X118206Y36935D02*
X117016Y34875D01*
G01X110840Y25730D02*
X109452Y23327D01*
G01X118743Y39921D02*
X117956Y38557D01*
G01X117136Y38005D02*
X116541Y36975D01*
G01X114996Y40144D02*
X115591Y41175D01*
G01X113927Y41214D02*
X115116Y43275D01*
G01X111657Y39921D02*
X110869Y38557D01*
G01X104570Y39921D02*
X103783Y38557D01*
G01X110097Y38145D02*
X122035Y40004D01*
G01X109275Y48917D02*
X122858D01*
G01X128968Y45039D02*
X102928D01*
G01X165452Y44837D02*
X138484D01*
G01X128968Y42516D02*
X102928D01*
G01X138484Y42450D02*
X165452D01*
G01X116541Y42125D02*
X115591D01*
G01X105318Y41043D02*
X103891D01*
G01X120266Y40025D02*
X120753D01*
G01X111866D02*
X111379D01*
G01X106066Y39921D02*
X104570D01*
G01X113153D02*
X111657D01*
G01X120239D02*
X118743D01*
G01X127326D02*
X125830D01*
G01X113966Y39550D02*
X113016D01*
G01X119116D02*
X118166D01*
G01Y38600D02*
X119116D01*
G01X113016D02*
X113966D01*
G01X111866Y38125D02*
X111379D01*
G01X120266D02*
X120753D01*
G01X115591Y36025D02*
X116541D01*
G01X122563Y31594D02*
X109570D01*
G01X122219Y31251D02*
X109913D01*
G01X135436Y25372D02*
X138980D01*
G01X121263D02*
X124806D01*
G01X114176D02*
X117720D01*
G01X107090D02*
X110633D01*
G01X131893D02*
X128350D01*
G01X110097Y40004D02*
X122035Y38145D01*
G01X122219Y24064D02*
X109913D01*
G01X109570Y23720D02*
X122563D01*
G01X109452Y23327D02*
X108271D01*
G01X116539D02*
X115358D01*
G01X123625D02*
X122444D01*
G01X130712D02*
X129531D01*
G01X137799D02*
X136617D01*
G01X139117Y22199D02*
X138484D01*
G01X103783Y21614D02*
X102928D01*
G01X110869D02*
X106854D01*
G01X117956D02*
X113940D01*
G01X125043D02*
X121027D01*
G01X128968D02*
X128113D01*
G01X114491Y14567D02*
X111148D01*
G01X120985D02*
X117641D01*
G01X128495Y10531D02*
X128968D01*
G01X122563Y5610D02*
X109570D01*
G01X122219Y5266D02*
X109913D01*
G01X122219Y48D02*
X109913D01*
G01X109570Y-296D02*
X122563D01*
G01X128968Y-1181D02*
X102928D01*
G01X165452D02*
X138484D01*
G01X117247Y-6299D02*
X122365D01*
G01X114885D02*
X109784D01*
G01X117247Y-6890D02*
X122937D01*
G01X109196D02*
X114885D01*
G01X117016Y43275D02*
X115116Y34875D01*
G01X116996Y45044D02*
X115137Y33105D01*
G01X111866Y40025D02*
X120266Y38125D01*
G01X123339Y62697D02*
X122858Y48917D01*
G01X122552Y62697D02*
X122071Y48917D01*
G01X121728D02*
X122011Y57775D01*
G01X135230Y25730D02*
Y39478D01*
G01X132100D02*
Y25730D01*
G01X128495Y57775D02*
Y10531D01*
G01X128143Y25730D02*
Y39478D01*
G01X128113Y38557D02*
Y21614D01*
G01X125043Y38557D02*
Y21614D01*
G01X125013Y39478D02*
Y25730D01*
G01X123350Y24507D02*
Y30807D01*
G01Y491D02*
Y4823D01*
G01X123006Y4479D02*
Y835D01*
G01Y30464D02*
Y24851D01*
G01X121056Y25730D02*
Y39478D01*
G01X121027Y38557D02*
Y21614D01*
G01X119116Y38600D02*
Y39550D01*
G01X117956Y38557D02*
Y21614D01*
G01X117926Y39478D02*
Y25730D01*
G01X117016Y43275D02*
Y43762D01*
G01Y34875D02*
Y34388D01*
G01X116541Y41175D02*
Y42125D01*
G01Y36025D02*
Y36975D01*
G01X116066Y16141D02*
Y19485D01*
G01Y12992D02*
Y9648D01*
G01X115591Y36975D02*
Y36025D01*
G01Y42125D02*
Y41175D01*
G01X115116Y34875D02*
Y34388D01*
G01Y43275D02*
Y43762D01*
G01X113970Y25730D02*
Y39478D01*
G01X113940Y38557D02*
Y21614D01*
G01X113016Y38600D02*
Y39550D01*
G01X110869Y38557D02*
Y21614D01*
G01X110840Y39478D02*
Y25730D01*
G01X109126Y24851D02*
Y30464D01*
G01Y835D02*
Y4479D01*
G01X108783Y4823D02*
Y491D01*
G01Y30807D02*
Y24507D01*
G01X116996Y33105D02*
X115137Y45044D01*
G01X117016Y34875D02*
X115116Y43275D01*
G01X118206Y41214D02*
X120266Y40025D01*
G01X106883Y25730D02*
Y39478D01*
G01X106854Y38557D02*
Y21614D01*
G01X103783Y38557D02*
Y21614D01*
G01X102326Y42608D02*
Y60138D01*
G01X110062Y48917D02*
X109581Y62697D01*
G01X108794D02*
X109275Y48917D01*
G01X127326Y39921D02*
X128113Y38557D01*
G01X136617Y23327D02*
X135230Y25730D01*
G01X120239Y39921D02*
X121027Y38557D01*
G01X129531Y23327D02*
X128143Y25730D01*
G01X117016Y43275D02*
X118206Y41214D01*
G01X117136Y40144D02*
X116541Y41175D01*
G01X114996Y38005D02*
X115591Y36975D01*
G01X113153Y39921D02*
X113940Y38557D01*
G01X122444Y23327D02*
X121056Y25730D01*
G01X115116Y34875D02*
X113927Y36935D01*
G01X118206D02*
X113927Y41214D01*
G01X123006Y24851D02*
X123350Y24507D01*
G01X122563Y23720D02*
X122219Y24064D01*
G01X117136Y40144D02*
X118166Y39550D01*
G01X113966Y38600D02*
X114996Y38005D01*
G01X113927Y36935D02*
X111866Y38125D01*
G01X106066Y39921D02*
X106854Y38557D01*
G01X115358Y23327D02*
X113970Y25730D01*
G01X108271Y23327D02*
X106883Y25730D01*
G01X109570Y31594D02*
X109913Y31251D01*
G01X109126Y30464D02*
X108783Y30807D01*
G01X116623Y19845D02*
X121345Y15123D01*
G01X116205Y19427D02*
X120927Y14706D01*
G01X115927Y19427D02*
X115509Y19845D01*
G01X120927Y14427D02*
X121345Y14010D01*
G01X117641Y14567D02*
X116066Y16141D01*
G01X114491Y14567D02*
X116066Y12992D01*
G01X111205Y14706D02*
X110788Y15123D01*
G01X116205Y9706D02*
X116623Y9288D01*
G01X111205Y14427D02*
X115927Y9706D01*
G01X115509Y9288D02*
X110788Y14010D01*
G01X123006Y835D02*
X123350Y491D01*
G01X122563Y-296D02*
X122219Y48D01*
G01X109570Y5610D02*
X109913Y5266D01*
G01X109126Y4479D02*
X108783Y4823D01*
G01X103907Y53332D02*
X103783Y53648D01*
G01X104124Y53051D02*
X103907Y53332D01*
G01X125167D02*
X125043Y53648D01*
G01X125384Y53051D02*
X125167Y53332D01*
G01X103927Y53421D02*
X104124Y53051D01*
G01X103798Y53852D02*
X103927Y53421D01*
G01X103753Y54309D02*
X103798Y53852D01*
G01X111014Y53421D02*
X111211Y53051D01*
G01X110885Y53852D02*
X111014Y53421D01*
G01X110840Y54309D02*
X110885Y53852D01*
G01X118100Y53421D02*
X118297Y53051D01*
G01X117971Y53852D02*
X118100Y53421D01*
G01X117926Y54309D02*
X117971Y53852D01*
G01X125187Y53421D02*
X125384Y53051D01*
G01X125058Y53852D02*
X125187Y53421D01*
G01X125013Y54309D02*
X125058Y53852D01*
G01X103761Y53766D02*
X103783Y53643D01*
G01X103753Y53889D02*
X103761Y53766D01*
G01X110163Y56397D02*
X110211Y55021D01*
G01X110122Y57775D02*
X110163Y56397D01*
G01X111006Y53310D02*
X111211Y53051D01*
G01X110882Y53596D02*
X111006Y53310D01*
G01X110840Y53889D02*
X110882Y53596D01*
G01X118093Y53310D02*
X118297Y53051D01*
G01X117968Y53596D02*
X118093Y53310D01*
G01X117926Y53889D02*
X117968Y53596D01*
G01X132266Y53310D02*
X132471Y53051D01*
G01X132141Y53596D02*
X132266Y53310D01*
G01X132100Y53889D02*
X132141Y53596D01*
G01X132274Y53421D02*
X132471Y53051D01*
G01X132145Y53852D02*
X132274Y53421D01*
G01X132100Y54309D02*
X132145Y53852D01*
G01X125021Y53766D02*
X125043Y53643D01*
G01X125013Y53889D02*
X125021Y53766D01*
G01X106876Y53767D02*
X106854Y53643D01*
G01X106883Y53889D02*
X106876Y53767D01*
G01X128136D02*
X128113Y53643D01*
G01X128143Y53889D02*
X128136Y53767D01*
G01X113808Y53317D02*
X113599Y53051D01*
G01X113930Y53605D02*
X113808Y53317D01*
G01X113970Y53889D02*
X113930Y53605D01*
G01X120894Y53317D02*
X120685Y53051D01*
G01X121017Y53605D02*
X120894Y53317D01*
G01X121056Y53889D02*
X121017Y53605D01*
G01X135067Y53317D02*
X134859Y53051D01*
G01X135190Y53605D02*
X135067Y53317D01*
G01X135230Y53889D02*
X135190Y53605D01*
G01X106728Y53330D02*
X106512Y53051D01*
G01X106854Y53648D02*
X106728Y53330D01*
G01X114045Y57423D02*
X113053Y57775D01*
G01X115060Y57214D02*
X114045Y57423D01*
G01X116066Y57145D02*
X115060Y57214D01*
G01X127988Y53330D02*
X127772Y53051D01*
G01X128113Y53648D02*
X127988Y53330D01*
G01X106838Y53853D02*
X106883Y54309D01*
G01X106709Y53422D02*
X106838Y53853D01*
G01X106512Y53051D02*
X106709Y53422D01*
G01X113925Y53853D02*
X113970Y54309D01*
G01X113796Y53422D02*
X113925Y53853D01*
G01X113599Y53051D02*
X113796Y53422D01*
G01X121011Y53853D02*
X121056Y54309D01*
G01X120883Y53422D02*
X121011Y53853D01*
G01X120685Y53051D02*
X120883Y53422D01*
G01X128098Y53853D02*
X128143Y54309D01*
G01X127969Y53422D02*
X128098Y53853D01*
G01X127772Y53051D02*
X127969Y53422D01*
G01X135185Y53853D02*
X135230Y54309D01*
G01X135056Y53422D02*
X135185Y53853D01*
G01X134859Y53051D02*
X135056Y53422D01*
G01X117071Y57214D02*
X116066Y57145D01*
G01X118087Y57423D02*
X117071Y57214D01*
G01X119079Y57775D02*
X118087Y57423D01*
G01X132463Y53045D02*
G03X134866I1201J1018D01*
G01X125376D02*
G03X127780I1202J1018D01*
G01X118290D02*
G03X120693I1201J1018D01*
G01X111203D02*
G03X113606I1202J1018D01*
G01X104117D02*
G03X106520I1201J1018D01*
G01X125830Y61909D02*
X125043Y61122D01*
G01X104570Y61909D02*
X103783Y61122D01*
G01X128968Y62697D02*
X102928D01*
G01X165452D02*
X138484D01*
G01X104570Y61909D02*
X106066D01*
G01X127326D02*
X125830D01*
G01X106854Y61122D02*
X103783D01*
G01X128113D02*
X125043D01*
G01X165554Y60138D02*
X102326D01*
G01X123208Y58956D02*
X128968D01*
G01X108924D02*
X102928D01*
G01X165452D02*
X138484D01*
G01X102326Y57775D02*
X165554D01*
G01X104124Y53051D02*
X102326D01*
G01X111211D02*
X106512D01*
G01X118297D02*
X113599D01*
G01X125384D02*
X120685D01*
G01X132471D02*
X127772D01*
G01X139557D02*
X134859D01*
G01X138484Y52854D02*
X139216D01*
G01X106854D02*
X125043D01*
G01X103783D02*
X102928D01*
G01X128968D02*
X128113D01*
G01X123166Y57775D02*
X123169Y57821D01*
G01X135230Y60138D02*
Y53889D01*
G01X132100Y60138D02*
Y53889D01*
G01X128143Y60138D02*
Y53889D01*
G01X128113Y61122D02*
Y52854D01*
G01X125043D02*
Y61122D01*
G01X125013Y60138D02*
Y53889D01*
G01X121056Y60138D02*
Y53889D01*
G01X117926Y60138D02*
Y53889D01*
G01X113970Y60138D02*
Y53889D01*
G01X110840Y60138D02*
Y53889D01*
G01X106883Y60138D02*
Y53889D01*
G01X106854Y61122D02*
Y52854D01*
G01X103783D02*
Y61122D01*
G01X103753Y60138D02*
Y53889D01*
G01X108967Y57775D02*
X108963Y57821D01*
G01X127326Y61909D02*
X128113Y61122D01*
G01X106066Y61909D02*
X106854Y61122D01*
G01X111778Y482644D02*
X111417Y482677D01*
G01X112152Y482534D02*
X111778Y482644D01*
G01X112518Y482340D02*
X112152Y482534D01*
G01X112849Y482059D02*
X112518Y482340D01*
G01X113122Y481693D02*
X112849Y482059D01*
G01X123370D02*
X123098Y481693D01*
G01X123701Y482340D02*
X123370Y482059D01*
G01X124066Y482534D02*
X123701Y482340D01*
G01X124441Y482643D02*
X124066Y482534D01*
G01X124803Y482677D02*
X124441Y482643D01*
G01X139173Y472441D02*
G03I-1378J0D01*
G01X99803D02*
G03I-1378J0D01*
G01X100197D02*
G03I-1772J0D01*
G01X139567D02*
G03I-1772J0D01*
G01X85334Y484252D02*
X150886D01*
G01X97638Y483464D02*
X107086D01*
G01X138582D02*
X129134D01*
G01Y483071D02*
X138582D01*
G01X107086D02*
X97638D01*
G01X124803Y482677D02*
X149311D01*
G01X86909D02*
X111417D01*
G01X95472Y482476D02*
X93504D01*
G01X103346D02*
X101378D01*
G01X111220D02*
X109252D01*
G01X119094D02*
X117126D01*
G01X126968D02*
X125000D01*
G01X134842D02*
X132874D01*
G01X126968Y481693D02*
X140748D01*
G01X122834D02*
X125000D01*
G01X111220D02*
X113386D01*
G01X95472D02*
X109252D01*
G01X93504D02*
X89862D01*
G01X147638Y481496D02*
X88582D01*
G01X89862Y480708D02*
X88878D01*
G01X95472D02*
X93504D01*
G01X111220D02*
X109252D01*
G01X126968D02*
X125000D01*
G01X131102Y478858D02*
X136614D01*
G01X123228D02*
X128740D01*
G01X115354D02*
X120866D01*
G01X107480D02*
X112992D01*
G01X99606D02*
X105118D01*
G01X97244D02*
X91732D01*
G01X95472Y478346D02*
X93504D01*
G01X103346D02*
X101378D01*
G01X111220D02*
X109252D01*
G01X119094D02*
X117126D01*
G01X126968D02*
X125000D01*
G01X134842D02*
X132874D01*
G01X96220Y478110D02*
X92756D01*
G01X104094D02*
X100630D01*
G01X111968D02*
X108504D01*
G01X119842D02*
X116378D01*
G01X127716D02*
X124252D01*
G01X135590D02*
X132126D01*
G01X95472Y477362D02*
X93504D01*
G01X103346D02*
X101378D01*
G01X111220D02*
X109252D01*
G01X119094D02*
X117126D01*
G01X126968D02*
X125000D01*
G01X134842D02*
X132874D01*
G01X95078Y476968D02*
X93897D01*
G01X102952D02*
X101771D01*
G01X110826D02*
X109645D01*
G01X118700D02*
X117519D01*
G01X126575D02*
X125393D01*
G01X134449D02*
X133267D01*
G01Y475787D02*
X134449D01*
G01X125393D02*
X126575D01*
G01X117519D02*
X118700D01*
G01X109645D02*
X110826D01*
G01X101771D02*
X102952D01*
G01X93897D02*
X95078D01*
G01X95472Y475393D02*
X93504D01*
G01X103346D02*
X101378D01*
G01X111220D02*
X109252D01*
G01X119094D02*
X117126D01*
G01X126968D02*
X125000D01*
G01X134842D02*
X132874D01*
G01X132126Y474645D02*
X135590D01*
G01X124252D02*
X127716D01*
G01X116378D02*
X119842D01*
G01X108504D02*
X111968D01*
G01X100630D02*
X104094D01*
G01X92756D02*
X96220D01*
G01X85334Y474409D02*
X86909D01*
G01X97244Y473425D02*
X91732D01*
G01X105118D02*
X99606D01*
G01X112992D02*
X107480D01*
G01X120866D02*
X115354D01*
G01X128740D02*
X123228D01*
G01X136614D02*
X131102D01*
G01X85334Y472441D02*
X88878D01*
G01X97244Y471456D02*
X91732D01*
G01X105118D02*
X99606D01*
G01X112992D02*
X107480D01*
G01X120866D02*
X115354D01*
G01X128740D02*
X123228D01*
G01X136614D02*
X131102D01*
G01X96220Y470236D02*
X92756D01*
G01X104094D02*
X100630D01*
G01X111968D02*
X108504D01*
G01X119842D02*
X116378D01*
G01X127716D02*
X124252D01*
G01X135590D02*
X132126D01*
G01X95472Y469488D02*
X93504D01*
G01X103346D02*
X101378D01*
G01X111220D02*
X109252D01*
G01X119094D02*
X117126D01*
G01X126968D02*
X125000D01*
G01X134842D02*
X132874D01*
G01X95078Y469094D02*
X93897D01*
G01X102952D02*
X101771D01*
G01X110826D02*
X109645D01*
G01X118700D02*
X117519D01*
G01X126575D02*
X125393D01*
G01X134449D02*
X133267D01*
G01X85334Y468504D02*
X88878D01*
G01X133267Y467913D02*
X134449D01*
G01X125393D02*
X126575D01*
G01X117519D02*
X118700D01*
G01X109645D02*
X110826D01*
G01X101771D02*
X102952D01*
G01X93897D02*
X95078D01*
G01X95472Y467519D02*
X93504D01*
G01X103346D02*
X101378D01*
G01X111220D02*
X109252D01*
G01X119094D02*
X117126D01*
G01X126968D02*
X125000D01*
G01X134842D02*
X132874D01*
G01X132126Y466771D02*
X135590D01*
G01X124252D02*
X127716D01*
G01X116378D02*
X119842D01*
G01X108504D02*
X111968D01*
G01X100630D02*
X104094D01*
G01X92756D02*
X96220D01*
G01X132874Y466535D02*
X134842D01*
G01X125000D02*
X126968D01*
G01X117126D02*
X119094D01*
G01X109252D02*
X111220D01*
G01X101378D02*
X103346D01*
G01X93504D02*
X95472D01*
G01X85334D02*
X86909D01*
G01X99606Y466023D02*
X105118D01*
G01X97244D02*
X91732D01*
G01X112992D02*
X107480D01*
G01X120866D02*
X115354D01*
G01X128740D02*
X123228D01*
G01X136614D02*
X131102D01*
G01X89862Y464173D02*
X88878D01*
G01X103346D02*
X101378D01*
G01X119094D02*
X117126D01*
G01X134842D02*
X132874D01*
G01X147638Y463386D02*
X88582D01*
G01X101378Y463189D02*
X89862D01*
G01X117126D02*
X103346D01*
G01X132874D02*
X119094D01*
G01X146358D02*
X134842D01*
G01X132874Y462406D02*
X134842D01*
G01X125000D02*
X126968D01*
G01X117126D02*
X119094D01*
G01X109252D02*
X111220D01*
G01X101378D02*
X103346D01*
G01X93504D02*
X95472D01*
G01X149311Y462204D02*
X86909D01*
G01X150886Y460630D02*
X85334D01*
G01X133267Y476968D02*
X132126Y478110D01*
G01X135590Y474645D02*
X134449Y475787D01*
G01X127716Y474645D02*
X126575Y475787D01*
G01X125393Y476968D02*
X124252Y478110D01*
G01X133267Y469094D02*
X132126Y470236D01*
G01X134449Y467913D02*
X135590Y466771D01*
G01X117519Y476968D02*
X116378Y478110D01*
G01X119842Y474645D02*
X118700Y475787D01*
G01X125393Y469094D02*
X124252Y470236D01*
G01X126575Y467913D02*
X127716Y466771D01*
G01X109645Y476968D02*
X108504Y478110D01*
G01X111968Y474645D02*
X110826Y475787D01*
G01X117519Y469094D02*
X116378Y470236D01*
G01X118700Y467913D02*
X119842Y466771D01*
G01X104094Y474645D02*
X102952Y475787D01*
G01X101771Y476968D02*
X100630Y478110D01*
G01X109645Y469094D02*
X108504Y470236D01*
G01X110826Y467913D02*
X111968Y466771D01*
G01X93897Y476968D02*
X92756Y478110D01*
G01X96220Y474645D02*
X95078Y475787D01*
G01X101771Y469094D02*
X100630Y470236D01*
G01X102952Y467913D02*
X104094Y466771D01*
G01X88878Y480708D02*
X86909Y482677D01*
G01X93897Y469094D02*
X92756Y470236D01*
G01X95078Y467913D02*
X96220Y466771D01*
G01X88878Y472441D02*
X86909Y474409D01*
G01X134449Y484252D02*
X134842Y482476D01*
G01X132874Y462406D02*
X133267Y460630D01*
G01X126575Y484252D02*
X126968Y482476D01*
G01X125000Y462406D02*
X125393Y460630D01*
G01X118700Y484252D02*
X119094Y482476D01*
G01X117126Y462406D02*
X117519Y460630D01*
G01X110826Y484252D02*
X111220Y482476D01*
G01X109252Y462406D02*
X109645Y460630D01*
G01X102952Y484252D02*
X103346Y482476D01*
G01X101378Y462406D02*
X101771Y460630D01*
G01X95078Y484252D02*
X95472Y482476D01*
G01X93504Y462406D02*
X93897Y460630D01*
G01X136614Y473761D02*
Y481496D01*
G01Y463386D02*
Y471120D01*
G01Y473425D02*
Y471456D01*
G01X135590Y474645D02*
Y478110D01*
G01Y466771D02*
Y470236D01*
G01X134842Y462406D02*
Y469488D01*
G01Y482476D02*
Y475393D01*
G01X134449Y475787D02*
Y476968D01*
G01Y467913D02*
Y469094D01*
G01X133267D02*
Y467913D01*
G01Y476968D02*
Y475787D01*
G01X132874Y469488D02*
Y462406D01*
G01Y482476D02*
Y475393D01*
G01X132126Y470236D02*
Y466771D01*
G01Y478110D02*
Y474645D01*
G01X131102Y463386D02*
Y481496D01*
G01X129134Y481693D02*
Y484252D01*
G01X128740Y463386D02*
Y481496D01*
G01X127716Y474645D02*
Y478110D01*
G01Y466771D02*
Y470236D01*
G01X126968Y462406D02*
Y469488D01*
G01Y482476D02*
Y475393D01*
G01X126575Y475787D02*
Y476968D01*
G01Y467913D02*
Y469094D01*
G01X125393D02*
Y467913D01*
G01Y476968D02*
Y475787D01*
G01X125000Y469488D02*
Y462406D01*
G01Y482476D02*
Y475393D01*
G01X124803Y484252D02*
Y482677D01*
G01X124252Y470236D02*
Y466771D01*
G01Y478110D02*
Y474645D01*
G01X123228Y463386D02*
Y481496D01*
G01X122834Y484252D02*
Y481693D01*
G01X120866Y463386D02*
Y481496D01*
G01X119842Y474645D02*
Y478110D01*
G01Y466771D02*
Y470236D01*
G01X119094Y462406D02*
Y469488D01*
G01Y482476D02*
Y475393D01*
G01X118700Y475787D02*
Y476968D01*
G01Y467913D02*
Y469094D01*
G01X117519D02*
Y467913D01*
G01Y476968D02*
Y475787D01*
G01X117126Y469488D02*
Y462406D01*
G01Y482476D02*
Y475393D01*
G01X116378Y470236D02*
Y466771D01*
G01Y478110D02*
Y474645D01*
G01X115354Y463386D02*
Y481496D01*
G01X113386Y484252D02*
Y481693D01*
G01X112992Y463386D02*
Y481496D01*
G01X111968Y474645D02*
Y478110D01*
G01Y466771D02*
Y470236D01*
G01X111417Y482677D02*
Y484252D01*
G01X111220Y462406D02*
Y469488D01*
G01Y482476D02*
Y475393D01*
G01X110826Y475787D02*
Y476968D01*
G01Y467913D02*
Y469094D01*
G01X109645D02*
Y467913D01*
G01Y476968D02*
Y475787D01*
G01X109252Y469488D02*
Y462406D01*
G01Y482476D02*
Y475393D01*
G01X108504Y470236D02*
Y466771D01*
G01Y478110D02*
Y474645D01*
G01X134842Y462406D02*
X134449Y460630D01*
G01X133267Y484252D02*
X132874Y482476D01*
G01X126968Y462406D02*
X126575Y460630D01*
G01X125393Y484252D02*
X125000Y482476D01*
G01X119094Y462406D02*
X118700Y460630D01*
G01X117519Y484252D02*
X117126Y482476D01*
G01X111220Y462406D02*
X110826Y460630D01*
G01X107480Y463386D02*
Y481496D01*
G01X107086Y484252D02*
Y481693D01*
G01X105118Y463386D02*
Y481496D01*
G01X104094Y474645D02*
Y478110D01*
G01Y466771D02*
Y470236D01*
G01X103346Y462406D02*
Y469488D01*
G01Y482476D02*
Y475393D01*
G01X102952Y475787D02*
Y476968D01*
G01Y467913D02*
Y469094D01*
G01X101771D02*
Y467913D01*
G01Y476968D02*
Y475787D01*
G01X101378Y469488D02*
Y462406D01*
G01Y482476D02*
Y475393D01*
G01X100630Y470236D02*
Y466771D01*
G01Y478110D02*
Y474645D01*
G01X99606Y473761D02*
Y481496D01*
G01Y471456D02*
Y473425D01*
G01Y463386D02*
Y471120D01*
G01X97638Y481693D02*
Y484252D01*
G01X97244Y471120D02*
Y463386D01*
G01Y473425D02*
Y471456D01*
G01Y481496D02*
Y473761D01*
G01X96220Y474645D02*
Y478110D01*
G01Y466771D02*
Y470236D01*
G01X95472Y462406D02*
Y469488D01*
G01Y482476D02*
Y475393D01*
G01X95078Y475787D02*
Y476968D01*
G01Y467913D02*
Y469094D01*
G01X93897D02*
Y467913D01*
G01Y476968D02*
Y475787D01*
G01X93504Y469488D02*
Y462406D01*
G01Y482476D02*
Y475393D01*
G01X92756Y470236D02*
Y466771D01*
G01Y478110D02*
Y474645D01*
G01X91732Y463386D02*
Y481496D01*
G01X89862Y480708D02*
Y481693D01*
G01Y463189D02*
Y464173D01*
G01X88878Y480708D02*
Y464173D01*
G01X88582Y481496D02*
Y463386D01*
G01X86909Y474409D02*
Y482677D01*
G01Y466535D02*
Y462204D01*
G01X85334Y460630D02*
Y484252D01*
G01X134449Y469094D02*
X135590Y470236D01*
G01X132126Y466771D02*
X133267Y467913D01*
G01X134449Y476968D02*
X135590Y478110D01*
G01X132126Y474645D02*
X133267Y475787D01*
G01X126575Y469094D02*
X127716Y470236D01*
G01X124252Y466771D02*
X125393Y467913D01*
G01X126575Y476968D02*
X127716Y478110D01*
G01X124252Y474645D02*
X125393Y475787D01*
G01X118700Y469094D02*
X119842Y470236D01*
G01X116378Y466771D02*
X117519Y467913D01*
G01X118700Y476968D02*
X119842Y478110D01*
G01X116378Y474645D02*
X117519Y475787D01*
G01X110826Y469094D02*
X111968Y470236D01*
G01X108504Y466771D02*
X109645Y467913D01*
G01X110826Y476968D02*
X111968Y478110D01*
G01X108504Y474645D02*
X109645Y475787D01*
G01X102952Y469094D02*
X104094Y470236D01*
G01X100630Y466771D02*
X101771Y467913D01*
G01X102952Y476968D02*
X104094Y478110D01*
G01X100630Y474645D02*
X101771Y475787D01*
G01X95078Y469094D02*
X96220Y470236D01*
G01X92756Y466771D02*
X93897Y467913D01*
G01X86909Y462204D02*
X88878Y464173D01*
G01X109645Y484252D02*
X109252Y482476D01*
G01X103346Y462406D02*
X102952Y460630D01*
G01X101771Y484252D02*
X101378Y482476D01*
G01X95472Y462406D02*
X95078Y460630D01*
G01X93897Y484252D02*
X93504Y482476D01*
G01X86909Y466535D02*
X88878Y468504D01*
G01X95078Y476968D02*
X96220Y478110D01*
G01X92756Y474645D02*
X93897Y475787D01*
G01X140649Y-46851D02*
X139468Y-48032D01*
G01X165452D02*
Y62697D01*
G01X163484Y-9716D02*
Y-48032D01*
G01X163287Y-9322D02*
Y-46851D01*
G01X163090Y-9322D02*
Y-48032D01*
G01X159842Y-40158D02*
Y-47441D01*
G01X156693Y-40158D02*
Y-47441D01*
G01X147244Y-40158D02*
Y-47441D01*
G01X144094Y-40158D02*
Y-47441D01*
G01X147244Y-40158D02*
X144094D01*
G01X159842D02*
X156693D01*
G01X140846Y-9322D02*
Y-48032D01*
G01X140649Y-9322D02*
Y-46851D01*
G01X140452Y-9716D02*
Y-48032D01*
G01X144094Y-46851D02*
X140649D01*
G01X156693D02*
X147244D01*
G01X163287D02*
X159842D01*
G01X147244Y-47441D02*
X144094D01*
G01X159842D02*
X156693D01*
G01X163287Y-46851D02*
X164468Y-48032D01*
G01X159724Y47362D02*
G03I-1457J0D01*
G01Y41456D02*
G03I-1457J0D01*
G01X163989Y41033D02*
G03X165564Y42608I0J1575D01*
G01X163980Y46771D02*
G03I-1969J0D01*
G01X156893D02*
G03I-1968J0D01*
G01X147126Y47362D02*
G03I-1457J0D01*
G01Y41456D02*
G03I-1457J0D01*
G01X149806Y46771D02*
G03I-1968J0D01*
G01X142720D02*
G03I-1969J0D01*
G01X159724Y31614D02*
G03I-1457J0D01*
G01Y25708D02*
G03I-1457J0D01*
G01X147126Y31614D02*
G03I-1457J0D01*
G01Y25708D02*
G03I-1457J0D01*
G01X149413Y39478D02*
G03X146263I-1575J0D01*
G01X156499D02*
G03X153350I-1575J0D01*
G01X162011Y41053D02*
G03X160436Y39478I0J-1575D01*
G01X142326D02*
G03X139176I-1575J0D01*
G01X159724Y19803D02*
G03I-1457J0D01*
G01X147126D02*
G03I-1457J0D01*
G01X148130D02*
G03I-2461J0D01*
G01X163484Y-9716D02*
G03X163090Y-9322I-394J0D01*
G01X140846D02*
G03X140452Y-9716I0J-394D01*
G01X143300Y15432D02*
X143399Y15465D01*
G01X143563Y15365D02*
X143431Y15264D01*
G01X161362Y39915D02*
X160377Y38931D01*
G01X154275Y39915D02*
X153291Y38931D01*
G01X143399Y15465D02*
X143464Y15532D01*
G01X147188Y39915D02*
X146204Y38931D01*
G01X140102Y39915D02*
X139117Y38931D01*
G01X149337Y15834D02*
X149140Y15599D01*
G01Y15868D02*
X149337Y16102D01*
G01X143661Y15499D02*
X143563Y15365D01*
G01X160377Y25611D02*
X159058Y23327D01*
G01X153291Y25611D02*
X151972Y23327D01*
G01X146204Y25611D02*
X144885Y23327D01*
G01X143431Y15264D02*
X143267Y15231D01*
G01X147565Y14527D02*
X148090Y16102D01*
G01X147893Y14929D02*
X147762Y14527D01*
G01X147926Y15063D02*
X148221Y15968D01*
G01X143694Y15599D02*
X143661Y15499D01*
G01X143464Y15532D02*
X143497Y15633D01*
G01X163989Y41043D02*
X162011D01*
G01X141401Y39915D02*
X140102D01*
G01X148488D02*
X147188D01*
G01X155574D02*
X154275D01*
G01X162661D02*
X161362D01*
G01X156696Y25372D02*
X160239D01*
G01X149610D02*
X153153D01*
G01X142523D02*
X146066D01*
G01X144885Y23327D02*
X143704D01*
G01X151972D02*
X150791D01*
G01X159058D02*
X157877D01*
G01X146204Y22199D02*
X142385D01*
G01X153291D02*
X149472D01*
G01X160377D02*
X156558D01*
G01X165452D02*
X163645D01*
G01X149337Y16102D02*
X149534D01*
G01X148090D02*
X148353D01*
G01X144416D02*
X144711D01*
G01X145531D02*
X145728D01*
G01X143956D02*
X144153D01*
G01X142480D02*
X143267D01*
G01X143300Y15935D02*
X142677D01*
G01Y15432D02*
X143300D01*
G01X143267Y15231D02*
X142677D01*
G01X148517Y15063D02*
X147926D01*
G01X148550Y14929D02*
X147893D01*
G01X142677Y14527D02*
X142480D01*
G01X144613D02*
X144416D01*
G01X145728D02*
X145433D01*
G01X144153D02*
X143956D01*
G01X148878D02*
X148681D01*
G01X147762D02*
X147565D01*
G01X149534D02*
X149337D01*
G01X163287Y-9322D02*
X140649D01*
G01X165554Y60138D02*
Y42608D01*
G01X163645Y38931D02*
Y22199D01*
G01X160446Y39478D02*
Y39000D01*
G01X160377Y38931D02*
Y22199D01*
G01X156558Y38931D02*
Y22199D01*
G01X156489Y39000D02*
Y39478D01*
G01X153360D02*
Y39000D01*
G01X153291Y38931D02*
Y22199D01*
G01X149534Y16102D02*
Y14527D01*
G01X149472Y38931D02*
Y22199D01*
G01X149403Y39000D02*
Y39478D01*
G01X149337Y14527D02*
Y15834D01*
G01X149140Y15599D02*
Y15868D01*
G01X146273Y39478D02*
Y39000D01*
G01X146204Y38931D02*
Y22199D01*
G01X145728Y16102D02*
Y14527D01*
G01X145531Y14762D02*
Y16102D01*
G01X144613Y15901D02*
Y14527D01*
G01X144416D02*
Y16102D01*
G01X144153D02*
Y14527D01*
G01X143956D02*
Y16102D01*
G01X143694Y15734D02*
Y15599D01*
G01X143497Y15633D02*
Y15734D01*
G01X142677Y15935D02*
Y15432D01*
G01Y15231D02*
Y14527D01*
G01X143267Y16102D02*
X143431Y16069D01*
G01X140452Y-9716D02*
X163484D01*
G01X142480Y14527D02*
Y16102D01*
G01X142385Y22199D02*
Y38931D01*
G01X142316Y39000D02*
Y39478D01*
G01X139186D02*
Y39000D01*
G01X139117Y38931D02*
Y22199D01*
G01X148221Y15968D02*
X148517Y15063D01*
G01X148681Y14527D02*
X148550Y14929D01*
G01X143661Y15834D02*
X143694Y15734D01*
G01X143497D02*
X143464Y15834D01*
G01X148353Y16102D02*
X148878Y14527D01*
G01X162661Y39915D02*
X163645Y38931D01*
G01X155574Y39915D02*
X156558Y38931D01*
G01X143399Y15901D02*
X143300Y15935D01*
G01X157877Y23327D02*
X156558Y25611D01*
G01X150791Y23327D02*
X149472Y25611D01*
G01X143704Y23327D02*
X142385Y25611D01*
G01X145433Y14527D02*
X144613Y15901D01*
G01X144711Y16102D02*
X145531Y14762D01*
G01X143563Y15968D02*
X143661Y15834D01*
G01X143464D02*
X143399Y15901D01*
G01X148488Y39915D02*
X149472Y38931D01*
G01X141401Y39915D02*
X142385Y38931D01*
G01X143431Y16069D02*
X143563Y15968D01*
G01X139340Y53332D02*
X139216Y53648D01*
G01X139557Y53051D02*
X139340Y53332D01*
G01X160600D02*
X160476Y53648D01*
G01X160817Y53051D02*
X160600Y53332D01*
G01X139360Y53421D02*
X139557Y53051D01*
G01X139231Y53852D02*
X139360Y53421D01*
G01X139186Y54309D02*
X139231Y53852D01*
G01X146447Y53421D02*
X146644Y53051D01*
G01X146318Y53852D02*
X146447Y53421D01*
G01X146273Y54309D02*
X146318Y53852D01*
G01X153533Y53421D02*
X153730Y53051D01*
G01X153405Y53852D02*
X153533Y53421D01*
G01X153360Y54309D02*
X153405Y53852D01*
G01X160620Y53421D02*
X160817Y53051D01*
G01X160491Y53852D02*
X160620Y53421D01*
G01X160446Y54309D02*
X160491Y53852D01*
G01X139194Y53766D02*
X139216Y53643D01*
G01X139186Y53889D02*
X139194Y53766D01*
G01X146439Y53310D02*
X146644Y53051D01*
G01X146315Y53596D02*
X146439Y53310D01*
G01X146273Y53889D02*
X146315Y53596D01*
G01X153526Y53310D02*
X153730Y53051D01*
G01X153401Y53596D02*
X153526Y53310D01*
G01X153360Y53889D02*
X153401Y53596D01*
G01X160454Y53766D02*
X160476Y53643D01*
G01X160446Y53889D02*
X160454Y53766D01*
G01X142309Y53767D02*
X142287Y53643D01*
G01X142316Y53889D02*
X142309Y53767D01*
G01X163569D02*
X163547Y53643D01*
G01X163576Y53889D02*
X163569Y53767D01*
G01X149241Y53317D02*
X149032Y53051D01*
G01X149363Y53605D02*
X149241Y53317D01*
G01X149403Y53889D02*
X149363Y53605D01*
G01X156327Y53317D02*
X156119Y53051D01*
G01X156450Y53605D02*
X156327Y53317D01*
G01X156489Y53889D02*
X156450Y53605D01*
G01X142161Y53330D02*
X141945Y53051D01*
G01X142287Y53648D02*
X142161Y53330D01*
G01X163421D02*
X163205Y53051D01*
G01X163547Y53648D02*
X163421Y53330D01*
G01X142271Y53853D02*
X142316Y54309D01*
G01X142143Y53422D02*
X142271Y53853D01*
G01X141945Y53051D02*
X142143Y53422D01*
G01X149358Y53853D02*
X149403Y54309D01*
G01X149229Y53422D02*
X149358Y53853D01*
G01X149032Y53051D02*
X149229Y53422D01*
G01X156445Y53853D02*
X156489Y54309D01*
G01X156316Y53422D02*
X156445Y53853D01*
G01X156119Y53051D02*
X156316Y53422D01*
G01X163531Y53853D02*
X163576Y54309D01*
G01X163402Y53422D02*
X163531Y53853D01*
G01X163205Y53051D02*
X163402Y53422D01*
G01X159724Y53267D02*
G03I-1457J0D01*
G01X160810Y53045D02*
G03X163213I1202J1018D01*
G01X153723D02*
G03X156126I1201J1018D01*
G01X147126Y53267D02*
G03I-1457J0D01*
G01X146636Y53045D02*
G03X149039I1202J1018D01*
G01X139550D02*
G03X141953I1202J1018D01*
G01X161263Y61712D02*
X160476Y60925D01*
G01X140003Y61712D02*
X139216Y60925D01*
G01X161263Y61712D02*
X162759D01*
G01X140003D02*
X141499D01*
G01X142287Y60925D02*
X139216D01*
G01X163547D02*
X160476D01*
G01X146644Y53051D02*
X141945D01*
G01X153730D02*
X149032D01*
G01X160817D02*
X156119D01*
G01X165554D02*
X163205D01*
G01X163547Y52854D02*
X165452D01*
G01X142287D02*
X160476D01*
G01X163576Y60138D02*
Y53889D01*
G01X163547Y60925D02*
Y52854D01*
G01X160476D02*
Y60925D01*
G01X160446Y60138D02*
Y53889D01*
G01X156489Y60138D02*
Y53889D01*
G01X153360Y60138D02*
Y53889D01*
G01X149403Y60138D02*
Y53889D01*
G01X146273Y60138D02*
Y53889D01*
G01X142316Y60138D02*
Y53889D01*
G01X142287Y60925D02*
Y52854D01*
G01X139216D02*
Y60925D01*
G01X139186Y60138D02*
Y53889D01*
G01X162759Y61712D02*
X163547Y60925D01*
G01X141499Y61712D02*
X142287Y60925D01*
G01X142716Y482476D02*
X140748D01*
G01X146358Y481693D02*
X142716D01*
G01Y480708D02*
X140748D01*
G01X147342D02*
X146358D01*
G01X138976Y478858D02*
X144488D01*
G01X142716Y478346D02*
X140748D01*
G01X143464Y478110D02*
X140000D01*
G01X143366Y478031D02*
X143789D01*
G01X142716Y477362D02*
X140748D01*
G01X142323Y476968D02*
X141141D01*
G01Y475787D02*
X142323D01*
G01X142716Y475393D02*
X140748D01*
G01X140000Y474645D02*
X143464D01*
G01X143789D02*
X143366D01*
G01X149311Y474409D02*
X150886D01*
G01X144488Y473425D02*
X138976D01*
G01X147342Y472441D02*
X150886D01*
G01X144488Y471456D02*
X138976D01*
G01X143464Y470236D02*
X140000D01*
G01X142716Y469488D02*
X140748D01*
G01X142323Y469094D02*
X141141D01*
G01X147342Y468504D02*
X150886D01*
G01X141141Y467913D02*
X142323D01*
G01X142716Y467519D02*
X140748D01*
G01X140000Y466771D02*
X143464D01*
G01X149311Y466535D02*
X150886D01*
G01X140748D02*
X142716D01*
G01X138976Y466023D02*
X144488D01*
G01X147342Y464173D02*
X146358D01*
G01X140748Y462406D02*
X142716D01*
G01X141141Y476968D02*
X140000Y478110D01*
G01X143464Y474645D02*
X142323Y475787D01*
G01X147342Y468504D02*
X149311Y466535D01*
G01Y462204D02*
X147342Y464173D01*
G01X141141Y469094D02*
X140000Y470236D01*
G01X143464Y466771D02*
X142323Y467913D01*
G01Y484252D02*
X142716Y482476D01*
G01X140748Y462406D02*
X141141Y460630D01*
G01X150886D02*
Y484252D01*
G01X149311Y466535D02*
Y462204D01*
G01Y482677D02*
Y474409D01*
G01X147638Y481496D02*
Y463386D01*
G01X147342Y480708D02*
Y464173D01*
G01X146358D02*
Y463189D01*
G01Y481693D02*
Y480708D01*
G01X144488Y463386D02*
Y481496D01*
G01X144212Y475726D02*
Y475150D01*
G01X143789Y478031D02*
Y475222D01*
G01X143464Y474645D02*
Y478110D01*
G01Y466771D02*
Y470236D01*
G01X143366Y474645D02*
Y478031D01*
G01X142716Y462406D02*
Y469488D01*
G01Y482476D02*
Y475393D01*
G01X142323Y475787D02*
Y476968D01*
G01Y467913D02*
Y469094D01*
G01X141141D02*
Y467913D01*
G01Y476968D02*
Y475787D01*
G01X140748Y469488D02*
Y462406D01*
G01Y482476D02*
Y475393D01*
G01X140000Y470236D02*
Y466771D01*
G01Y478110D02*
Y474645D01*
G01X138976Y473761D02*
Y481496D01*
G01Y471456D02*
Y473425D01*
G01Y463386D02*
Y471120D01*
G01X138582Y484252D02*
Y481693D01*
G01X147342Y472441D02*
X149311Y474409D01*
G01X140000Y466771D02*
X141141Y467913D01*
G01X143464Y470236D02*
X142323Y469094D01*
G01X142716Y462406D02*
X142323Y460630D01*
G01X141141Y484252D02*
X140748Y482476D01*
G01X147342Y480708D02*
X149311Y482677D01*
G01X140000Y474645D02*
X141141Y475787D01*
G01X143464Y478110D02*
X142323Y476968D01*
G01X144212Y475150D02*
X143789Y474645D01*
G01Y475222D02*
X144212Y475726D01*
G01X295896Y-879845D02*
Y-898782D01*
G01X316433Y-102362D02*
X315941D01*
G01D02*
Y-102756D01*
G01Y-102362D02*
Y-101969D01*
G01X315449Y-102362D02*
X316433D01*
G01X319878D02*
G03X312004I-3937J0D01*
G01X811771D02*
X319878D01*
G01X326770Y0D02*
G03Y-7874I0J-3937D01*
G01X287400D02*
G03Y0I0J3937D01*
G01X302165Y531496D02*
G03I-6890J0D01*
G01X313976D02*
G03I-18701J0D01*
G01X295896Y1297911D02*
Y1278974D01*
G01X378931Y-100963D02*
Y-103762D01*
G01X347436Y-100963D02*
Y-103762D01*
G01X344290Y-39739D02*
X344413Y-39764D01*
G01X344185Y-39666D02*
X344290Y-39739D01*
G01X358463D02*
X358586Y-39764D01*
G01X358358Y-39666D02*
X358463Y-39739D01*
G01X372636D02*
X372760Y-39764D01*
G01X372531Y-39666D02*
X372636Y-39739D01*
G01X386809D02*
X386933Y-39764D01*
G01X386704Y-39666D02*
X386809Y-39739D01*
G01X338315Y-38609D02*
X338309Y-38615D01*
G01X338331Y-38589D02*
X338315Y-38609D01*
G01X338356Y-38556D02*
X338331Y-38589D01*
G01X338390Y-38512D02*
X338356Y-38556D01*
G01X338430Y-38457D02*
X338390Y-38512D01*
G01X338475Y-38389D02*
X338430Y-38457D01*
G01X338522Y-38312D02*
X338475Y-38389D01*
G01X338565Y-38233D02*
X338522Y-38312D01*
G01X338601Y-38160D02*
X338565Y-38233D01*
G01X338629Y-38092D02*
X338601Y-38160D01*
G01X338650Y-38029D02*
X338629Y-38092D01*
G01X338662Y-37971D02*
X338650Y-38029D01*
G01X338666Y-37920D02*
X338662Y-37971D01*
G01X338660Y-37878D02*
X338666Y-37920D01*
G01X338647Y-37844D02*
X338660Y-37878D01*
G01X338631Y-37819D02*
X338647Y-37844D01*
G01X338617Y-37804D02*
X338631Y-37819D01*
G01X338611Y-37799D02*
X338617Y-37804D01*
G01X352488Y-38609D02*
X352483Y-38615D01*
G01X352504Y-38589D02*
X352488Y-38609D01*
G01X352530Y-38556D02*
X352504Y-38589D01*
G01X352563Y-38512D02*
X352530Y-38556D01*
G01X352603Y-38457D02*
X352563Y-38512D01*
G01X352648Y-38389D02*
X352603Y-38457D01*
G01X352696Y-38312D02*
X352648Y-38389D01*
G01X352739Y-38233D02*
X352696Y-38312D01*
G01X352774Y-38160D02*
X352739Y-38233D01*
G01X352802Y-38092D02*
X352774Y-38160D01*
G01X352823Y-38029D02*
X352802Y-38092D01*
G01X352836Y-37971D02*
X352823Y-38029D01*
G01X352839Y-37920D02*
X352836Y-37971D01*
G01X352833Y-37878D02*
X352839Y-37920D01*
G01X352820Y-37844D02*
X352833Y-37878D01*
G01X352804Y-37819D02*
X352820Y-37844D01*
G01X352790Y-37804D02*
X352804Y-37819D01*
G01X352784Y-37799D02*
X352790Y-37804D01*
G01X366661Y-38609D02*
X366656Y-38615D01*
G01X366677Y-38589D02*
X366661Y-38609D01*
G01X366703Y-38556D02*
X366677Y-38589D01*
G01X366737Y-38512D02*
X366703Y-38556D01*
G01X366776Y-38457D02*
X366737Y-38512D01*
G01X366821Y-38389D02*
X366776Y-38457D01*
G01X366869Y-38312D02*
X366821Y-38389D01*
G01X366912Y-38233D02*
X366869Y-38312D01*
G01X366947Y-38160D02*
X366912Y-38233D01*
G01X366975Y-38092D02*
X366947Y-38160D01*
G01X366996Y-38029D02*
X366975Y-38092D01*
G01X367009Y-37971D02*
X366996Y-38029D01*
G01X367012Y-37920D02*
X367009Y-37971D01*
G01X367006Y-37878D02*
X367012Y-37920D01*
G01X366993Y-37844D02*
X367006Y-37878D01*
G01X366977Y-37819D02*
X366993Y-37844D01*
G01X366963Y-37804D02*
X366977Y-37819D01*
G01X366957Y-37799D02*
X366963Y-37804D01*
G01X380834Y-38609D02*
X380829Y-38615D01*
G01X380850Y-38589D02*
X380834Y-38609D01*
G01X380876Y-38556D02*
X380850Y-38589D01*
G01X380910Y-38512D02*
X380876Y-38556D01*
G01X380950Y-38457D02*
X380910Y-38512D01*
G01X380995Y-38389D02*
X380950Y-38457D01*
G01X381042Y-38312D02*
X380995Y-38389D01*
G01X381085Y-38233D02*
X381042Y-38312D01*
G01X381121Y-38160D02*
X381085Y-38233D01*
G01X381149Y-38092D02*
X381121Y-38160D01*
G01X381169Y-38029D02*
X381149Y-38092D01*
G01X381182Y-37971D02*
X381169Y-38029D01*
G01X381185Y-37920D02*
X381182Y-37971D01*
G01X381180Y-37878D02*
X381185Y-37920D01*
G01X381167Y-37844D02*
X381180Y-37878D01*
G01X381150Y-37819D02*
X381167Y-37844D01*
G01X381136Y-37804D02*
X381150Y-37819D01*
G01X381131Y-37799D02*
X381136Y-37804D01*
G01X342210Y-37808D02*
X342215Y-37803D01*
G01X342196Y-37823D02*
X342210Y-37808D01*
G01X342181Y-37848D02*
X342196Y-37823D01*
G01X342168Y-37881D02*
X342181Y-37848D01*
G01X342162Y-37923D02*
X342168Y-37881D01*
G01X342166Y-37973D02*
X342162Y-37923D01*
G01X342178Y-38030D02*
X342166Y-37973D01*
G01X342198Y-38092D02*
X342178Y-38030D01*
G01X342226Y-38160D02*
X342198Y-38092D01*
G01X342262Y-38235D02*
X342226Y-38160D01*
G01X342306Y-38315D02*
X342262Y-38235D01*
G01X342352Y-38390D02*
X342306Y-38315D01*
G01X342396Y-38455D02*
X342352Y-38390D01*
G01X342435Y-38510D02*
X342396Y-38455D01*
G01X342468Y-38553D02*
X342435Y-38510D01*
G01X342493Y-38586D02*
X342468Y-38553D01*
G01X342509Y-38605D02*
X342493Y-38586D01*
G01X342514Y-38611D02*
X342509Y-38605D01*
G01X356383Y-37808D02*
X356389Y-37803D01*
G01X356370Y-37823D02*
X356383Y-37808D01*
G01X356354Y-37848D02*
X356370Y-37823D01*
G01X356341Y-37881D02*
X356354Y-37848D01*
G01X356336Y-37923D02*
X356341Y-37881D01*
G01X356339Y-37973D02*
X356336Y-37923D01*
G01X356351Y-38030D02*
X356339Y-37973D01*
G01X356371Y-38092D02*
X356351Y-38030D01*
G01X356399Y-38160D02*
X356371Y-38092D01*
G01X356435Y-38235D02*
X356399Y-38160D01*
G01X356479Y-38315D02*
X356435Y-38235D01*
G01X356525Y-38390D02*
X356479Y-38315D01*
G01X356569Y-38455D02*
X356525Y-38390D01*
G01X356608Y-38510D02*
X356569Y-38455D01*
G01X356641Y-38553D02*
X356608Y-38510D01*
G01X356667Y-38586D02*
X356641Y-38553D01*
G01X356683Y-38605D02*
X356667Y-38586D01*
G01X356688Y-38611D02*
X356683Y-38605D01*
G01X370556Y-37808D02*
X370562Y-37803D01*
G01X370543Y-37823D02*
X370556Y-37808D01*
G01X370527Y-37848D02*
X370543Y-37823D01*
G01X370514Y-37881D02*
X370527Y-37848D01*
G01X370509Y-37923D02*
X370514Y-37881D01*
G01X370512Y-37973D02*
X370509Y-37923D01*
G01X370524Y-38030D02*
X370512Y-37973D01*
G01X370545Y-38092D02*
X370524Y-38030D01*
G01X370572Y-38160D02*
X370545Y-38092D01*
G01X370609Y-38235D02*
X370572Y-38160D01*
G01X370652Y-38315D02*
X370609Y-38235D01*
G01X370699Y-38390D02*
X370652Y-38315D01*
G01X370742Y-38455D02*
X370699Y-38390D01*
G01X370781Y-38510D02*
X370742Y-38455D01*
G01X370814Y-38553D02*
X370781Y-38510D01*
G01X370840Y-38586D02*
X370814Y-38553D01*
G01X370856Y-38605D02*
X370840Y-38586D01*
G01X370861Y-38611D02*
X370856Y-38605D01*
G01X384730Y-37808D02*
X384735Y-37803D01*
G01X384716Y-37823D02*
X384730Y-37808D01*
G01X384700Y-37848D02*
X384716Y-37823D01*
G01X384688Y-37881D02*
X384700Y-37848D01*
G01X384682Y-37923D02*
X384688Y-37881D01*
G01X384685Y-37973D02*
X384682Y-37923D01*
G01X384698Y-38030D02*
X384685Y-37973D01*
G01X384718Y-38092D02*
X384698Y-38030D01*
G01X384746Y-38160D02*
X384718Y-38092D01*
G01X384782Y-38235D02*
X384746Y-38160D01*
G01X384826Y-38315D02*
X384782Y-38235D01*
G01X384872Y-38390D02*
X384826Y-38315D01*
G01X384915Y-38455D02*
X384872Y-38390D01*
G01X384954Y-38510D02*
X384915Y-38455D01*
G01X384988Y-38553D02*
X384954Y-38510D01*
G01X385013Y-38586D02*
X384988Y-38553D01*
G01X385029Y-38605D02*
X385013Y-38586D01*
G01X385034Y-38611D02*
X385029Y-38605D01*
G01X337920Y-39375D02*
X337737Y-39494D01*
G01X338044Y-39251D02*
X337920Y-39375D01*
G01X338123Y-39119D02*
X338044Y-39251D01*
G01X352093Y-39375D02*
X351910Y-39494D01*
G01X352217Y-39251D02*
X352093Y-39375D01*
G01X352296Y-39119D02*
X352217Y-39251D01*
G01X336680Y-39666D02*
X336576Y-39739D01*
G01X336747Y-39558D02*
X336680Y-39666D01*
G01X350853D02*
X350749Y-39739D01*
G01X350920Y-39558D02*
X350853Y-39666D01*
G01X366266Y-39375D02*
X366083Y-39494D01*
G01X366390Y-39251D02*
X366266Y-39375D01*
G01X366469Y-39119D02*
X366390Y-39251D01*
G01X380440Y-39375D02*
X380256Y-39494D01*
G01X380564Y-39251D02*
X380440Y-39375D01*
G01X380643Y-39119D02*
X380564Y-39251D01*
G01X365026Y-39666D02*
X364922Y-39739D01*
G01X365093Y-39558D02*
X365026Y-39666D01*
G01X379200D02*
X379096Y-39739D01*
G01X379267Y-39558D02*
X379200Y-39666D01*
G01X336875Y-39706D02*
X336408Y-39764D01*
G01X337285Y-39559D02*
X336875Y-39706D01*
G01X337657Y-39339D02*
X337285Y-39559D01*
G01X351048Y-39706D02*
X350581Y-39764D01*
G01X351458Y-39559D02*
X351048Y-39706D01*
G01X351830Y-39339D02*
X351458Y-39559D01*
G01X365222Y-39706D02*
X364754Y-39764D01*
G01X365631Y-39559D02*
X365222Y-39706D01*
G01X366003Y-39339D02*
X365631Y-39559D01*
G01X379395Y-39706D02*
X378927Y-39764D01*
G01X379804Y-39559D02*
X379395Y-39706D01*
G01X380176Y-39339D02*
X379804Y-39559D01*
G01X337684Y-39519D02*
X337657Y-39531D01*
G01X337711Y-39507D02*
X337684Y-39519D01*
G01X337737Y-39494D02*
X337711Y-39507D01*
G01X351858Y-39519D02*
X351830Y-39531D01*
G01X351884Y-39507D02*
X351858Y-39519D01*
G01X351910Y-39494D02*
X351884Y-39507D01*
G01X366031Y-39519D02*
X366003Y-39531D01*
G01X366058Y-39507D02*
X366031Y-39519D01*
G01X366083Y-39494D02*
X366058Y-39507D01*
G01X380204Y-39519D02*
X380176Y-39531D01*
G01X380231Y-39507D02*
X380204Y-39519D01*
G01X380256Y-39494D02*
X380231Y-39507D01*
G01X336767Y-39549D02*
X336747Y-39558D01*
G01X336821Y-39525D02*
X336767Y-39549D01*
G01X336901Y-39490D02*
X336821Y-39525D01*
G01X336997Y-39449D02*
X336901Y-39490D01*
G01X350940Y-39549D02*
X350920Y-39558D01*
G01X350994Y-39525D02*
X350940Y-39549D01*
G01X351075Y-39490D02*
X350994Y-39525D01*
G01X351170Y-39449D02*
X351075Y-39490D01*
G01X365113Y-39549D02*
X365093Y-39558D01*
G01X365167Y-39525D02*
X365113Y-39549D01*
G01X365248Y-39490D02*
X365167Y-39525D01*
G01X365344Y-39449D02*
X365248Y-39490D01*
G01X379286Y-39549D02*
X379267Y-39558D01*
G01X379340Y-39525D02*
X379286Y-39549D01*
G01X379421Y-39490D02*
X379340Y-39525D01*
G01X379517Y-39449D02*
X379421Y-39490D01*
G01X386637Y-39558D02*
G03X386933Y-39764I296J110D01*
G01X378971D02*
G03X379267Y-39558I0J316D01*
G01X385708Y-35626D02*
G03X385806Y-36172I1575J1D01*
G01X380099D02*
G03X380196Y-35626I-1478J544D01*
G01X385314D02*
G03X385436Y-36308I1969J0D01*
G01X380468D02*
G03X380590Y-35626I-1847J682D01*
G01X385117D02*
G03X385252Y-36377I2166J2D01*
G01X380652D02*
G03X380787Y-35626I-2031J753D01*
G01X380174Y-39325D02*
G03X380829Y-38615I-1372J1923D01*
G01X381131Y-37799D02*
G03X381164Y-37402I-2329J393D01*
G01X384701D02*
G03X384735Y-37803I2362J-2D01*
G01X385034Y-38611D02*
G03X387063Y-39764I2029J1209D01*
G01X371535Y-35626D02*
G03X371632Y-36172I1575J-2D01*
G01X371141Y-35626D02*
G03X371263Y-36308I1969J0D01*
G01X370944Y-35626D02*
G03X371078Y-36377I2166J-1D01*
G01X370528Y-37402D02*
G03X370562Y-37803I2362J-2D01*
G01X370861Y-38611D02*
G03X372890Y-39764I2029J1209D01*
G01X372464Y-39558D02*
G03X372760Y-39764I296J110D01*
G01X365925Y-36172D02*
G03X366023Y-35626I-1477J547D01*
G01X357362D02*
G03X357459Y-36172I1574J-2D01*
G01X356968Y-35626D02*
G03X357090Y-36308I1967J0D01*
G01X366295D02*
G03X366417Y-35626I-1847J682D01*
G01X356771D02*
G03X356905Y-36377I2165J-1D01*
G01X366479D02*
G03X366613Y-35626I-2031J750D01*
G01X356354Y-37402D02*
G03X356389Y-37803I2363J4D01*
G01X356688Y-38611D02*
G03X358717Y-39764I2029J1209D01*
G01X366001Y-39325D02*
G03X366656Y-38615I-1372J1923D01*
G01X366958Y-37797D02*
G03X366991Y-37402I-2329J393D01*
G01X364798Y-39764D02*
G03X365093Y-39558I0J314D01*
G01X358291D02*
G03X358586Y-39764I295J108D01*
G01X350625D02*
G03X350920Y-39558I0J314D01*
G01X344118D02*
G03X344413Y-39764I295J108D01*
G01X336452D02*
G03X336747Y-39558I0J314D01*
G01X343188Y-35626D02*
G03X343286Y-36172I1575J1D01*
G01X337579D02*
G03X337676Y-35626I-1477J544D01*
G01X351752Y-36172D02*
G03X351850Y-35626I-1477J547D01*
G01X352121Y-36308D02*
G03X352243Y-35626I-1845J682D01*
G01X342795D02*
G03X342917Y-36308I1967J0D01*
G01X337948D02*
G03X338070Y-35626I-1845J682D01*
G01X352306Y-36377D02*
G03X352440Y-35626I-2031J750D01*
G01X338133Y-36377D02*
G03X338267Y-35626I-2031J750D01*
G01X342598D02*
G03X342732Y-36377I2165J-1D01*
G01X351827Y-39325D02*
G03X352483Y-38615I-1370J1924D01*
G01X352785Y-37797D02*
G03X352818Y-37402I-2329J393D01*
G01X337654Y-39325D02*
G03X338310Y-38615I-1371J1924D01*
G01X338611Y-37799D02*
G03X338645Y-37402I-2329J399D01*
G01X342181D02*
G03X342215Y-37803I2362J-2D01*
G01X342514Y-38611D02*
G03X344543Y-39764I2029J1209D01*
G01X386637Y-39558D02*
X387017Y-39449D01*
G01X372464Y-39558D02*
X372844Y-39449D01*
G01X358291Y-39558D02*
X358670Y-39449D01*
G01X344118Y-39558D02*
X344497Y-39449D01*
G01X385252Y-36377D02*
X385806Y-36172D01*
G01X371078Y-36377D02*
X371632Y-36172D01*
G01X356905Y-36377D02*
X357459Y-36172D01*
G01X342732Y-36377D02*
X343286Y-36172D01*
G01X381164Y-37708D02*
X380643Y-39119D01*
G01X380771Y-37637D02*
X380176Y-39245D01*
G01X380652Y-36377D02*
X379517Y-39449D01*
G01X380468Y-36308D02*
X379267Y-39558D01*
G01X378887Y-39449D02*
X380099Y-36172D01*
G01X366469Y-39119D02*
X366991Y-37708D01*
G01X366597Y-37637D02*
X366003Y-39245D01*
G01X366479Y-36377D02*
X365344Y-39449D01*
G01X366295Y-36308D02*
X365093Y-39558D01*
G01X364714Y-39449D02*
X365925Y-36172D01*
G01X352296Y-39119D02*
X352818Y-37708D01*
G01X352424Y-37637D02*
X351830Y-39245D01*
G01X352306Y-36377D02*
X351170Y-39449D01*
G01X352121Y-36308D02*
X350920Y-39558D01*
G01X350541Y-39449D02*
X351752Y-36172D01*
G01X338645Y-37708D02*
X338123Y-39119D01*
G01X338251Y-37637D02*
X337657Y-39245D01*
G01X338133Y-36377D02*
X336997Y-39449D01*
G01X337948Y-36308D02*
X336747Y-39558D01*
G01X336368Y-39449D02*
X337579Y-36172D01*
G01X386387Y-39449D02*
Y-39764D01*
G01X385708Y-35626D02*
Y-7499D01*
G01X385314D02*
Y-35626D01*
G01X385117Y-7499D02*
Y-35626D01*
G01X385095Y-7577D02*
Y-37640D01*
G01X384701Y-7577D02*
Y-37402D01*
G01X384307Y-7577D02*
Y-39764D01*
G01X381558Y-7577D02*
Y-39764D01*
G01X381164Y-7577D02*
Y-37708D01*
G01X380787Y-35626D02*
Y-7499D01*
G01X380771Y-37637D02*
Y-7577D01*
G01X380590Y-7499D02*
Y-35626D01*
G01X380196Y-7499D02*
Y-35626D01*
G01X380176Y-31890D02*
Y-39531D01*
G01X379517Y-39449D02*
Y-39764D01*
G01X378887Y-39449D02*
Y-39764D01*
G01X377814Y-31890D02*
Y-39764D01*
G01X377454Y-31890D02*
Y-39764D01*
G01X372926Y-31890D02*
Y-39764D01*
G01X372844Y-39449D02*
Y-39764D01*
G01X372214Y-39449D02*
Y-39764D01*
G01X371535Y-35626D02*
Y-7499D01*
G01X371141D02*
Y-35626D01*
G01X370944Y-7499D02*
Y-35626D01*
G01X370921Y-7577D02*
Y-37640D01*
G01X370528Y-7577D02*
Y-37402D01*
G01X370134Y-39764D02*
Y-7577D01*
G01X367385D02*
Y-39764D01*
G01X366991Y-37708D02*
Y-7577D01*
G01X366613Y-35626D02*
Y-7499D01*
G01X366597Y-37637D02*
Y-7577D01*
G01X366417Y-7499D02*
Y-35626D01*
G01X366023Y-7499D02*
Y-35626D01*
G01X366003Y-39531D02*
Y-31890D01*
G01X365344Y-39449D02*
Y-39764D01*
G01X364714Y-39449D02*
Y-39764D01*
G01X363641Y-31890D02*
Y-39764D01*
G01X363281Y-31890D02*
Y-39764D01*
G01X358753Y-31890D02*
Y-39764D01*
G01X358670Y-39449D02*
Y-39764D01*
G01X358041Y-39449D02*
Y-39764D01*
G01X357362Y-35626D02*
Y-7499D01*
G01X356968D02*
Y-35626D01*
G01X356771Y-7499D02*
Y-35626D01*
G01X356748Y-7577D02*
Y-37640D01*
G01X356354Y-7577D02*
Y-37402D01*
G01X355961Y-39764D02*
Y-7577D01*
G01X353212D02*
Y-39764D01*
G01X352818Y-37708D02*
Y-7577D01*
G01X352440Y-35626D02*
Y-7499D01*
G01X352424Y-37637D02*
Y-7577D01*
G01X352243Y-7499D02*
Y-35626D01*
G01X351850Y-7499D02*
Y-35626D01*
G01X351830Y-39531D02*
Y-31890D01*
G01X351170Y-39449D02*
Y-39764D01*
G01X350541Y-39449D02*
Y-39764D01*
G01X349468Y-31890D02*
Y-39764D01*
G01X349108Y-31890D02*
Y-39764D01*
G01X344580Y-31890D02*
Y-39764D01*
G01X344497D02*
Y-39449D01*
G01X343868D02*
Y-39764D01*
G01X343188Y-35626D02*
Y-7499D01*
G01X342795Y-35626D02*
Y-7499D01*
G01X342598D02*
Y-35626D01*
G01X342575Y-7577D02*
Y-37640D01*
G01X342181Y-7577D02*
Y-37402D01*
G01X341788Y-7577D02*
Y-39764D01*
G01X339038Y-7577D02*
Y-39764D01*
G01X338645Y-7577D02*
Y-37708D01*
G01X338267Y-35626D02*
Y-7499D01*
G01X338251Y-37637D02*
Y-7577D01*
G01X338070Y-7499D02*
Y-35626D01*
G01X337676Y-7499D02*
Y-35626D01*
G01X337657Y-39531D02*
Y-31890D01*
G01X336997Y-39449D02*
Y-39764D01*
G01X336368Y-39449D02*
Y-39764D01*
G01X336214Y-1181D02*
Y-39764D01*
G01X335886Y62697D02*
Y-12828D01*
G01X385806Y-36172D02*
X387017Y-39449D01*
G01X386637Y-39558D02*
X385436Y-36308D01*
G01X386387Y-39449D02*
X385252Y-36377D01*
G01X385727Y-39350D02*
X385095Y-37640D01*
G01X384735Y-37803D02*
X385034Y-38611D01*
G01X371632Y-36172D02*
X372844Y-39449D01*
G01X372464Y-39558D02*
X371263Y-36308D01*
G01X372214Y-39449D02*
X371078Y-36377D01*
G01X371553Y-39350D02*
X370921Y-37640D01*
G01X370562Y-37803D02*
X370861Y-38611D01*
G01X357459Y-36172D02*
X358670Y-39449D01*
G01X358291Y-39558D02*
X357090Y-36308D01*
G01X358041Y-39449D02*
X356905Y-36377D01*
G01X357380Y-39350D02*
X356748Y-37640D01*
G01X356389Y-37803D02*
X356688Y-38611D01*
G01X343286Y-36172D02*
X344497Y-39449D01*
G01X342917Y-36308D02*
X344118Y-39558D01*
G01X343868Y-39449D02*
X342732Y-36377D01*
G01X343207Y-39350D02*
X342575Y-37640D01*
G01X342215Y-37803D02*
X342514Y-38611D01*
G01X386704Y-39666D02*
X386637Y-39558D01*
G01X372531Y-39666D02*
X372464Y-39558D01*
G01X358358Y-39666D02*
X358291Y-39558D01*
G01X344185Y-39666D02*
X344118Y-39558D01*
G01X386387Y-39449D02*
X386637Y-39558D01*
G01X372214Y-39449D02*
X372464Y-39558D01*
G01X358041Y-39449D02*
X358291Y-39558D01*
G01X343868Y-39449D02*
X344118Y-39558D01*
G01X380099Y-36172D02*
X380652Y-36377D01*
G01X365925Y-36172D02*
X366479Y-36377D01*
G01X351752Y-36172D02*
X352306Y-36377D01*
G01X380176Y-39471D02*
X380256Y-39494D01*
G01X378887Y-39449D02*
X379267Y-39558D01*
G01X366003Y-39471D02*
X366083Y-39494D01*
G01X364714Y-39449D02*
X365093Y-39558D01*
G01X381164Y-37708D02*
X380771Y-37637D01*
G01X366991Y-37708D02*
X366597Y-37637D01*
G01X352818Y-37708D02*
X352424Y-37637D01*
G01X336214Y-12828D02*
X335886D01*
G01X377814Y-31890D02*
X380176D01*
G01X363641D02*
X366003D01*
G01X349468D02*
X351830D01*
G01X337657D02*
X336214D01*
G01X349108D02*
X344580D01*
G01X363281D02*
X358753D01*
G01X377454D02*
X372926D01*
G01X385117Y-35626D02*
X385708D01*
G01X370944D02*
X371535D01*
G01X356771D02*
X357362D01*
G01X342598D02*
X343188D01*
G01X337676D02*
X338267D01*
G01X352440D02*
X351850D01*
G01X366613D02*
X366023D01*
G01X380787D02*
X380196D01*
G01X381164Y-37402D02*
X384701D01*
G01X366991D02*
X370528D01*
G01X352818D02*
X356354D01*
G01X338645D02*
X342181D01*
G01X372926Y-39276D02*
X377454D01*
G01X358753D02*
X363281D01*
G01X344580D02*
X349108D01*
G01X337657D02*
X336214D01*
G01X351830D02*
X349468D01*
G01X366003D02*
X363641D01*
G01X380176D02*
X377814D01*
G01X379517Y-39449D02*
X392513D01*
G01X365344D02*
X378887D01*
G01X351170D02*
X364714D01*
G01X336997D02*
X350541D01*
G01X336214D02*
X336368D01*
G01X336214Y-39764D02*
X392513D01*
G01X342575Y-37640D02*
X342201Y-37706D01*
G01X356374D02*
X356748Y-37640D01*
G01X370547Y-37706D02*
X370921Y-37640D01*
G01X384721Y-37706D02*
X385095Y-37640D01*
G01X336452Y-39764D02*
X336575Y-39738D01*
G01X350625Y-39764D02*
X350749Y-39738D01*
G01X364798Y-39764D02*
X364922Y-39738D01*
G01X378971Y-39764D02*
X379095Y-39738D01*
G01X337579Y-36172D02*
X338133Y-36377D01*
G01X351830Y-39471D02*
X351910Y-39494D01*
G01X350541Y-39449D02*
X350920Y-39558D01*
G01X337657Y-39471D02*
X337737Y-39494D01*
G01X336368Y-39449D02*
X336747Y-39558D01*
G01X338645Y-37708D02*
X338251Y-37637D01*
G01X597707Y-7874D02*
X326770D01*
G01X339018Y-7354D02*
X339071Y-7480D01*
G01X338977Y-7224D02*
X339018Y-7354D01*
G01X338950Y-7124D02*
X338977Y-7224D01*
G01X338940Y-7087D02*
X338950Y-7124D01*
G01X353191Y-7354D02*
X353244Y-7480D01*
G01X353150Y-7224D02*
X353191Y-7354D01*
G01X353123Y-7124D02*
X353150Y-7224D01*
G01X353114Y-7087D02*
X353123Y-7124D01*
G01X367365Y-7354D02*
X367417Y-7480D01*
G01X367323Y-7224D02*
X367365Y-7354D01*
G01X367296Y-7124D02*
X367323Y-7224D01*
G01X367287Y-7087D02*
X367296Y-7124D01*
G01X353069Y-6892D02*
X353030Y-6693D01*
G01X353101Y-7035D02*
X353069Y-6892D01*
G01X353114Y-7087D02*
X353101Y-7035D01*
G01X367242Y-6892D02*
X367203Y-6693D01*
G01X367274Y-7035D02*
X367242Y-6892D01*
G01X367287Y-7087D02*
X367274Y-7035D01*
G01X338928D02*
X338940Y-7087D01*
G01X338896Y-6890D02*
X338928Y-7035D01*
G01X338857Y-6693D02*
X338896Y-6890D01*
G01X381538Y-7354D02*
X381590Y-7480D01*
G01X381497Y-7224D02*
X381538Y-7354D01*
G01X381470Y-7124D02*
X381497Y-7224D01*
G01X381460Y-7087D02*
X381470Y-7124D01*
G01X381416Y-6892D02*
X381376Y-6693D01*
G01X381448Y-7035D02*
X381416Y-6892D01*
G01X381460Y-7087D02*
X381448Y-7035D01*
G01X341898D02*
X341885Y-7087D01*
G01X341930Y-6890D02*
X341898Y-7035D01*
G01X341969Y-6693D02*
X341930Y-6890D01*
G01X356103Y-6892D02*
X356142Y-6693D01*
G01X356071Y-7034D02*
X356103Y-6892D01*
G01X356059Y-7087D02*
X356071Y-7034D01*
G01X370276Y-6892D02*
X370316Y-6693D01*
G01X370244Y-7034D02*
X370276Y-6892D01*
G01X370232Y-7087D02*
X370244Y-7034D01*
G01X384449Y-6892D02*
X384489Y-6693D01*
G01X384418Y-7034D02*
X384449Y-6892D01*
G01X384405Y-7087D02*
X384418Y-7034D01*
G01X341877Y-7120D02*
X341885Y-7087D01*
G01X341851Y-7214D02*
X341877Y-7120D01*
G01X341810Y-7346D02*
X341851Y-7214D01*
G01X341755Y-7480D02*
X341810Y-7346D01*
G01X356050Y-7120D02*
X356059Y-7087D01*
G01X356025Y-7214D02*
X356050Y-7120D01*
G01X355983Y-7346D02*
X356025Y-7214D01*
G01X355928Y-7480D02*
X355983Y-7346D01*
G01X370223Y-7120D02*
X370232Y-7087D01*
G01X370198Y-7214D02*
X370223Y-7120D01*
G01X370157Y-7346D02*
X370198Y-7214D01*
G01X370102Y-7480D02*
X370157Y-7346D01*
G01X384397Y-7120D02*
X384405Y-7087D01*
G01X384371Y-7214D02*
X384397Y-7120D01*
G01X384330Y-7346D02*
X384371Y-7214D01*
G01X384275Y-7480D02*
X384330Y-7346D01*
G01X390436Y46771D02*
G03I-1968J0D01*
G01X383743Y44055D02*
G03X382759Y45039I-984J0D01*
G01X387090D02*
G03X386106Y44055I0J-984D01*
G01X386932Y36087D02*
G03Y34307I1300J-890D01*
G01X381811Y48819D02*
G03I-709J0D01*
G01X383350Y46771D02*
G03I-1969J0D01*
G01X381811Y43307D02*
G03I-709J0D01*
G01Y38976D02*
G03I-709J0D01*
G01Y34645D02*
G03I-709J0D01*
G01X376657Y44055D02*
G03X375673Y45039I-984J0D01*
G01X380003D02*
G03X379019Y44055I0J-984D01*
G01X382956Y39478D02*
G03X379806I-1575J0D01*
G01X382917Y34307D02*
G03Y36087I-1300J890D01*
G01X379846D02*
G03Y34307I1299J-890D01*
G01X386932Y29000D02*
G03Y27220I1300J-890D01*
G01X381811Y29134D02*
G03I-709J0D01*
G01Y24803D02*
G03I-709J0D01*
G01Y20472D02*
G03I-709J0D01*
G01X382917Y27220D02*
G03Y29000I-1300J890D01*
G01X379846D02*
G03Y27220I1299J-890D01*
G01X381811Y14960D02*
G03I-709J0D01*
G01X384304Y-7577D02*
G03X384272Y-7482I-157J0D01*
G01X381593D02*
G03X381561Y-7577I125J-95D01*
G01X381002Y-7302D02*
G03X380805Y-7499I0J-197D01*
G01X385099D02*
G03X384902Y-7302I-197J0D01*
G01X385296Y-7499D02*
G03X384902Y-7105I-394J0D01*
G01X381002D02*
G03X380608Y-7499I0J-394D01*
G01X381462Y-7089D02*
G03X381167Y-7577I256J-488D01*
G01X384698D02*
G03X384404Y-7089I-552J0D01*
G01X385690Y-7499D02*
G03X384902Y-6711I-788J0D01*
G01X381002D02*
G03X380214Y-7499I0J-788D01*
G01X381378Y-6696D02*
G03X380774Y-7577I341J-881D01*
G01X385091D02*
G03X384488Y-6696I-945J0D01*
G01X374724Y48425D02*
G03I-709J0D01*
G01X367638Y48819D02*
G03I-709J0D01*
G01X376263Y46771D02*
G03I-1968J0D01*
G01X369176D02*
G03I-1968J0D01*
G01X374724Y44094D02*
G03I-709J0D01*
G01X372917Y45039D02*
G03X371932Y44055I0J-985D01*
G01X375869Y39478D02*
G03X372720I-1574J0D01*
G01X374724Y38582D02*
G03I-709J0D01*
G01Y34252D02*
G03I-709J0D01*
G01X375830Y34307D02*
G03Y36087I-1299J890D01*
G01X372759D02*
G03Y34307I1299J-890D01*
G01X367638Y43307D02*
G03I-709J0D01*
G01X369570Y44055D02*
G03X368586Y45039I-984J0D01*
G01X368783Y39478D02*
G03X365633I-1575J0D01*
G01X367638Y38976D02*
G03I-709J0D01*
G01Y34645D02*
G03I-709J0D01*
G01X368743Y34307D02*
G03Y36087I-1299J890D01*
G01X365673D02*
G03Y34307I1299J-890D01*
G01X360551Y48425D02*
G03I-709J0D01*
G01X362090Y46771D02*
G03I-1969J0D01*
G01X360551Y44094D02*
G03I-709J0D01*
G01Y38582D02*
G03I-709J0D01*
G01Y34252D02*
G03I-709J0D01*
G01X358743Y45039D02*
G03X357759Y44055I0J-984D01*
G01X362484D02*
G03X361499Y45039I-984J0D01*
G01X365830D02*
G03X364846Y44055I0J-984D01*
G01X361696Y39478D02*
G03X358547I-1574J0D01*
G01X361657Y34307D02*
G03Y36087I-1299J890D01*
G01X358586D02*
G03Y34307I1299J-890D01*
G01X374724Y29921D02*
G03I-709J0D01*
G01Y24409D02*
G03I-709J0D01*
G01Y20078D02*
G03I-709J0D01*
G01X375830Y27220D02*
G03Y29000I-1299J890D01*
G01X372759D02*
G03Y27220I1299J-890D01*
G01X368743D02*
G03Y29000I-1299J890D01*
G01X374724Y15748D02*
G03I-709J0D01*
G01Y10236D02*
G03I-709J0D01*
G01X367638Y29134D02*
G03I-709J0D01*
G01Y24803D02*
G03I-709J0D01*
G01Y20472D02*
G03I-709J0D01*
G01X360551Y29921D02*
G03I-709J0D01*
G01Y24409D02*
G03I-709J0D01*
G01Y20078D02*
G03I-709J0D01*
G01X365673Y29000D02*
G03Y27220I1299J-890D01*
G01X361657D02*
G03Y29000I-1299J890D01*
G01X358586D02*
G03Y27220I1299J-890D01*
G01X367638Y14960D02*
G03I-709J0D01*
G01X360551Y15748D02*
G03I-709J0D01*
G01Y10236D02*
G03I-709J0D01*
G01X353464Y48819D02*
G03I-708J0D01*
G01X355003Y46771D02*
G03I-1968J0D01*
G01X347917D02*
G03I-1969J0D01*
G01X353464Y43307D02*
G03I-708J0D01*
G01Y38976D02*
G03I-708J0D01*
G01Y34645D02*
G03I-708J0D01*
G01X348310Y44055D02*
G03X347326Y45039I-984J0D01*
G01X351657D02*
G03X350673Y44055I0J-984D01*
G01X355397D02*
G03X354413Y45039I-984J0D01*
G01X347523Y39478D02*
G03X344373I-1575J0D01*
G01X354610D02*
G03X351460I-1575J0D01*
G01X347484Y34307D02*
G03Y36087I-1300J890D01*
G01X354570Y34307D02*
G03Y36087I-1299J890D01*
G01X351499D02*
G03Y34307I1300J-890D01*
G01X346378Y48425D02*
G03I-709J0D01*
G01X339291Y48819D02*
G03I-709J0D01*
G01X340830Y46771D02*
G03I-1968J0D01*
G01X346378Y44094D02*
G03I-709J0D01*
G01X344570Y45039D02*
G03X343586Y44055I0J-984D01*
G01X346378Y38582D02*
G03I-709J0D01*
G01Y34252D02*
G03I-709J0D01*
G01X344413Y36087D02*
G03Y34307I1299J-890D01*
G01X339291Y43307D02*
G03I-709J0D01*
G01X337484Y45039D02*
G03X336499Y44055I0J-985D01*
G01X341224D02*
G03X340239Y45039I-984J0D01*
G01X335860Y42608D02*
G03X337434Y41033I1575J0D01*
G01X340436Y39478D02*
G03X338862Y41053I-1575J0D01*
G01X339291Y38976D02*
G03I-709J0D01*
G01Y34645D02*
G03I-709J0D01*
G01X337326Y36087D02*
G03Y34307I1299J-890D01*
G01X340397D02*
G03Y36087I-1299J890D01*
G01X353464Y29134D02*
G03I-708J0D01*
G01Y24803D02*
G03I-708J0D01*
G01Y20472D02*
G03I-708J0D01*
G01X347484Y27220D02*
G03Y29000I-1300J890D01*
G01X354570Y27220D02*
G03Y29000I-1299J890D01*
G01X351499D02*
G03Y27220I1300J-890D01*
G01X353464Y14960D02*
G03I-708J0D01*
G01X346378Y29921D02*
G03I-709J0D01*
G01X344413Y29000D02*
G03Y27220I1299J-890D01*
G01X346378Y24409D02*
G03I-709J0D01*
G01Y20078D02*
G03I-709J0D01*
G01X339291Y29134D02*
G03I-709J0D01*
G01X337326Y29000D02*
G03Y27220I1299J-890D01*
G01X340397D02*
G03Y29000I-1299J890D01*
G01X339291Y24803D02*
G03I-709J0D01*
G01Y20472D02*
G03I-709J0D01*
G01X339783Y24803D02*
G03I-1201J0D01*
G01X346378Y15748D02*
G03I-709J0D01*
G01Y10236D02*
G03I-709J0D01*
G01X339291Y14960D02*
G03I-709J0D01*
G01X339783D02*
G03I-1201J0D01*
G01X374724Y5905D02*
G03I-709J0D01*
G01X370131Y-7577D02*
G03X370099Y-7482I-157J0D01*
G01X367420D02*
G03X367388Y-7577I125J-95D01*
G01X366828Y-7302D02*
G03X366632Y-7499I0J-196D01*
G01X370926D02*
G03X370729Y-7302I-197J0D01*
G01X371123Y-7499D02*
G03X370729Y-7105I-394J0D01*
G01X366828D02*
G03X366435Y-7499I0J-393D01*
G01X367288Y-7089D02*
G03X366994Y-7577I258J-488D01*
G01X370525D02*
G03X370230Y-7089I-551J0D01*
G01X371517Y-7499D02*
G03X370729Y-6711I-788J0D01*
G01X366828D02*
G03X366041Y-7499I0J-787D01*
G01X367204Y-6696D02*
G03X366600Y-7577I341J-881D01*
G01X370918D02*
G03X370314Y-6696I-945J0D01*
G01X360551Y5905D02*
G03I-709J0D01*
G01X355958Y-7577D02*
G03X355926Y-7482I-157J0D01*
G01X356753Y-7499D02*
G03X356556Y-7302I-197J0D01*
G01X356950Y-7499D02*
G03X356556Y-7105I-394J0D01*
G01X356351Y-7577D02*
G03X356057Y-7089I-552J0D01*
G01X357343Y-7499D02*
G03X356556Y-6711I-788J0D01*
G01X356745Y-7577D02*
G03X356141Y-6696I-945J0D01*
G01X353246Y-7482D02*
G03X353215Y-7577I126J-94D01*
G01X352655Y-7302D02*
G03X352458Y-7499I0J-197D01*
G01X352655Y-7105D02*
G03X352262Y-7499I0J-393D01*
G01X353115Y-7089D02*
G03X352821Y-7577I258J-488D01*
G01X352655Y-6711D02*
G03X351868Y-7499I0J-787D01*
G01X353031Y-6696D02*
G03X352427Y-7577I341J-881D01*
G01X346378Y5905D02*
G03I-709J0D01*
G01X341784Y-7577D02*
G03X341753Y-7482I-157J1D01*
G01X339073D02*
G03X339041Y-7577I125J-95D01*
G01X338482Y-7302D02*
G03X338285Y-7499I0J-197D01*
G01X342580D02*
G03X342383Y-7302I-197J0D01*
G01X342776Y-7499D02*
G03X342383Y-7105I-394J0D01*
G01X338482D02*
G03X338088Y-7499I0J-394D01*
G01X342178Y-7577D02*
G03X341884Y-7089I-552J0D01*
G01X338942D02*
G03X338648Y-7577I258J-488D01*
G01X343170Y-7499D02*
G03X342383Y-6711I-788J0D01*
G01X338482D02*
G03X337695Y-7499I0J-787D01*
G01X338858Y-6696D02*
G03X338254Y-7577I341J-881D01*
G01X342572D02*
G03X341968Y-6696I-945J0D01*
G01X337556Y12736D02*
X337605Y12752D01*
G01X337879Y22535D02*
X337928Y22552D01*
G01X342111Y22133D02*
X342046Y22100D01*
G01X340569Y22133D02*
X340504Y22100D01*
G01X340126Y22820D02*
X340192Y22853D01*
G01X342079Y22234D02*
X342029Y22200D01*
G01X340487D02*
X340537Y22234D01*
G01X340208Y22753D02*
X340159Y22719D01*
G01X337688Y12702D02*
X337622Y12652D01*
G01X338010Y22502D02*
X337945Y22451D01*
G01X337605Y12752D02*
X337638Y12786D01*
G01X342177Y22200D02*
X342111Y22133D01*
G01X340635Y22200D02*
X340569Y22133D01*
G01X340061Y22753D02*
X340126Y22820D01*
G01X337928Y22552D02*
X337961Y22585D01*
G01X340575Y12937D02*
X340476Y12819D01*
G01Y12953D02*
X340575Y13071D01*
G01X342456Y22736D02*
X342357Y22619D01*
G01Y22753D02*
X342456Y22870D01*
G01X337737Y12769D02*
X337688Y12702D01*
G01X338060Y22569D02*
X338010Y22502D01*
G01X386903Y25730D02*
X385515Y23327D01*
G01X379816Y25730D02*
X378428Y23327D01*
G01X387720Y39921D02*
X386932Y38557D01*
G01X372730Y25730D02*
X371342Y23327D01*
G01X380633Y39921D02*
X379846Y38557D01*
G01X365643Y25730D02*
X364255Y23327D01*
G01X373547Y39921D02*
X372759Y38557D01*
G01X342111Y22284D02*
X342079Y22234D01*
G01X340159Y22719D02*
X340126Y22669D01*
G01X358556Y25730D02*
X357169Y23327D01*
G01X366460Y39921D02*
X365673Y38557D01*
G01X351470Y25730D02*
X350082Y23327D01*
G01X359373Y39921D02*
X358586Y38557D01*
G01X344383Y25730D02*
X342995Y23327D01*
G01X352287Y39921D02*
X351499Y38557D01*
G01X345200Y39921D02*
X344413Y38557D01*
G01X338113Y39921D02*
X337326Y38557D01*
G01X342210Y22267D02*
X342177Y22200D01*
G01X340028Y22686D02*
X340061Y22753D01*
G01X339689Y12283D02*
X339951Y13071D01*
G01X339853Y12484D02*
X339787Y12283D01*
G01X339869Y12551D02*
X340017Y13004D01*
G01X337753Y12819D02*
X337737Y12769D01*
G01X337638Y12786D02*
X337655Y12836D01*
G01X340537Y22234D02*
X340553Y22284D01*
G01X338076Y22619D02*
X338060Y22569D01*
G01X337961Y22585D02*
X337978Y22636D01*
G01X342128Y22351D02*
X342111Y22284D01*
G01X340651Y22267D02*
X340635Y22200D01*
G01X340126Y22669D02*
X340110Y22602D01*
G01X342226Y22351D02*
X342210Y22267D01*
G01X340012Y22602D02*
X340028Y22686D01*
G01X386106Y44055D02*
Y22204D01*
G01X384902Y-7284D02*
Y-6693D01*
G01X383743Y44055D02*
Y22204D01*
G01X382946Y36042D02*
Y39478D01*
G01Y28955D02*
Y34351D01*
G01Y25730D02*
Y27265D01*
G01X382917Y27220D02*
Y22204D01*
G01Y34307D02*
Y29000D01*
G01Y38557D02*
Y36087D01*
G01X381002Y-7284D02*
Y-6693D01*
G01X379846Y36087D02*
Y38557D01*
G01Y29000D02*
Y34307D01*
G01Y22204D02*
Y27220D01*
G01X379816Y27265D02*
Y25730D01*
G01Y34351D02*
Y28955D01*
G01Y39478D02*
Y36042D01*
G01X379019Y44055D02*
Y22204D01*
G01X376657Y44055D02*
Y22204D01*
G01X375860Y36042D02*
Y39478D01*
G01Y28955D02*
Y34351D01*
G01Y25730D02*
Y27265D01*
G01X375830Y27220D02*
Y22204D01*
G01Y34307D02*
Y29000D01*
G01Y38557D02*
Y36087D01*
G01X372759D02*
Y38557D01*
G01Y29000D02*
Y34307D01*
G01Y22204D02*
Y27220D01*
G01X372730Y27265D02*
Y25730D01*
G01Y34351D02*
Y28955D01*
G01Y39478D02*
Y36042D01*
G01X371932Y44055D02*
Y22204D01*
G01X370729Y-7284D02*
Y-6693D01*
G01X369570Y44055D02*
Y22204D01*
G01X368773Y36042D02*
Y39478D01*
G01Y28955D02*
Y34351D01*
G01Y25730D02*
Y27265D01*
G01X368743Y27220D02*
Y22204D01*
G01Y34307D02*
Y29000D01*
G01Y38557D02*
Y36087D01*
G01X366828Y-7284D02*
Y-6693D01*
G01X365673Y36087D02*
Y38557D01*
G01Y29000D02*
Y34307D01*
G01Y22204D02*
Y27220D01*
G01X365643Y27265D02*
Y25730D01*
G01Y34351D02*
Y28955D01*
G01Y39478D02*
Y36042D01*
G01X364846Y44055D02*
Y22204D01*
G01X362484Y44055D02*
Y22204D01*
G01X361686Y36042D02*
Y39478D01*
G01Y28955D02*
Y34351D01*
G01Y25730D02*
Y27265D01*
G01X361657Y27220D02*
Y22204D01*
G01Y34307D02*
Y29000D01*
G01Y38557D02*
Y36087D01*
G01X358586D02*
Y38557D01*
G01Y29000D02*
Y34307D01*
G01Y22204D02*
Y27220D01*
G01X358556Y27265D02*
Y25730D01*
G01Y34351D02*
Y28955D01*
G01Y39478D02*
Y36042D01*
G01X357759Y44055D02*
Y22204D01*
G01X356556Y-7284D02*
Y-6693D01*
G01X355397Y44055D02*
Y22204D01*
G01X354600Y36042D02*
Y39478D01*
G01Y28955D02*
Y34351D01*
G01Y25730D02*
Y27265D01*
G01X354570Y27220D02*
Y22204D01*
G01Y34307D02*
Y29000D01*
G01Y38557D02*
Y36087D01*
G01X352655Y-7284D02*
Y-6693D01*
G01X351499Y36087D02*
Y38557D01*
G01Y29000D02*
Y34307D01*
G01Y22204D02*
Y27220D01*
G01X351470Y27265D02*
Y25730D01*
G01Y34351D02*
Y28955D01*
G01Y39478D02*
Y36042D01*
G01X350673Y44055D02*
Y22204D01*
G01X348310D02*
Y44055D01*
G01X347513Y36042D02*
Y39478D01*
G01Y28955D02*
Y34351D01*
G01Y25730D02*
Y27265D01*
G01X347484Y27220D02*
Y22204D01*
G01Y34307D02*
Y29000D01*
G01Y38557D02*
Y36087D01*
G01X344413D02*
Y38557D01*
G01Y29000D02*
Y34307D01*
G01Y22204D02*
Y27220D01*
G01X344383Y27265D02*
Y25730D01*
G01Y34351D02*
Y28955D01*
G01Y39478D02*
Y36042D01*
G01X343586Y44055D02*
Y22204D01*
G01X342554Y22870D02*
Y22083D01*
G01X342456D02*
Y22736D01*
G01X342383Y-7284D02*
Y-6693D01*
G01X342357Y22619D02*
Y22753D01*
G01X342226Y22602D02*
Y22351D01*
G01X342128Y22602D02*
Y22351D01*
G01X341668Y22183D02*
Y22770D01*
G01X341570Y22083D02*
Y22870D01*
G01X341439D02*
Y22083D01*
G01X341340Y22200D02*
Y22870D01*
G01X341224Y22204D02*
Y44055D01*
G01X340881Y22770D02*
Y22083D01*
G01X340783D02*
Y22870D01*
G01X340673Y13071D02*
Y12283D01*
G01X340651Y22518D02*
Y22267D01*
G01X340575Y12283D02*
Y12937D01*
G01X340553Y22284D02*
Y22418D01*
G01X340476Y12819D02*
Y12953D01*
G01X340426Y36042D02*
Y39478D01*
G01Y28955D02*
Y34351D01*
G01Y25730D02*
Y27265D01*
G01X340405Y22418D02*
Y22518D01*
G01X340397Y27220D02*
Y22204D01*
G01Y34307D02*
Y29000D01*
G01Y38557D02*
Y36087D01*
G01X340110Y22602D02*
Y22351D01*
G01X340012D02*
Y22602D01*
G01X339093Y22870D02*
Y22083D01*
G01X338995Y22200D02*
Y22870D01*
G01X338770Y13071D02*
Y12283D01*
G01X338672Y12400D02*
Y13071D01*
G01X338535Y22770D02*
Y22083D01*
G01X338482Y-7284D02*
Y-6693D01*
G01X338437Y22083D02*
Y22870D01*
G01X338306D02*
Y22083D01*
G01X338212Y12970D02*
Y12283D01*
G01X338207Y22083D02*
Y22870D01*
G01X338114Y12283D02*
Y13071D01*
G01X338076Y22686D02*
Y22619D01*
G01X337983Y13071D02*
Y12283D01*
G01X337978Y22636D02*
Y22686D01*
G01X337884Y12283D02*
Y13071D01*
G01X337753Y12886D02*
Y12819D01*
G01X337655Y12836D02*
Y12886D01*
G01X337567Y22786D02*
Y22535D01*
G01Y22435D02*
Y22083D01*
G01X337469D02*
Y22870D01*
G01X337326Y36087D02*
Y38557D01*
G01Y29000D02*
Y34307D01*
G01Y22204D02*
Y27220D01*
G01X337245Y12987D02*
Y12736D01*
G01Y12635D02*
Y12283D01*
G01X337146D02*
Y13071D01*
G01X336499Y44055D02*
Y22204D01*
G01X335869Y42608D02*
Y60138D01*
G01X342210Y22686D02*
X342226Y22602D01*
G01X340635Y22753D02*
X340651Y22669D01*
G01X340028Y22267D02*
X340012Y22351D01*
G01X342111Y22669D02*
X342128Y22602D01*
G01X340110Y22351D02*
X340126Y22284D01*
G01X340553Y22669D02*
X340537Y22719D01*
G01X338060Y22736D02*
X338076Y22686D01*
G01X337978D02*
X337961Y22736D01*
G01X340017Y13004D02*
X340165Y12551D01*
G01X340247Y12283D02*
X340181Y12484D01*
G01X337737Y12937D02*
X337753Y12886D01*
G01X337655D02*
X337638Y12937D01*
G01X340083Y13071D02*
X340345Y12283D01*
G01X382129Y39921D02*
X382917Y38557D01*
G01X375043Y39921D02*
X375830Y38557D01*
G01X384334Y23327D02*
X382946Y25730D01*
G01X367956Y39921D02*
X368743Y38557D01*
G01X377247Y23327D02*
X375860Y25730D01*
G01X360869Y39921D02*
X361657Y38557D01*
G01X370161Y23327D02*
X368773Y25730D01*
G01X353783Y39921D02*
X354570Y38557D01*
G01X363074Y23327D02*
X361686Y25730D01*
G01X342177Y22753D02*
X342210Y22686D01*
G01X340061Y22200D02*
X340028Y22267D01*
G01X346696Y39921D02*
X347484Y38557D01*
G01X355988Y23327D02*
X354600Y25730D01*
G01X339610Y39921D02*
X340397Y38557D01*
G01X348901Y23327D02*
X347513Y25730D01*
G01X341814Y23327D02*
X340426Y25730D01*
G01X341291Y22083D02*
X340881Y22770D01*
G01X338945Y22083D02*
X338535Y22770D01*
G01X338623Y12283D02*
X338212Y12970D01*
G01X340930Y22870D02*
X341340Y22200D01*
G01X338584Y22870D02*
X338995Y22200D01*
G01X338262Y13071D02*
X338672Y12400D01*
G01X342079Y22719D02*
X342111Y22669D01*
G01X340126Y22284D02*
X340159Y22234D01*
G01X338010Y22803D02*
X338060Y22736D01*
G01X337688Y13004D02*
X337737Y12937D01*
G01X342111Y22820D02*
X342177Y22753D01*
G01X340569Y22820D02*
X340635Y22753D01*
G01X340126Y22133D02*
X340061Y22200D01*
G01X337961Y22736D02*
X337928Y22770D01*
G01X337638Y12937D02*
X337605Y12970D01*
G01X337945Y22853D02*
X338010Y22803D01*
G01X340239Y45039D02*
X337484D01*
G01X347326D02*
X344570D01*
G01X354413D02*
X351657D01*
G01X361499D02*
X358743D01*
G01X368586D02*
X365830D01*
G01X375673D02*
X372917D01*
G01X382759D02*
X380003D01*
G01X379019Y42516D02*
X383743D01*
G01X371932D02*
X376657D01*
G01X364846D02*
X369570D01*
G01X357759D02*
X362484D01*
G01X350673D02*
X355397D01*
G01X341224D02*
X336499D01*
G01X348310D02*
X343586D01*
G01X390830D02*
X386106D01*
G01X338862Y41043D02*
X337434D01*
G01X345200Y39921D02*
X346696D01*
G01X338113D02*
X339610D01*
G01X353783D02*
X352287D01*
G01X360869D02*
X359373D01*
G01X367956D02*
X366460D01*
G01X375043D02*
X373547D01*
G01X382129D02*
X380633D01*
G01X383153Y25372D02*
X386696D01*
G01X376066D02*
X379610D01*
G01X368980D02*
X372523D01*
G01X361893D02*
X365436D01*
G01X354806D02*
X358350D01*
G01X347720D02*
X351263D01*
G01X340633D02*
X344176D01*
G01X337945Y22451D02*
X337863Y22435D01*
G01X340192Y22853D02*
X340274Y22870D01*
G01X340504Y22100D02*
X340422Y22083D01*
G01X342046Y22100D02*
X341964Y22083D01*
G01X337622Y12652D02*
X337540Y12635D01*
G01X340274Y22770D02*
X340208Y22753D01*
G01X340422Y22183D02*
X340487Y22200D01*
G01X342029D02*
X341964Y22183D01*
G01X337622Y13054D02*
X337688Y13004D01*
G01X342029Y22753D02*
X342079Y22719D01*
G01X340537D02*
X340487Y22753D01*
G01X340159Y22234D02*
X340208Y22200D01*
G01X342046Y22853D02*
X342111Y22820D01*
G01X340504Y22853D02*
X340569Y22820D01*
G01X340192Y22100D02*
X340126Y22133D01*
G01X337928Y22770D02*
X337879Y22786D01*
G01X337605Y12970D02*
X337556Y12987D01*
G01X341964Y22770D02*
X342029Y22753D01*
G01X340487D02*
X340422Y22770D01*
G01X340208Y22200D02*
X340274Y22183D01*
G01X341964Y22870D02*
X342046Y22853D01*
G01X340422Y22870D02*
X340504Y22853D01*
G01X337863Y22870D02*
X337945Y22853D01*
G01X340274Y22083D02*
X340192Y22100D01*
G01X337540Y13071D02*
X337622Y13054D01*
G01X342995Y23327D02*
X341814D01*
G01X350082D02*
X348901D01*
G01X357169D02*
X355988D01*
G01X364255D02*
X363074D01*
G01X371342D02*
X370161D01*
G01X378428D02*
X377247D01*
G01X385515D02*
X384334D01*
G01X342456Y22870D02*
X342554D01*
G01X341570D02*
X341964D01*
G01X341340D02*
X341439D01*
G01X340783D02*
X340930D01*
G01X340274D02*
X340422D01*
G01X338437D02*
X338584D01*
G01X338995D02*
X339093D01*
G01X338207D02*
X338306D01*
G01X337469D02*
X337863D01*
G01X337879Y22786D02*
X337567D01*
G01X341668Y22770D02*
X341964D01*
G01X340422D02*
X340274D01*
G01X340651Y22669D02*
X340553D01*
G01X337567Y22535D02*
X337879D01*
G01X340405Y22518D02*
X340651D01*
G01X337863Y22435D02*
X337567D01*
G01X340553Y22418D02*
X340405D01*
G01X375830Y22204D02*
X379846D01*
G01X368743D02*
X372759D01*
G01X361657D02*
X365673D01*
G01X354570D02*
X358586D01*
G01X347484D02*
X351499D01*
G01X340397D02*
X344413D01*
G01X335886D02*
X337326D01*
G01X386932D02*
X382917D01*
G01X340274Y22183D02*
X340422D01*
G01X341964D02*
X341668D01*
G01X337567Y22083D02*
X337469D01*
G01X340881D02*
X340783D01*
G01X340422D02*
X340274D01*
G01X338535D02*
X338437D01*
G01X339093D02*
X338945D01*
G01X338306D02*
X338207D01*
G01X342554D02*
X342456D01*
G01X341964D02*
X341570D01*
G01X341439D02*
X341291D01*
G01X340575Y13071D02*
X340673D01*
G01X339951D02*
X340083D01*
G01X338114D02*
X338262D01*
G01X338672D02*
X338770D01*
G01X337884D02*
X337983D01*
G01X337146D02*
X337540D01*
G01X337556Y12987D02*
X337245D01*
G01Y12736D02*
X337556D01*
G01X337540Y12635D02*
X337245D01*
G01X340165Y12551D02*
X339869D01*
G01X340181Y12484D02*
X339853D01*
G01X337983Y12283D02*
X337884D01*
G01X337245D02*
X337146D01*
G01X340673D02*
X340575D01*
G01X340345D02*
X340247D01*
G01X339787D02*
X339689D01*
G01X338212D02*
X338114D01*
G01X338770D02*
X338623D01*
G01X392513Y-1181D02*
X335886D01*
G01X392513Y-1772D02*
X336214D01*
G01X392513Y-4394D02*
X336214D01*
G01X392513Y-4591D02*
X336214D01*
G01X342383Y-6693D02*
X338482D01*
G01X356556D02*
X352655D01*
G01X370729D02*
X366828D01*
G01X384902D02*
X381002D01*
G01X342383Y-7087D02*
X338482D01*
G01X356556D02*
X352655D01*
G01X370729D02*
X366828D01*
G01X384902D02*
X381002D01*
G01Y-7284D02*
X384902D01*
G01X366828D02*
X370729D01*
G01X352655D02*
X356556D01*
G01X338482D02*
X342383D01*
G01X341755Y-7480D02*
X339071D01*
G01X355928D02*
X353244D01*
G01X370102D02*
X367417D01*
G01X384275D02*
X381590D01*
G01X385117Y-7499D02*
X385708D01*
G01X380196D02*
X380787D01*
G01X370944D02*
X371535D01*
G01X366023D02*
X366613D01*
G01X356771D02*
X357362D01*
G01X351850D02*
X352440D01*
G01X342598D02*
X343188D01*
G01X338267D02*
X337676D01*
G01X384307Y-7577D02*
X385095D01*
G01X370134D02*
X370921D01*
G01X355961D02*
X356748D01*
G01X341788D02*
X342575D01*
G01X338251D02*
X339038D01*
G01X353212D02*
X352424D01*
G01X367385D02*
X366597D01*
G01X381558D02*
X380771D01*
G01X337451Y53330D02*
X337326Y53648D01*
G01X337667Y53051D02*
X337451Y53330D01*
G01X344538D02*
X344413Y53648D01*
G01X344754Y53051D02*
X344538Y53330D01*
G01X351625D02*
X351499Y53648D01*
G01X351841Y53051D02*
X351625Y53330D01*
G01X358711D02*
X358586Y53648D01*
G01X358927Y53051D02*
X358711Y53330D01*
G01X365798D02*
X365673Y53648D01*
G01X366014Y53051D02*
X365798Y53330D01*
G01X372884D02*
X372759Y53648D01*
G01X373101Y53051D02*
X372884Y53330D01*
G01X379971D02*
X379846Y53648D01*
G01X380187Y53051D02*
X379971Y53330D01*
G01X387058D02*
X386932Y53648D01*
G01X337469Y53425D02*
X337667Y53051D01*
G01X337342Y53849D02*
X337469Y53425D01*
G01X337297Y54309D02*
X337342Y53849D01*
G01X344556Y53425D02*
X344754Y53051D01*
G01X344429Y53849D02*
X344556Y53425D01*
G01X344383Y54309D02*
X344429Y53849D01*
G01X351642Y53425D02*
X351841Y53051D01*
G01X351515Y53849D02*
X351642Y53425D01*
G01X351470Y54309D02*
X351515Y53849D01*
G01X358729Y53425D02*
X358927Y53051D01*
G01X358602Y53849D02*
X358729Y53425D01*
G01X358556Y54309D02*
X358602Y53849D01*
G01X365815Y53425D02*
X366014Y53051D01*
G01X365689Y53849D02*
X365815Y53425D01*
G01X365643Y54309D02*
X365689Y53849D01*
G01X337304Y53766D02*
X337326Y53643D01*
G01X337297Y53889D02*
X337304Y53766D01*
G01X344391D02*
X344413Y53643D01*
G01X344383Y53889D02*
X344391Y53766D01*
G01X351477D02*
X351499Y53643D01*
G01X351470Y53889D02*
X351477Y53766D01*
G01X358564D02*
X358586Y53643D01*
G01X358556Y53889D02*
X358564Y53766D01*
G01X372902Y53425D02*
X373101Y53051D01*
G01X372775Y53849D02*
X372902Y53425D01*
G01X372730Y54309D02*
X372775Y53849D01*
G01X379989Y53425D02*
X380187Y53051D01*
G01X379862Y53849D02*
X379989Y53425D01*
G01X379816Y54309D02*
X379862Y53849D01*
G01X386948D02*
X387075Y53425D01*
G01X386903Y54309D02*
X386948Y53849D01*
G01X365650Y53766D02*
X365673Y53643D01*
G01X365643Y53889D02*
X365650Y53766D01*
G01X372737D02*
X372759Y53643D01*
G01X372730Y53889D02*
X372737Y53766D01*
G01X379824D02*
X379846Y53643D01*
G01X379816Y53889D02*
X379824Y53766D01*
G01X386910D02*
X386932Y53643D01*
G01X340419Y53767D02*
X340397Y53643D01*
G01X340426Y53889D02*
X340419Y53767D01*
G01X347506D02*
X347484Y53643D01*
G01X347513Y53889D02*
X347506Y53767D01*
G01X354592D02*
X354570Y53643D01*
G01X354600Y53889D02*
X354592Y53767D01*
G01X361679D02*
X361657Y53643D01*
G01X361686Y53889D02*
X361679Y53767D01*
G01X368766D02*
X368743Y53643D01*
G01X368773Y53889D02*
X368766Y53767D01*
G01X375852D02*
X375830Y53643D01*
G01X375860Y53889D02*
X375852Y53767D01*
G01X382939D02*
X382917Y53643D01*
G01X382946Y53889D02*
X382939Y53767D01*
G01X340270Y53327D02*
X340056Y53051D01*
G01X340397Y53648D02*
X340270Y53327D01*
G01X347356D02*
X347142Y53051D01*
G01X347484Y53648D02*
X347356Y53327D01*
G01X354443D02*
X354229Y53051D01*
G01X354570Y53648D02*
X354443Y53327D01*
G01X361530D02*
X361315Y53051D01*
G01X361657Y53648D02*
X361530Y53327D01*
G01X368616D02*
X368402Y53051D01*
G01X368743Y53648D02*
X368616Y53327D01*
G01X340381Y53849D02*
X340426Y54309D01*
G01X340254Y53425D02*
X340381Y53849D01*
G01X340056Y53051D02*
X340254Y53425D01*
G01X375703Y53327D02*
X375489Y53051D01*
G01X375830Y53648D02*
X375703Y53327D01*
G01X382789D02*
X382575Y53051D01*
G01X382917Y53648D02*
X382789Y53327D01*
G01X347468Y53849D02*
X347513Y54309D01*
G01X347341Y53425D02*
X347468Y53849D01*
G01X347142Y53051D02*
X347341Y53425D01*
G01X354554Y53849D02*
X354600Y54309D01*
G01X354427Y53425D02*
X354554Y53849D01*
G01X354229Y53051D02*
X354427Y53425D01*
G01X361641Y53849D02*
X361686Y54309D01*
G01X361514Y53425D02*
X361641Y53849D01*
G01X361315Y53051D02*
X361514Y53425D01*
G01X368727Y53849D02*
X368773Y54309D01*
G01X368601Y53425D02*
X368727Y53849D01*
G01X368402Y53051D02*
X368601Y53425D01*
G01X375814Y53849D02*
X375860Y54309D01*
G01X375687Y53425D02*
X375814Y53849D01*
G01X375489Y53051D02*
X375687Y53425D01*
G01X382901Y53849D02*
X382946Y54309D01*
G01X382774Y53425D02*
X382901Y53849D01*
G01X382575Y53051D02*
X382774Y53425D01*
G01X381811Y53149D02*
G03I-709J0D01*
G01X380180Y53045D02*
G03X382583I1201J1018D01*
G01X367638Y53149D02*
G03I-709J0D01*
G01X373093Y53045D02*
G03X375496I1202J1018D01*
G01X366006D02*
G03X368410I1202J1018D01*
G01X358920D02*
G03X361323I1202J1018D01*
G01X353464Y53149D02*
G03I-708J0D01*
G01X351833Y53045D02*
G03X354236I1201J1018D01*
G01X344747D02*
G03X347150I1202J1018D01*
G01X339291Y53149D02*
G03I-709J0D01*
G01X337660Y53045D02*
G03X340063I1201J1018D01*
G01X388113Y61712D02*
X386932Y60531D01*
G01X381027Y61712D02*
X379846Y60531D01*
G01X373940Y61712D02*
X372759Y60531D01*
G01X366854Y61712D02*
X365673Y60531D01*
G01X359767Y61712D02*
X358586Y60531D01*
G01X352680Y61712D02*
X351499Y60531D01*
G01X345594Y61712D02*
X344413Y60531D01*
G01X338507Y61712D02*
X337326Y60531D01*
G01X382946Y60138D02*
Y53889D01*
G01X382917Y60531D02*
Y52657D01*
G01X379846D02*
Y60531D01*
G01X379816Y60138D02*
Y53889D01*
G01X375860Y60138D02*
Y53889D01*
G01X375830Y60531D02*
Y52657D01*
G01X372759D02*
Y60531D01*
G01X372730Y60138D02*
Y53889D01*
G01X368773Y60138D02*
Y53889D01*
G01X368743Y60531D02*
Y52657D01*
G01X365673D02*
Y60531D01*
G01X365643Y60138D02*
Y53889D01*
G01X361686Y60138D02*
Y53889D01*
G01X361657Y60531D02*
Y52657D01*
G01X358586D02*
Y60531D01*
G01X358556Y60138D02*
Y53889D01*
G01X354600Y60138D02*
Y53889D01*
G01X354570Y60531D02*
Y52657D01*
G01X351499D02*
Y60531D01*
G01X351470Y60138D02*
Y53889D01*
G01X347513Y60138D02*
Y53889D01*
G01X347484Y60531D02*
Y52657D01*
G01X344413D02*
Y60531D01*
G01X344383Y60138D02*
Y53889D01*
G01X340426Y60138D02*
Y53889D01*
G01X340397Y60531D02*
Y52657D01*
G01X337326D02*
Y60531D01*
G01X337297Y60138D02*
Y53889D01*
G01X381736Y61712D02*
X382917Y60531D01*
G01X374649Y61712D02*
X375830Y60531D01*
G01X367562Y61712D02*
X368743Y60531D01*
G01X360476Y61712D02*
X361657Y60531D01*
G01X353389Y61712D02*
X354570Y60531D01*
G01X346302Y61712D02*
X347484Y60531D01*
G01X339216Y61712D02*
X340397Y60531D01*
G01X335886Y62697D02*
X392024D01*
G01X339216Y61712D02*
X338507D01*
G01X346302D02*
X345594D01*
G01X353389D02*
X352680D01*
G01X360476D02*
X359767D01*
G01X367562D02*
X366854D01*
G01X374649D02*
X373940D01*
G01X381736D02*
X381027D01*
G01X340397Y60531D02*
X337326D01*
G01X347484D02*
X344413D01*
G01X354570D02*
X351499D01*
G01X361657D02*
X358586D01*
G01X368743D02*
X365673D01*
G01X375830D02*
X372759D01*
G01X382917D02*
X379846D01*
G01X590436Y60138D02*
X335869D01*
G01X335886Y58956D02*
X392024D01*
G01X335869Y57775D02*
X590449D01*
G01X337667Y53051D02*
X335869D01*
G01X344754D02*
X340056D01*
G01X351841D02*
X347142D01*
G01X358927D02*
X354229D01*
G01X366014D02*
X361315D01*
G01X373101D02*
X368402D01*
G01X380187D02*
X375489D01*
G01X387274D02*
X382575D01*
G01X382917Y52657D02*
X386932D01*
G01X375830D02*
X379846D01*
G01X368743D02*
X372759D01*
G01X361657D02*
X365673D01*
G01X354570D02*
X358586D01*
G01X347484D02*
X351499D01*
G01X340397D02*
X344413D01*
G01X335886D02*
X337326D01*
G01X379921Y156220D02*
G03I-5906J0D01*
G01X385826D02*
G03I-11811J0D01*
G01X393325Y460630D02*
G03I-3543J0D01*
G01X394112D02*
G03I-4330J0D01*
G01X391063Y473041D02*
X385502D01*
G01Y470088D02*
X441305D01*
G01X385502Y451139D02*
X441305D01*
G01X383543Y453098D02*
X385502Y451139D01*
G01X386880D02*
Y495978D01*
G01X385502Y494993D02*
Y470088D01*
G01X383543Y453098D02*
Y468129D01*
G01X385502Y470088D02*
X383543Y468129D01*
G01X342529Y530315D02*
Y520720D01*
G01Y530315D02*
G03X334655I-3937J0D01*
G01X442287Y503937D02*
X384484D01*
G01D02*
X352475Y509057D01*
G01X342529Y520720D02*
G03X352474Y509057I11811J0D01*
G01X386487Y495978D02*
G03X385502Y494993I0J-985D01*
G01X334655Y520720D02*
G03X351230Y501282I19685J0D01*
G01X383858Y496063D02*
X351231Y501282D01*
G01X442913Y496063D02*
X383858D01*
G01X440321Y495978D02*
X386487D01*
G01X334655Y562992D02*
Y520720D01*
G01X346466Y570866D02*
G03X342529Y566929I0J-3937D01*
G01X334655Y555512D02*
G03X342529I3937J0D01*
G01X346466Y570866D02*
X480325D01*
G01X342529Y566929D02*
Y555512D01*
G01X334655Y562992D02*
G03X326781Y570866I-7874J0D01*
G01X441921Y-100963D02*
Y-103762D01*
G01X410426Y-100963D02*
Y-103762D01*
G01X400983Y-39739D02*
X401106Y-39764D01*
G01X400878Y-39666D02*
X400983Y-39739D01*
G01X415156D02*
X415279Y-39764D01*
G01X415051Y-39666D02*
X415156Y-39739D01*
G01X429329D02*
X429453Y-39764D01*
G01X429224Y-39666D02*
X429329Y-39739D01*
G01X443502D02*
X443626Y-39764D01*
G01X443397Y-39666D02*
X443502Y-39739D01*
G01X395007Y-38609D02*
X395002Y-38615D01*
G01X395023Y-38589D02*
X395007Y-38609D01*
G01X395049Y-38556D02*
X395023Y-38589D01*
G01X395083Y-38512D02*
X395049Y-38556D01*
G01X395123Y-38457D02*
X395083Y-38512D01*
G01X395168Y-38389D02*
X395123Y-38457D01*
G01X395215Y-38312D02*
X395168Y-38389D01*
G01X395258Y-38233D02*
X395215Y-38312D01*
G01X395294Y-38160D02*
X395258Y-38233D01*
G01X395322Y-38092D02*
X395294Y-38160D01*
G01X395343Y-38029D02*
X395322Y-38092D01*
G01X395355Y-37971D02*
X395343Y-38029D01*
G01X395359Y-37920D02*
X395355Y-37971D01*
G01X395353Y-37878D02*
X395359Y-37920D01*
G01X395340Y-37844D02*
X395353Y-37878D01*
G01X395324Y-37819D02*
X395340Y-37844D01*
G01X395310Y-37804D02*
X395324Y-37819D01*
G01X395304Y-37799D02*
X395310Y-37804D01*
G01X409181Y-38609D02*
X409176Y-38615D01*
G01X409197Y-38589D02*
X409181Y-38609D01*
G01X409223Y-38556D02*
X409197Y-38589D01*
G01X409256Y-38512D02*
X409223Y-38556D01*
G01X409296Y-38457D02*
X409256Y-38512D01*
G01X409341Y-38389D02*
X409296Y-38457D01*
G01X409389Y-38312D02*
X409341Y-38389D01*
G01X409432Y-38233D02*
X409389Y-38312D01*
G01X409467Y-38160D02*
X409432Y-38233D01*
G01X409495Y-38092D02*
X409467Y-38160D01*
G01X409516Y-38029D02*
X409495Y-38092D01*
G01X409528Y-37971D02*
X409516Y-38029D01*
G01X409532Y-37920D02*
X409528Y-37971D01*
G01X409526Y-37878D02*
X409532Y-37920D01*
G01X409513Y-37844D02*
X409526Y-37878D01*
G01X409497Y-37819D02*
X409513Y-37844D01*
G01X409483Y-37804D02*
X409497Y-37819D01*
G01X409477Y-37799D02*
X409483Y-37804D01*
G01X423354Y-38609D02*
X423349Y-38615D01*
G01X423370Y-38589D02*
X423354Y-38609D01*
G01X423396Y-38556D02*
X423370Y-38589D01*
G01X423429Y-38512D02*
X423396Y-38556D01*
G01X423469Y-38457D02*
X423429Y-38512D01*
G01X423514Y-38389D02*
X423469Y-38457D01*
G01X423562Y-38312D02*
X423514Y-38389D01*
G01X423605Y-38233D02*
X423562Y-38312D01*
G01X423640Y-38160D02*
X423605Y-38233D01*
G01X423668Y-38092D02*
X423640Y-38160D01*
G01X423689Y-38029D02*
X423668Y-38092D01*
G01X423702Y-37971D02*
X423689Y-38029D01*
G01X423705Y-37920D02*
X423702Y-37971D01*
G01X423699Y-37878D02*
X423705Y-37920D01*
G01X423686Y-37844D02*
X423699Y-37878D01*
G01X423670Y-37819D02*
X423686Y-37844D01*
G01X423656Y-37804D02*
X423670Y-37819D01*
G01X423650Y-37799D02*
X423656Y-37804D01*
G01X398903Y-37808D02*
X398908Y-37803D01*
G01X398889Y-37823D02*
X398903Y-37808D01*
G01X398874Y-37848D02*
X398889Y-37823D01*
G01X398861Y-37881D02*
X398874Y-37848D01*
G01X398855Y-37923D02*
X398861Y-37881D01*
G01X398859Y-37973D02*
X398855Y-37923D01*
G01X398871Y-38030D02*
X398859Y-37973D01*
G01X398891Y-38092D02*
X398871Y-38030D01*
G01X398919Y-38160D02*
X398891Y-38092D01*
G01X398955Y-38235D02*
X398919Y-38160D01*
G01X398999Y-38315D02*
X398955Y-38235D01*
G01X399045Y-38390D02*
X398999Y-38315D01*
G01X399089Y-38455D02*
X399045Y-38390D01*
G01X399128Y-38510D02*
X399089Y-38455D01*
G01X399161Y-38553D02*
X399128Y-38510D01*
G01X399186Y-38586D02*
X399161Y-38553D01*
G01X399202Y-38605D02*
X399186Y-38586D01*
G01X399207Y-38611D02*
X399202Y-38605D01*
G01X437527Y-38609D02*
X437522Y-38615D01*
G01X437543Y-38589D02*
X437527Y-38609D01*
G01X437569Y-38556D02*
X437543Y-38589D01*
G01X437603Y-38512D02*
X437569Y-38556D01*
G01X437642Y-38457D02*
X437603Y-38512D01*
G01X437688Y-38389D02*
X437642Y-38457D01*
G01X437735Y-38312D02*
X437688Y-38389D01*
G01X437778Y-38233D02*
X437735Y-38312D01*
G01X437813Y-38160D02*
X437778Y-38233D01*
G01X437842Y-38092D02*
X437813Y-38160D01*
G01X437862Y-38029D02*
X437842Y-38092D01*
G01X437875Y-37971D02*
X437862Y-38029D01*
G01X437878Y-37920D02*
X437875Y-37971D01*
G01X437873Y-37878D02*
X437878Y-37920D01*
G01X437860Y-37844D02*
X437873Y-37878D01*
G01X437843Y-37819D02*
X437860Y-37844D01*
G01X437829Y-37804D02*
X437843Y-37819D01*
G01X437824Y-37799D02*
X437829Y-37804D01*
G01X413076Y-37808D02*
X413082Y-37803D01*
G01X413063Y-37823D02*
X413076Y-37808D01*
G01X413047Y-37848D02*
X413063Y-37823D01*
G01X413034Y-37881D02*
X413047Y-37848D01*
G01X413029Y-37923D02*
X413034Y-37881D01*
G01X413032Y-37973D02*
X413029Y-37923D01*
G01X413044Y-38030D02*
X413032Y-37973D01*
G01X413064Y-38092D02*
X413044Y-38030D01*
G01X413092Y-38160D02*
X413064Y-38092D01*
G01X413128Y-38235D02*
X413092Y-38160D01*
G01X413172Y-38315D02*
X413128Y-38235D01*
G01X413218Y-38390D02*
X413172Y-38315D01*
G01X413262Y-38455D02*
X413218Y-38390D01*
G01X413301Y-38510D02*
X413262Y-38455D01*
G01X413334Y-38553D02*
X413301Y-38510D01*
G01X413360Y-38586D02*
X413334Y-38553D01*
G01X413375Y-38605D02*
X413360Y-38586D01*
G01X413380Y-38611D02*
X413375Y-38605D01*
G01X427249Y-37808D02*
X427255Y-37803D01*
G01X427236Y-37823D02*
X427249Y-37808D01*
G01X427220Y-37848D02*
X427236Y-37823D01*
G01X427207Y-37881D02*
X427220Y-37848D01*
G01X427202Y-37923D02*
X427207Y-37881D01*
G01X427205Y-37973D02*
X427202Y-37923D01*
G01X427217Y-38030D02*
X427205Y-37973D01*
G01X427237Y-38092D02*
X427217Y-38030D01*
G01X427265Y-38160D02*
X427237Y-38092D01*
G01X427302Y-38235D02*
X427265Y-38160D01*
G01X427345Y-38315D02*
X427302Y-38235D01*
G01X427392Y-38390D02*
X427345Y-38315D01*
G01X427435Y-38455D02*
X427392Y-38390D01*
G01X427474Y-38510D02*
X427435Y-38455D01*
G01X427507Y-38553D02*
X427474Y-38510D01*
G01X427533Y-38586D02*
X427507Y-38553D01*
G01X427549Y-38605D02*
X427533Y-38586D01*
G01X427554Y-38611D02*
X427549Y-38605D01*
G01X441422Y-37808D02*
X441428Y-37803D01*
G01X441409Y-37823D02*
X441422Y-37808D01*
G01X441393Y-37848D02*
X441409Y-37823D01*
G01X441381Y-37881D02*
X441393Y-37848D01*
G01X441375Y-37923D02*
X441381Y-37881D01*
G01X441378Y-37973D02*
X441375Y-37923D01*
G01X441390Y-38030D02*
X441378Y-37973D01*
G01X441411Y-38092D02*
X441390Y-38030D01*
G01X441439Y-38160D02*
X441411Y-38092D01*
G01X441475Y-38235D02*
X441439Y-38160D01*
G01X441519Y-38315D02*
X441475Y-38235D01*
G01X441565Y-38390D02*
X441519Y-38315D01*
G01X441608Y-38455D02*
X441565Y-38390D01*
G01X441647Y-38510D02*
X441608Y-38455D01*
G01X441680Y-38553D02*
X441647Y-38510D01*
G01X441706Y-38586D02*
X441680Y-38553D01*
G01X441722Y-38605D02*
X441706Y-38586D01*
G01X441727Y-38611D02*
X441722Y-38605D01*
G01X394613Y-39375D02*
X394430Y-39494D01*
G01X394737Y-39251D02*
X394613Y-39375D01*
G01X394816Y-39119D02*
X394737Y-39251D01*
G01X393373Y-39666D02*
X393269Y-39739D01*
G01X393440Y-39558D02*
X393373Y-39666D01*
G01X408786Y-39375D02*
X408603Y-39494D01*
G01X408910Y-39251D02*
X408786Y-39375D01*
G01X408989Y-39119D02*
X408910Y-39251D01*
G01X422959Y-39375D02*
X422776Y-39494D01*
G01X423083Y-39251D02*
X422959Y-39375D01*
G01X423162Y-39119D02*
X423083Y-39251D01*
G01X437132Y-39375D02*
X436949Y-39494D01*
G01X437257Y-39251D02*
X437132Y-39375D01*
G01X437336Y-39119D02*
X437257Y-39251D01*
G01X407546Y-39666D02*
X407442Y-39739D01*
G01X407613Y-39558D02*
X407546Y-39666D01*
G01X421719D02*
X421615Y-39739D01*
G01X421786Y-39558D02*
X421719Y-39666D01*
G01X435893D02*
X435788Y-39739D01*
G01X435960Y-39558D02*
X435893Y-39666D01*
G01X393568Y-39706D02*
X393100Y-39764D01*
G01X393977Y-39559D02*
X393568Y-39706D01*
G01X394350Y-39339D02*
X393977Y-39559D01*
G01X407741Y-39706D02*
X407274Y-39764D01*
G01X408151Y-39559D02*
X407741Y-39706D01*
G01X408523Y-39339D02*
X408151Y-39559D01*
G01X421914Y-39706D02*
X421447Y-39764D01*
G01X422324Y-39559D02*
X421914Y-39706D01*
G01X422696Y-39339D02*
X422324Y-39559D01*
G01X436088Y-39706D02*
X435620Y-39764D01*
G01X436497Y-39559D02*
X436088Y-39706D01*
G01X436869Y-39339D02*
X436497Y-39559D01*
G01X394377Y-39519D02*
X394350Y-39531D01*
G01X394404Y-39507D02*
X394377Y-39519D01*
G01X394430Y-39494D02*
X394404Y-39507D01*
G01X408550Y-39519D02*
X408523Y-39531D01*
G01X408577Y-39507D02*
X408550Y-39519D01*
G01X408603Y-39494D02*
X408577Y-39507D01*
G01X422724Y-39519D02*
X422696Y-39531D01*
G01X422750Y-39507D02*
X422724Y-39519D01*
G01X422776Y-39494D02*
X422750Y-39507D01*
G01X436897Y-39519D02*
X436869Y-39531D01*
G01X436924Y-39507D02*
X436897Y-39519D01*
G01X436949Y-39494D02*
X436924Y-39507D01*
G01X393460Y-39549D02*
X393440Y-39558D01*
G01X393514Y-39525D02*
X393460Y-39549D01*
G01X393594Y-39490D02*
X393514Y-39525D01*
G01X393690Y-39449D02*
X393594Y-39490D01*
G01X407633Y-39549D02*
X407613Y-39558D01*
G01X407687Y-39525D02*
X407633Y-39549D01*
G01X407768Y-39490D02*
X407687Y-39525D01*
G01X407863Y-39449D02*
X407768Y-39490D01*
G01X421806Y-39549D02*
X421786Y-39558D01*
G01X421860Y-39525D02*
X421806Y-39549D01*
G01X421941Y-39490D02*
X421860Y-39525D01*
G01X422037Y-39449D02*
X421941Y-39490D01*
G01X435979Y-39549D02*
X435960Y-39558D01*
G01X436033Y-39525D02*
X435979Y-39549D01*
G01X436114Y-39490D02*
X436033Y-39525D01*
G01X436210Y-39449D02*
X436114Y-39490D01*
G01X442401Y-35626D02*
G03X442499Y-36172I1575J1D01*
G01X442007Y-35626D02*
G03X442129Y-36308I1969J0D01*
G01X441810Y-35626D02*
G03X441945Y-36377I2166J2D01*
G01X441394Y-37402D02*
G03X441428Y-37803I2362J-2D01*
G01X441727Y-38611D02*
G03X443756Y-39764I2029J1209D01*
G01X443330Y-39558D02*
G03X443626Y-39764I296J110D01*
G01X436791Y-36172D02*
G03X436889Y-35626I-1477J547D01*
G01X428228D02*
G03X428325Y-36172I1574J-2D01*
G01X427834Y-35626D02*
G03X427956Y-36308I1967J0D01*
G01X437161D02*
G03X437283Y-35626I-1847J682D01*
G01X427637D02*
G03X427771Y-36377I2165J-1D01*
G01X437345D02*
G03X437480Y-35626I-2031J753D01*
G01X427221Y-37402D02*
G03X427255Y-37803I2362J-2D01*
G01X427554Y-38611D02*
G03X429583Y-39764I2029J1209D01*
G01X436867Y-39325D02*
G03X437522Y-38615I-1372J1923D01*
G01X437824Y-37797D02*
G03X437857Y-37402I-2329J393D01*
G01X422618Y-36172D02*
G03X422716Y-35626I-1477J547D01*
G01X414054D02*
G03X414152Y-36172I1575J1D01*
G01X413661Y-35626D02*
G03X413783Y-36308I1967J0D01*
G01X422988D02*
G03X423110Y-35626I-1847J682D01*
G01X413464D02*
G03X413598Y-36377I2165J-1D01*
G01X423172D02*
G03X423306Y-35626I-2031J750D01*
G01X413047Y-37402D02*
G03X413082Y-37803I2363J4D01*
G01X413381Y-38611D02*
G03X415410Y-39764I2029J1209D01*
G01X422693Y-39325D02*
G03X423349Y-38615I-1370J1924D01*
G01X423650Y-37799D02*
G03X423684Y-37402I-2328J399D01*
G01X435664Y-39764D02*
G03X435960Y-39558I0J316D01*
G01X429157D02*
G03X429453Y-39764I296J110D01*
G01X421491D02*
G03X421786Y-39558I0J314D01*
G01X414984D02*
G03X415279Y-39764I295J108D01*
G01X407318D02*
G03X407613Y-39558I0J314D01*
G01X400811D02*
G03X401106Y-39764I295J108D01*
G01X399881Y-35626D02*
G03X399979Y-36172I1575J1D01*
G01X408445D02*
G03X408543Y-35626I-1477J547D01*
G01X408814Y-36308D02*
G03X408936Y-35626I-1845J682D01*
G01X399488D02*
G03X399610Y-36308I1967J0D01*
G01X408999Y-36377D02*
G03X409133Y-35626I-2031J750D01*
G01X399291D02*
G03X399425Y-36377I2165J-1D01*
G01X408520Y-39325D02*
G03X409176Y-38615I-1370J1924D01*
G01X409477Y-37799D02*
G03X409511Y-37402I-2328J399D01*
G01X398874D02*
G03X398908Y-37803I2362J-2D01*
G01X399207Y-38611D02*
G03X401236Y-39764I2029J1209D01*
G01X393145D02*
G03X393440Y-39558I0J314D01*
G01X394272Y-36172D02*
G03X394369Y-35626I-1477J544D01*
G01X394641Y-36308D02*
G03X394763Y-35626I-1845J682D01*
G01X394826Y-36377D02*
G03X394960Y-35626I-2031J750D01*
G01X394347Y-39325D02*
G03X395002Y-38615I-1372J1923D01*
G01X395304Y-37799D02*
G03X395338Y-37402I-2329J399D01*
G01X443330Y-39558D02*
X443710Y-39449D01*
G01X429157Y-39558D02*
X429536Y-39449D01*
G01X414984Y-39558D02*
X415363Y-39449D01*
G01X400811Y-39558D02*
X401190Y-39449D01*
G01X441945Y-36377D02*
X442499Y-36172D01*
G01X427771Y-36377D02*
X428325Y-36172D01*
G01X413598Y-36377D02*
X414152Y-36172D01*
G01X399425Y-36377D02*
X399979Y-36172D01*
G01X393373Y-39665D02*
X393440Y-39558D01*
G01X437857Y-37708D02*
X437336Y-39119D01*
G01X437463Y-37637D02*
X436869Y-39245D01*
G01X437345Y-36377D02*
X436210Y-39449D01*
G01X437161Y-36308D02*
X435960Y-39558D01*
G01X435580Y-39449D02*
X436791Y-36172D01*
G01X423162Y-39119D02*
X423684Y-37708D01*
G01X423290Y-37637D02*
X422696Y-39245D01*
G01X423172Y-36377D02*
X422037Y-39449D01*
G01X422987Y-36308D02*
X421786Y-39558D01*
G01X421407Y-39449D02*
X422618Y-36172D01*
G01X408989Y-39119D02*
X409511Y-37708D01*
G01X409117Y-37637D02*
X408523Y-39245D01*
G01X408999Y-36377D02*
X407863Y-39449D01*
G01X408814Y-36308D02*
X407613Y-39558D01*
G01X407234Y-39449D02*
X408445Y-36172D01*
G01X395338Y-37708D02*
X394816Y-39119D01*
G01X394944Y-37637D02*
X394350Y-39245D01*
G01X394826Y-36377D02*
X393690Y-39449D01*
G01X394641Y-36308D02*
X393440Y-39558D01*
G01X393061Y-39449D02*
X394272Y-36172D01*
G01X448717Y-12828D02*
Y62697D01*
G01X443793Y-31890D02*
Y-39764D01*
G01X443710Y-39449D02*
Y-39764D01*
G01X443080Y-39449D02*
Y-39764D01*
G01X442401Y-35626D02*
Y-7499D01*
G01X442007D02*
Y-35626D01*
G01X441810Y-7499D02*
Y-35626D01*
G01X441788Y-7577D02*
Y-37640D01*
G01X441394Y-7577D02*
Y-37402D01*
G01X441000Y-7577D02*
Y-39764D01*
G01X438251Y-7577D02*
Y-39764D01*
G01X437857Y-7577D02*
Y-37708D01*
G01X437480Y-35626D02*
Y-7499D01*
G01X437463Y-37637D02*
Y-7577D01*
G01X437283Y-7499D02*
Y-35626D01*
G01X436889Y-7499D02*
Y-35626D01*
G01X436869Y-31890D02*
Y-39531D01*
G01X436210Y-39449D02*
Y-39764D01*
G01X435580Y-39449D02*
Y-39764D01*
G01X434507Y-31890D02*
Y-39764D01*
G01X434147Y-31890D02*
Y-39764D01*
G01X429619Y-31890D02*
Y-39764D01*
G01X429536Y-39449D02*
Y-39764D01*
G01X428907Y-39449D02*
Y-39764D01*
G01X428228Y-35626D02*
Y-7499D01*
G01X427834D02*
Y-35626D01*
G01X427637Y-7499D02*
Y-35626D01*
G01X427614Y-7577D02*
Y-37640D01*
G01X427221Y-7577D02*
Y-37402D01*
G01X426827Y-39764D02*
Y-7577D01*
G01X424078D02*
Y-39764D01*
G01X423684Y-37708D02*
Y-7577D01*
G01X423306Y-35626D02*
Y-7499D01*
G01X423290Y-37637D02*
Y-7577D01*
G01X423110Y-7499D02*
Y-35626D01*
G01X422716Y-7499D02*
Y-35626D01*
G01X422696Y-39531D02*
Y-31890D01*
G01X422037Y-39449D02*
Y-39764D01*
G01X421407Y-39449D02*
Y-39764D01*
G01X420334Y-31890D02*
Y-39764D01*
G01X419974Y-31890D02*
Y-39764D01*
G01X415446Y-31890D02*
Y-39764D01*
G01X415363Y-39449D02*
Y-39764D01*
G01X414734Y-39449D02*
Y-39764D01*
G01X414054Y-35626D02*
Y-7499D01*
G01X413661D02*
Y-35626D01*
G01X413464Y-7499D02*
Y-35626D01*
G01X413441Y-7577D02*
Y-37640D01*
G01X413047Y-7577D02*
Y-37402D01*
G01X412654Y-39764D02*
Y-7577D01*
G01X409904D02*
Y-39764D01*
G01X409511Y-37708D02*
Y-7577D01*
G01X409133Y-35626D02*
Y-7499D01*
G01X409117Y-37637D02*
Y-7577D01*
G01X408936Y-7499D02*
Y-35626D01*
G01X408543Y-7499D02*
Y-35626D01*
G01X408523Y-39531D02*
Y-31890D01*
G01X407863Y-39449D02*
Y-39764D01*
G01X407234Y-39449D02*
Y-39764D01*
G01X406161Y-31890D02*
Y-39764D01*
G01X405800Y-31890D02*
Y-39764D01*
G01X401273Y-31890D02*
Y-39764D01*
G01X401190D02*
Y-39449D01*
G01X400560D02*
Y-39764D01*
G01X399881Y-35626D02*
Y-7499D01*
G01X399488Y-35626D02*
Y-7499D01*
G01X399291D02*
Y-35626D01*
G01X399268Y-7577D02*
Y-37640D01*
G01X398874Y-7577D02*
Y-37402D01*
G01X398480Y-7577D02*
Y-39764D01*
G01X395731Y-7577D02*
Y-39764D01*
G01X395338Y-7577D02*
Y-37708D01*
G01X394960Y-35626D02*
Y-7499D01*
G01X394944Y-37637D02*
Y-7577D01*
G01X394763Y-7499D02*
Y-35626D01*
G01X394369Y-7499D02*
Y-35626D01*
G01X394350Y-39531D02*
Y-31890D01*
G01X393690Y-39449D02*
Y-39764D01*
G01X393061Y-39449D02*
Y-39764D01*
G01X392907Y-1181D02*
Y-39764D01*
G01X392579Y62697D02*
Y-12828D01*
G01X392513Y-39764D02*
Y-1181D01*
G01X392024Y-12828D02*
Y62697D01*
G01X387100Y-31890D02*
Y-39764D01*
G01X387017Y-39449D02*
Y-39764D01*
G01X442499Y-36172D02*
X443710Y-39449D01*
G01X443330Y-39558D02*
X442129Y-36308D01*
G01X443080Y-39449D02*
X441945Y-36377D01*
G01X442419Y-39350D02*
X441788Y-37640D01*
G01X441428Y-37803D02*
X441727Y-38611D01*
G01X428325Y-36172D02*
X429536Y-39449D01*
G01X429157Y-39558D02*
X427956Y-36308D01*
G01X428907Y-39449D02*
X427771Y-36377D01*
G01X428246Y-39350D02*
X427614Y-37640D01*
G01X427255Y-37803D02*
X427554Y-38611D01*
G01X414152Y-36172D02*
X415363Y-39449D01*
G01X414984Y-39558D02*
X413783Y-36308D01*
G01X414734Y-39449D02*
X413598Y-36377D01*
G01X414073Y-39350D02*
X413441Y-37640D01*
G01X413082Y-37803D02*
X413380Y-38611D01*
G01X399979Y-36172D02*
X401190Y-39449D01*
G01X399610Y-36308D02*
X400811Y-39558D01*
G01X400560Y-39449D02*
X399425Y-36377D01*
G01X399900Y-39350D02*
X399268Y-37640D01*
G01X398908Y-37803D02*
X399207Y-38611D01*
G01X443397Y-39666D02*
X443330Y-39558D01*
G01X429224Y-39666D02*
X429157Y-39558D01*
G01X415051Y-39666D02*
X414984Y-39558D01*
G01X400878Y-39666D02*
X400811Y-39558D01*
G01X443080Y-39449D02*
X443330Y-39558D01*
G01X428907Y-39449D02*
X429157Y-39558D01*
G01X414734Y-39449D02*
X414984Y-39558D01*
G01X400560Y-39449D02*
X400811Y-39558D01*
G01X436791Y-36172D02*
X437345Y-36377D01*
G01X422618Y-36172D02*
X423172Y-36377D01*
G01X408445Y-36172D02*
X408999Y-36377D01*
G01X394272Y-36172D02*
X394826Y-36377D01*
G01X436869Y-39471D02*
X436949Y-39494D01*
G01X435580Y-39449D02*
X435960Y-39558D01*
G01X422696Y-39471D02*
X422776Y-39494D01*
G01X421407Y-39449D02*
X421786Y-39558D01*
G01X408523Y-39471D02*
X408603Y-39494D01*
G01X407234Y-39449D02*
X407613Y-39558D01*
G01X394350Y-39471D02*
X394430Y-39494D01*
G01X393061Y-39449D02*
X393440Y-39558D01*
G01X437857Y-37708D02*
X437463Y-37637D01*
G01X423684Y-37708D02*
X423290Y-37637D01*
G01X409511Y-37708D02*
X409117Y-37637D01*
G01X395338Y-37708D02*
X394944Y-37637D01*
G01X392907Y-12828D02*
X392579D01*
G01X392513D02*
X392024D01*
G01X449206D02*
X448717D01*
G01X434507Y-31890D02*
X436869D01*
G01X420334D02*
X422696D01*
G01X406161D02*
X408523D01*
G01X392513D02*
X387100D01*
G01X394350D02*
X392907D01*
G01X405800D02*
X401273D01*
G01X419974D02*
X415446D01*
G01X434147D02*
X429619D01*
G01X449206D02*
X443793D01*
G01X441810Y-35626D02*
X442401D01*
G01X427637D02*
X428228D01*
G01X413464D02*
X414054D01*
G01X399291D02*
X399881D01*
G01X394369D02*
X394960D01*
G01X409133D02*
X408543D01*
G01X423306D02*
X422716D01*
G01X437480D02*
X436889D01*
G01X437857Y-37402D02*
X441394D01*
G01X423684D02*
X427221D01*
G01X409511D02*
X413047D01*
G01X395338D02*
X398874D01*
G01X443793Y-39276D02*
X449206D01*
G01X429619D02*
X434147D01*
G01X415446D02*
X419974D01*
G01X401273D02*
X405800D01*
G01X387100D02*
X392513D01*
G01X394350D02*
X392907D01*
G01X408523D02*
X406161D01*
G01X422696D02*
X420334D01*
G01X436869D02*
X434507D01*
G01X436210Y-39449D02*
X449206D01*
G01X422037D02*
X435580D01*
G01X407863D02*
X421407D01*
G01X393690D02*
X407234D01*
G01X392907D02*
X393061D01*
G01X392907Y-39764D02*
X449206D01*
G01X399268Y-37640D02*
X398894Y-37706D01*
G01X413067D02*
X413441Y-37640D01*
G01X427240Y-37706D02*
X427614Y-37640D01*
G01X441414Y-37706D02*
X441788Y-37640D01*
G01X393145Y-39764D02*
X393268Y-39738D01*
G01X407318Y-39764D02*
X407442Y-39738D01*
G01X421491Y-39764D02*
X421615Y-39738D01*
G01X435664Y-39764D02*
X435788Y-39738D01*
G01X395711Y-7354D02*
X395764Y-7480D01*
G01X395670Y-7224D02*
X395711Y-7354D01*
G01X395643Y-7124D02*
X395670Y-7224D01*
G01X395633Y-7087D02*
X395643Y-7124D01*
G01X409884Y-7354D02*
X409937Y-7480D01*
G01X409843Y-7224D02*
X409884Y-7354D01*
G01X409816Y-7124D02*
X409843Y-7224D01*
G01X409807Y-7087D02*
X409816Y-7124D01*
G01X409762Y-6892D02*
X409723Y-6693D01*
G01X409794Y-7035D02*
X409762Y-6892D01*
G01X409807Y-7087D02*
X409794Y-7035D01*
G01X395621D02*
X395633Y-7087D01*
G01X395589Y-6890D02*
X395621Y-7035D01*
G01X395550Y-6693D02*
X395589Y-6890D01*
G01X424058Y-7354D02*
X424110Y-7480D01*
G01X424016Y-7224D02*
X424058Y-7354D01*
G01X423989Y-7124D02*
X424016Y-7224D01*
G01X423980Y-7087D02*
X423989Y-7124D01*
G01X438231Y-7354D02*
X438283Y-7480D01*
G01X438190Y-7224D02*
X438231Y-7354D01*
G01X438163Y-7124D02*
X438190Y-7224D01*
G01X438153Y-7087D02*
X438163Y-7124D01*
G01X423935Y-6892D02*
X423896Y-6693D01*
G01X423967Y-7035D02*
X423935Y-6892D01*
G01X423980Y-7087D02*
X423967Y-7035D01*
G01X438109Y-6892D02*
X438069Y-6693D01*
G01X438140Y-7035D02*
X438109Y-6892D01*
G01X438153Y-7087D02*
X438140Y-7035D01*
G01X398591D02*
X398578Y-7087D01*
G01X398623Y-6890D02*
X398591Y-7035D01*
G01X398662Y-6693D02*
X398623Y-6890D01*
G01X412796Y-6892D02*
X412835Y-6693D01*
G01X412764Y-7034D02*
X412796Y-6892D01*
G01X412751Y-7087D02*
X412764Y-7034D01*
G01X426969Y-6892D02*
X427009Y-6693D01*
G01X426937Y-7034D02*
X426969Y-6892D01*
G01X426925Y-7087D02*
X426937Y-7034D01*
G01X441142Y-6892D02*
X441182Y-6693D01*
G01X441111Y-7034D02*
X441142Y-6892D01*
G01X441098Y-7087D02*
X441111Y-7034D01*
G01X398570Y-7120D02*
X398578Y-7087D01*
G01X398544Y-7214D02*
X398570Y-7120D01*
G01X398503Y-7346D02*
X398544Y-7214D01*
G01X398448Y-7480D02*
X398503Y-7346D01*
G01X412743Y-7120D02*
X412751Y-7087D01*
G01X412718Y-7214D02*
X412743Y-7120D01*
G01X412676Y-7346D02*
X412718Y-7214D01*
G01X412621Y-7480D02*
X412676Y-7346D01*
G01X426916Y-7120D02*
X426925Y-7087D01*
G01X426891Y-7214D02*
X426916Y-7120D01*
G01X426849Y-7346D02*
X426891Y-7214D01*
G01X426795Y-7480D02*
X426849Y-7346D01*
G01X441090Y-7120D02*
X441098Y-7087D01*
G01X441064Y-7214D02*
X441090Y-7120D01*
G01X441023Y-7346D02*
X441064Y-7214D01*
G01X440968Y-7480D02*
X441023Y-7346D01*
G01X438504Y48819D02*
G03I-709J0D01*
G01X445590Y48425D02*
G03I-708J0D01*
G01X447129Y46771D02*
G03I-1968J0D01*
G01X440043D02*
G03I-1969J0D01*
G01X445590Y44094D02*
G03I-708J0D01*
G01X438504Y43307D02*
G03I-709J0D01*
G01X436696Y45039D02*
G03X435712Y44055I0J-984D01*
G01X440436D02*
G03X439452Y45039I-984J0D01*
G01X443783D02*
G03X442799Y44055I0J-984D01*
G01X447523D02*
G03X446539Y45039I-984J0D01*
G01X439649Y39478D02*
G03X436499I-1575J0D01*
G01X446736D02*
G03X443586I-1575J0D01*
G01X445590Y38582D02*
G03I-708J0D01*
G01X438504Y38976D02*
G03I-709J0D01*
G01Y34645D02*
G03I-709J0D01*
G01X445590Y34252D02*
G03I-708J0D01*
G01X443625Y36087D02*
G03Y34307I1300J-890D01*
G01X446696D02*
G03Y36087I-1299J890D01*
G01X439610Y34307D02*
G03Y36087I-1300J890D01*
G01X436539D02*
G03Y34307I1299J-890D01*
G01X431417Y48425D02*
G03I-709J0D01*
G01X424330Y48819D02*
G03I-708J0D01*
G01X417244Y48425D02*
G03I-709J0D01*
G01X432956Y46771D02*
G03I-1968J0D01*
G01X425869D02*
G03I-1968J0D01*
G01X418783D02*
G03I-1969J0D01*
G01X431417Y44094D02*
G03I-709J0D01*
G01X426263Y44055D02*
G03X425279Y45039I-984J0D01*
G01X429610D02*
G03X428625Y44055I0J-985D01*
G01X433350D02*
G03X432365Y45039I-984J0D01*
G01X425476Y39478D02*
G03X422326I-1575J0D01*
G01X432562D02*
G03X429413I-1574J0D01*
G01X431417Y38582D02*
G03I-709J0D01*
G01Y34252D02*
G03I-709J0D01*
G01X432523Y34307D02*
G03Y36087I-1299J890D01*
G01X429452D02*
G03Y34307I1299J-890D01*
G01X425436D02*
G03Y36087I-1299J890D01*
G01X424330Y43307D02*
G03I-708J0D01*
G01X417244Y44094D02*
G03I-709J0D01*
G01X415436Y45039D02*
G03X414452Y44055I0J-984D01*
G01X419176D02*
G03X418192Y45039I-984J0D01*
G01X422523D02*
G03X421539Y44055I0J-984D01*
G01X418389Y39478D02*
G03X415239I-1575J0D01*
G01X424330Y38976D02*
G03I-708J0D01*
G01Y34645D02*
G03I-708J0D01*
G01X417244Y38582D02*
G03I-709J0D01*
G01Y34252D02*
G03I-709J0D01*
G01X422365Y36087D02*
G03Y34307I1300J-890D01*
G01X418350D02*
G03Y36087I-1300J890D01*
G01X415279D02*
G03Y34307I1299J-890D01*
G01X446696Y27220D02*
G03Y29000I-1299J890D01*
G01X445590Y29921D02*
G03I-708J0D01*
G01X438504Y29134D02*
G03I-709J0D01*
G01X443625Y29000D02*
G03Y27220I1300J-890D01*
G01X439610D02*
G03Y29000I-1300J890D01*
G01X436539D02*
G03Y27220I1299J-890D01*
G01X438504Y24803D02*
G03I-709J0D01*
G01X445590Y24409D02*
G03I-708J0D01*
G01X438504Y20472D02*
G03I-709J0D01*
G01X445590Y20078D02*
G03I-708J0D01*
G01X438504Y14960D02*
G03I-709J0D01*
G01X445590Y15748D02*
G03I-708J0D01*
G01Y10236D02*
G03I-708J0D01*
G01X431417Y29921D02*
G03I-709J0D01*
G01X432523Y27220D02*
G03Y29000I-1299J890D01*
G01X429452D02*
G03Y27220I1299J-890D01*
G01X425436D02*
G03Y29000I-1299J890D01*
G01X431417Y24409D02*
G03I-709J0D01*
G01Y20078D02*
G03I-709J0D01*
G01X424330Y29134D02*
G03I-708J0D01*
G01X417244Y29921D02*
G03I-709J0D01*
G01X422365Y29000D02*
G03Y27220I1300J-890D01*
G01X418350D02*
G03Y29000I-1300J890D01*
G01X415279D02*
G03Y27220I1299J-890D01*
G01X424330Y24803D02*
G03I-708J0D01*
G01Y20472D02*
G03I-708J0D01*
G01X417244Y24409D02*
G03I-709J0D01*
G01Y20078D02*
G03I-709J0D01*
G01X424330Y14960D02*
G03I-708J0D01*
G01X431417Y15748D02*
G03I-709J0D01*
G01Y10236D02*
G03I-709J0D01*
G01X417244Y15748D02*
G03I-709J0D01*
G01Y10236D02*
G03I-709J0D01*
G01X445590Y5905D02*
G03I-708J0D01*
G01X440997Y-7577D02*
G03X440965Y-7482I-157J0D01*
G01X438286D02*
G03X438254Y-7577I125J-95D01*
G01X437695Y-7302D02*
G03X437498Y-7499I0J-197D01*
G01X441792D02*
G03X441595Y-7302I-197J0D01*
G01X441989Y-7499D02*
G03X441595Y-7105I-394J0D01*
G01X437695D02*
G03X437301Y-7499I0J-394D01*
G01X438155Y-7089D02*
G03X437860Y-7577I256J-488D01*
G01X441391D02*
G03X441096Y-7089I-551J0D01*
G01X442383Y-7499D02*
G03X441595Y-6711I-788J0D01*
G01X437695D02*
G03X436907Y-7499I0J-788D01*
G01X438070Y-6696D02*
G03X437467Y-7577I342J-881D01*
G01X441784D02*
G03X441181Y-6696I-945J0D01*
G01X431417Y5905D02*
G03I-709J0D01*
G01X417244D02*
G03I-709J0D01*
G01X426824Y-7577D02*
G03X426792Y-7482I-157J0D01*
G01X424113D02*
G03X424081Y-7577I125J-95D01*
G01X423521Y-7302D02*
G03X423325Y-7499I0J-196D01*
G01X427619D02*
G03X427422Y-7302I-197J0D01*
G01X427816Y-7499D02*
G03X427422Y-7105I-394J0D01*
G01X423521D02*
G03X423128Y-7499I0J-393D01*
G01X423981Y-7089D02*
G03X423687Y-7577I258J-488D01*
G01X427217D02*
G03X426923Y-7089I-552J0D01*
G01X428210Y-7499D02*
G03X427422Y-6711I-788J0D01*
G01X423521D02*
G03X422734Y-7499I0J-787D01*
G01X423897Y-6696D02*
G03X423293Y-7577I341J-881D01*
G01X427611D02*
G03X427007Y-6696I-945J0D01*
G01X410157Y48819D02*
G03I-708J0D01*
G01X411696Y46771D02*
G03I-1968J0D01*
G01X404610D02*
G03I-1969J0D01*
G01X410157Y43307D02*
G03I-708J0D01*
G01Y38976D02*
G03I-708J0D01*
G01Y34645D02*
G03I-708J0D01*
G01X405003Y44055D02*
G03X404019Y45039I-984J0D01*
G01X408350D02*
G03X407365Y44055I0J-985D01*
G01X412090D02*
G03X411106Y45039I-984J0D01*
G01X404216Y39478D02*
G03X401066I-1575J0D01*
G01X411302D02*
G03X408153I-1575J0D01*
G01X404176Y34307D02*
G03Y36087I-1299J890D01*
G01X411263Y34307D02*
G03Y36087I-1299J890D01*
G01X408192D02*
G03Y34307I1299J-890D01*
G01X403071Y48425D02*
G03I-709J0D01*
G01X395984Y48819D02*
G03I-709J0D01*
G01X397523Y46771D02*
G03I-1969J0D01*
G01X403071Y44094D02*
G03I-709J0D01*
G01X401263Y45039D02*
G03X400279Y44055I0J-984D01*
G01X403071Y38582D02*
G03I-709J0D01*
G01Y34252D02*
G03I-709J0D01*
G01X401106Y36087D02*
G03Y34307I1299J-890D01*
G01X395984Y43307D02*
G03I-709J0D01*
G01X394176Y45039D02*
G03X393192Y44055I0J-984D01*
G01X397917D02*
G03X396932Y45039I-984J0D01*
G01X397129Y39478D02*
G03X393980I-1574J0D01*
G01X395984Y38976D02*
G03I-709J0D01*
G01Y34645D02*
G03I-709J0D01*
G01X394019Y36087D02*
G03Y34307I1299J-890D01*
G01X397090D02*
G03Y36087I-1299J890D01*
G01X410157Y29134D02*
G03I-708J0D01*
G01Y24803D02*
G03I-708J0D01*
G01Y20472D02*
G03I-708J0D01*
G01X404176Y27220D02*
G03Y29000I-1299J890D01*
G01X411263Y27220D02*
G03Y29000I-1299J890D01*
G01X408192D02*
G03Y27220I1299J-890D01*
G01X410157Y14960D02*
G03I-708J0D01*
G01X403071Y29921D02*
G03I-709J0D01*
G01X395984Y29134D02*
G03I-709J0D01*
G01Y24803D02*
G03I-709J0D01*
G01X403071Y24409D02*
G03I-709J0D01*
G01X395984Y20472D02*
G03I-709J0D01*
G01X403071Y20078D02*
G03I-709J0D01*
G01X394019Y29000D02*
G03Y27220I1299J-890D01*
G01X397090D02*
G03Y29000I-1299J890D01*
G01X401106D02*
G03Y27220I1299J-890D01*
G01X403071Y15748D02*
G03I-709J0D01*
G01Y10236D02*
G03I-709J0D01*
G01X395984Y14960D02*
G03I-709J0D01*
G01X388897Y48425D02*
G03I-708J0D01*
G01Y44094D02*
G03I-708J0D01*
G01Y38582D02*
G03I-708J0D01*
G01Y34252D02*
G03I-708J0D01*
G01X390830Y44055D02*
G03X389846Y45039I-984J0D01*
G01X390043Y39478D02*
G03X386893I-1575J0D01*
G01X390003Y34307D02*
G03Y36087I-1299J890D01*
G01X388897Y29921D02*
G03I-708J0D01*
G01Y24409D02*
G03I-708J0D01*
G01Y20078D02*
G03I-708J0D01*
G01X390003Y27220D02*
G03Y29000I-1299J890D01*
G01X388897Y15748D02*
G03I-708J0D01*
G01Y10236D02*
G03I-708J0D01*
G01X412650Y-7577D02*
G03X412619Y-7482I-157J1D01*
G01X409939D02*
G03X409908Y-7577I126J-94D01*
G01X409348Y-7302D02*
G03X409151Y-7499I0J-197D01*
G01X413446D02*
G03X413249Y-7302I-197J0D01*
G01X413643Y-7499D02*
G03X413249Y-7105I-394J0D01*
G01X409348D02*
G03X408954Y-7499I0J-394D01*
G01X409808Y-7089D02*
G03X409514Y-7577I258J-488D01*
G01X413044D02*
G03X412750Y-7089I-552J0D01*
G01X414036Y-7499D02*
G03X413249Y-6711I-788J0D01*
G01X409348D02*
G03X408561Y-7499I0J-787D01*
G01X409724Y-6696D02*
G03X409120Y-7577I341J-881D01*
G01X413438D02*
G03X412834Y-6696I-945J0D01*
G01X403071Y5905D02*
G03I-709J0D01*
G01X398477Y-7577D02*
G03X398446Y-7482I-157J1D01*
G01X399273Y-7499D02*
G03X399076Y-7302I-197J0D01*
G01X399469Y-7499D02*
G03X399076Y-7105I-394J0D01*
G01X398871Y-7577D02*
G03X398577Y-7089I-552J0D01*
G01X399863Y-7499D02*
G03X399076Y-6711I-788J0D01*
G01X399265Y-7577D02*
G03X398661Y-6696I-945J0D01*
G01X395766Y-7482D02*
G03X395734Y-7577I125J-95D01*
G01X395175Y-7302D02*
G03X394978Y-7499I0J-197D01*
G01X395175Y-7105D02*
G03X394781Y-7499I0J-394D01*
G01X395635Y-7089D02*
G03X395341Y-7577I258J-488D01*
G01X395175Y-6711D02*
G03X394388Y-7499I0J-787D01*
G01X395551Y-6696D02*
G03X394947Y-7577I341J-881D01*
G01X388897Y5905D02*
G03I-708J0D01*
G01X443596Y25730D02*
X442208Y23327D01*
G01X436509Y25730D02*
X435121Y23327D01*
G01X444413Y39921D02*
X443625Y38557D01*
G01X429423Y25730D02*
X428035Y23327D01*
G01X437326Y39921D02*
X436539Y38557D01*
G01X422336Y25730D02*
X420948Y23327D01*
G01X430239Y39921D02*
X429452Y38557D01*
G01X415249Y25730D02*
X413862Y23327D01*
G01X423153Y39921D02*
X422365Y38557D01*
G01X408163Y25730D02*
X406775Y23327D01*
G01X416066Y39921D02*
X415279Y38557D01*
G01X401076Y25730D02*
X399688Y23327D01*
G01X408980Y39921D02*
X408192Y38557D01*
G01X393989Y25730D02*
X392602Y23327D01*
G01X401893Y39921D02*
X401106Y38557D01*
G01X394806Y39921D02*
X394019Y38557D01*
G01X447523Y22204D02*
Y44055D01*
G01X446726Y36042D02*
Y39478D01*
G01Y28955D02*
Y34351D01*
G01Y25730D02*
Y27265D01*
G01X446696Y27220D02*
Y22204D01*
G01Y34307D02*
Y29000D01*
G01Y38557D02*
Y36087D01*
G01X443625Y27220D02*
Y22204D01*
G01Y34307D02*
Y29000D01*
G01Y38557D02*
Y36087D01*
G01X443596Y27265D02*
Y25730D01*
G01Y34351D02*
Y28955D01*
G01Y39478D02*
Y36042D01*
G01X442799Y44055D02*
Y22204D01*
G01X441595Y-7284D02*
Y-6693D01*
G01X440436Y44055D02*
Y22204D01*
G01X439639Y36042D02*
Y39478D01*
G01Y28955D02*
Y34351D01*
G01Y25730D02*
Y27265D01*
G01X439610Y27220D02*
Y22204D01*
G01Y34307D02*
Y29000D01*
G01Y38557D02*
Y36087D01*
G01X437695Y-7284D02*
Y-6693D01*
G01X436539Y36087D02*
Y38557D01*
G01Y29000D02*
Y34307D01*
G01Y22204D02*
Y27220D01*
G01X436509Y27265D02*
Y25730D01*
G01Y34351D02*
Y28955D01*
G01Y39478D02*
Y36042D01*
G01X435712Y44055D02*
Y22204D01*
G01X433350Y44055D02*
Y22204D01*
G01X432552Y36042D02*
Y39478D01*
G01Y28955D02*
Y34351D01*
G01Y25730D02*
Y27265D01*
G01X432523Y27220D02*
Y22204D01*
G01Y34307D02*
Y29000D01*
G01Y38557D02*
Y36087D01*
G01X429452D02*
Y38557D01*
G01Y29000D02*
Y34307D01*
G01Y22204D02*
Y27220D01*
G01X429423Y27265D02*
Y25730D01*
G01Y34351D02*
Y28955D01*
G01Y39478D02*
Y36042D01*
G01X428625Y44055D02*
Y22204D01*
G01X427422Y-7284D02*
Y-6693D01*
G01X426263Y44055D02*
Y22204D01*
G01X425466Y36042D02*
Y39478D01*
G01Y28955D02*
Y34351D01*
G01Y25730D02*
Y27265D01*
G01X425436Y27220D02*
Y22204D01*
G01Y34307D02*
Y29000D01*
G01Y38557D02*
Y36087D01*
G01X423521Y-7284D02*
Y-6693D01*
G01X422365Y36087D02*
Y38557D01*
G01Y29000D02*
Y34307D01*
G01Y22204D02*
Y27220D01*
G01X422336Y27265D02*
Y25730D01*
G01Y34351D02*
Y28955D01*
G01Y39478D02*
Y36042D01*
G01X421539Y44055D02*
Y22204D01*
G01X419176Y44055D02*
Y22204D01*
G01X418379Y36042D02*
Y39478D01*
G01Y28955D02*
Y34351D01*
G01Y25730D02*
Y27265D01*
G01X418350Y27220D02*
Y22204D01*
G01Y34307D02*
Y29000D01*
G01Y38557D02*
Y36087D01*
G01X415279D02*
Y38557D01*
G01Y29000D02*
Y34307D01*
G01Y22204D02*
Y27220D01*
G01X415249Y27265D02*
Y25730D01*
G01Y34351D02*
Y28955D01*
G01Y39478D02*
Y36042D01*
G01X414452Y44055D02*
Y22204D01*
G01X413249Y-7284D02*
Y-6693D01*
G01X412090Y44055D02*
Y22204D01*
G01X411293Y36042D02*
Y39478D01*
G01Y28955D02*
Y34351D01*
G01Y25730D02*
Y27265D01*
G01X411263Y27220D02*
Y22204D01*
G01Y34307D02*
Y29000D01*
G01Y38557D02*
Y36087D01*
G01X409348Y-7284D02*
Y-6693D01*
G01X408192Y36087D02*
Y38557D01*
G01Y29000D02*
Y34307D01*
G01Y22204D02*
Y27220D01*
G01X408163Y27265D02*
Y25730D01*
G01Y34351D02*
Y28955D01*
G01Y39478D02*
Y36042D01*
G01X407365Y44055D02*
Y22204D01*
G01X405003D02*
Y44055D01*
G01X404206Y36042D02*
Y39478D01*
G01Y28955D02*
Y34351D01*
G01Y25730D02*
Y27265D01*
G01X404176Y27220D02*
Y22204D01*
G01Y34307D02*
Y29000D01*
G01Y38557D02*
Y36087D01*
G01X401106D02*
Y38557D01*
G01Y29000D02*
Y34307D01*
G01Y22204D02*
Y27220D01*
G01X401076Y27265D02*
Y25730D01*
G01Y34351D02*
Y28955D01*
G01Y39478D02*
Y36042D01*
G01X400279Y44055D02*
Y22204D01*
G01X399076Y-7284D02*
Y-6693D01*
G01X397917Y22204D02*
Y44055D01*
G01X397119Y36042D02*
Y39478D01*
G01Y28955D02*
Y34351D01*
G01Y25730D02*
Y27265D01*
G01X397090Y27220D02*
Y22204D01*
G01Y34307D02*
Y29000D01*
G01Y38557D02*
Y36087D01*
G01X395175Y-7284D02*
Y-6693D01*
G01X394019Y36087D02*
Y38557D01*
G01Y29000D02*
Y34307D01*
G01Y22204D02*
Y27220D01*
G01X393989Y27265D02*
Y25730D01*
G01Y34351D02*
Y28955D01*
G01Y39478D02*
Y36042D01*
G01X393192Y44055D02*
Y22204D01*
G01X390830D02*
Y44055D01*
G01X390033Y36042D02*
Y39478D01*
G01Y28955D02*
Y34351D01*
G01Y25730D02*
Y27265D01*
G01X390003Y27220D02*
Y22204D01*
G01Y34307D02*
Y29000D01*
G01Y38557D02*
Y36087D01*
G01X386932Y27220D02*
Y22204D01*
G01Y34307D02*
Y29000D01*
G01Y38557D02*
Y36087D01*
G01X386903Y27265D02*
Y25730D01*
G01Y34351D02*
Y28955D01*
G01Y39478D02*
Y36042D01*
G01X445909Y39921D02*
X446696Y38557D01*
G01X438822Y39921D02*
X439610Y38557D01*
G01X448113Y23327D02*
X446726Y25730D01*
G01X431736Y39921D02*
X432523Y38557D01*
G01X441027Y23327D02*
X439639Y25730D01*
G01X424649Y39921D02*
X425436Y38557D01*
G01X433940Y23327D02*
X432552Y25730D01*
G01X417562Y39921D02*
X418350Y38557D01*
G01X426854Y23327D02*
X425466Y25730D01*
G01X410476Y39921D02*
X411263Y38557D01*
G01X419767Y23327D02*
X418379Y25730D01*
G01X403389Y39921D02*
X404176Y38557D01*
G01X412680Y23327D02*
X411293Y25730D01*
G01X396302Y39921D02*
X397090Y38557D01*
G01X405594Y23327D02*
X404206Y25730D01*
G01X389216Y39921D02*
X390003Y38557D01*
G01X398507Y23327D02*
X397119Y25730D01*
G01X391421Y23327D02*
X390033Y25730D01*
G01X389846Y45039D02*
X387090D01*
G01X396932D02*
X394176D01*
G01X404019D02*
X401263D01*
G01X411106D02*
X408350D01*
G01X418192D02*
X415436D01*
G01X425279D02*
X422523D01*
G01X432365D02*
X429610D01*
G01X439452D02*
X436696D01*
G01X446539D02*
X443783D01*
G01X435712Y42516D02*
X440436D01*
G01X428625D02*
X433350D01*
G01X421539D02*
X426263D01*
G01X414452D02*
X419176D01*
G01X407365D02*
X412090D01*
G01X397917D02*
X393192D01*
G01X405003D02*
X400279D01*
G01X447523D02*
X442799D01*
G01X401893Y39921D02*
X403389D01*
G01X394806D02*
X396302D01*
G01X389216D02*
X387720D01*
G01X410476D02*
X408980D01*
G01X417562D02*
X416066D01*
G01X424649D02*
X423153D01*
G01X431736D02*
X430239D01*
G01X438822D02*
X437326D01*
G01X445909D02*
X444413D01*
G01X446932Y25372D02*
X450476D01*
G01X439846D02*
X443389D01*
G01X432759D02*
X436302D01*
G01X425673D02*
X429216D01*
G01X418586D02*
X422129D01*
G01X411499D02*
X415043D01*
G01X404413D02*
X407956D01*
G01X397326D02*
X400869D01*
G01X390239D02*
X393783D01*
G01X392602Y23327D02*
X391421D01*
G01X399688D02*
X398507D01*
G01X406775D02*
X405594D01*
G01X413862D02*
X412680D01*
G01X420948D02*
X419767D01*
G01X428035D02*
X426854D01*
G01X435121D02*
X433940D01*
G01X442208D02*
X441027D01*
G01X449295D02*
X448113D01*
G01X446696Y22204D02*
X448717D01*
G01X432523D02*
X436539D01*
G01X425436D02*
X429452D01*
G01X418350D02*
X422365D01*
G01X411263D02*
X415279D01*
G01X404176D02*
X408192D01*
G01X397090D02*
X401106D01*
G01X392579D02*
X394019D01*
G01X390003D02*
X392024D01*
G01X443625D02*
X439610D01*
G01X449206Y-1181D02*
X392579D01*
G01X449206Y-1772D02*
X392907D01*
G01X449206Y-4394D02*
X392907D01*
G01X449206Y-4591D02*
X392907D01*
G01X399076Y-6693D02*
X395175D01*
G01X413249D02*
X409348D01*
G01X427422D02*
X423521D01*
G01X441595D02*
X437695D01*
G01X399076Y-7087D02*
X395175D01*
G01X413249D02*
X409348D01*
G01X427422D02*
X423521D01*
G01X441595D02*
X437695D01*
G01Y-7284D02*
X441595D01*
G01X423521D02*
X427422D01*
G01X409348D02*
X413249D01*
G01X395175D02*
X399076D01*
G01X398448Y-7480D02*
X395764D01*
G01X412621D02*
X409937D01*
G01X426795D02*
X424110D01*
G01X440968D02*
X438283D01*
G01X441810Y-7499D02*
X442401D01*
G01X436889D02*
X437480D01*
G01X427637D02*
X428228D01*
G01X422716D02*
X423306D01*
G01X413464D02*
X414054D01*
G01X408543D02*
X409133D01*
G01X399291D02*
X399881D01*
G01X394960D02*
X394369D01*
G01X441000Y-7577D02*
X441788D01*
G01X426827D02*
X427614D01*
G01X412654D02*
X413441D01*
G01X398480D02*
X399268D01*
G01X394944D02*
X395731D01*
G01X409904D02*
X409117D01*
G01X424078D02*
X423290D01*
G01X438251D02*
X437463D01*
G01X387274Y53051D02*
X387058Y53330D01*
G01X394144D02*
X394019Y53648D01*
G01X394360Y53051D02*
X394144Y53330D01*
G01X401231D02*
X401106Y53648D01*
G01X401447Y53051D02*
X401231Y53330D01*
G01X408317D02*
X408192Y53648D01*
G01X408534Y53051D02*
X408317Y53330D01*
G01X415404D02*
X415279Y53648D01*
G01X415620Y53051D02*
X415404Y53330D01*
G01X422491D02*
X422365Y53648D01*
G01X422707Y53051D02*
X422491Y53330D01*
G01X429577D02*
X429452Y53648D01*
G01X429793Y53051D02*
X429577Y53330D01*
G01X436664D02*
X436539Y53648D01*
G01X436880Y53051D02*
X436664Y53330D01*
G01X443751D02*
X443625Y53648D01*
G01X443967Y53051D02*
X443751Y53330D01*
G01X387075Y53425D02*
X387274Y53051D01*
G01X394162Y53425D02*
X394360Y53051D01*
G01X394035Y53849D02*
X394162Y53425D01*
G01X393989Y54309D02*
X394035Y53849D01*
G01X401249Y53425D02*
X401447Y53051D01*
G01X401122Y53849D02*
X401249Y53425D01*
G01X401076Y54309D02*
X401122Y53849D01*
G01X386903Y53889D02*
X386910Y53766D01*
G01X393997D02*
X394019Y53643D01*
G01X393989Y53889D02*
X393997Y53766D01*
G01X408335Y53425D02*
X408534Y53051D01*
G01X408208Y53849D02*
X408335Y53425D01*
G01X408163Y54309D02*
X408208Y53849D01*
G01X415422Y53425D02*
X415620Y53051D01*
G01X415295Y53849D02*
X415422Y53425D01*
G01X415249Y54309D02*
X415295Y53849D01*
G01X422508Y53425D02*
X422707Y53051D01*
G01X422382Y53849D02*
X422508Y53425D01*
G01X422336Y54309D02*
X422382Y53849D01*
G01X429595Y53425D02*
X429793Y53051D01*
G01X429468Y53849D02*
X429595Y53425D01*
G01X429423Y54309D02*
X429468Y53849D01*
G01X436682Y53425D02*
X436880Y53051D01*
G01X436555Y53849D02*
X436682Y53425D01*
G01X436509Y54309D02*
X436555Y53849D01*
G01X401084Y53766D02*
X401106Y53643D01*
G01X401076Y53889D02*
X401084Y53766D01*
G01X408170D02*
X408192Y53643D01*
G01X408163Y53889D02*
X408170Y53766D01*
G01X415257D02*
X415279Y53643D01*
G01X415249Y53889D02*
X415257Y53766D01*
G01X422343D02*
X422365Y53643D01*
G01X422336Y53889D02*
X422343Y53766D01*
G01X429430D02*
X429452Y53643D01*
G01X429423Y53889D02*
X429430Y53766D01*
G01X390025Y53767D02*
X390003Y53643D01*
G01X390033Y53889D02*
X390025Y53767D01*
G01X397112D02*
X397090Y53643D01*
G01X397119Y53889D02*
X397112Y53767D01*
G01X404199D02*
X404176Y53643D01*
G01X404206Y53889D02*
X404199Y53767D01*
G01X443768Y53425D02*
X443967Y53051D01*
G01X443641Y53849D02*
X443768Y53425D01*
G01X443596Y54309D02*
X443641Y53849D01*
G01X436517Y53766D02*
X436539Y53643D01*
G01X436509Y53889D02*
X436517Y53766D01*
G01X443603D02*
X443625Y53643D01*
G01X443596Y53889D02*
X443603Y53766D01*
G01X411285Y53767D02*
X411263Y53643D01*
G01X411293Y53889D02*
X411285Y53767D01*
G01X418372D02*
X418350Y53643D01*
G01X418379Y53889D02*
X418372Y53767D01*
G01X425458D02*
X425436Y53643D01*
G01X425466Y53889D02*
X425458Y53767D01*
G01X432545D02*
X432523Y53643D01*
G01X432552Y53889D02*
X432545Y53767D01*
G01X439632D02*
X439610Y53643D01*
G01X439639Y53889D02*
X439632Y53767D01*
G01X446718D02*
X446696Y53643D01*
G01X446726Y53889D02*
X446718Y53767D01*
G01X389876Y53327D02*
X389662Y53051D01*
G01X390003Y53648D02*
X389876Y53327D01*
G01X396963D02*
X396748Y53051D01*
G01X397090Y53648D02*
X396963Y53327D01*
G01X404049D02*
X403835Y53051D01*
G01X404176Y53648D02*
X404049Y53327D01*
G01X411136D02*
X410922Y53051D01*
G01X411263Y53648D02*
X411136Y53327D01*
G01X418222D02*
X418008Y53051D01*
G01X418350Y53648D02*
X418222Y53327D01*
G01X425309D02*
X425095Y53051D01*
G01X425436Y53648D02*
X425309Y53327D01*
G01X432396D02*
X432182Y53051D01*
G01X432523Y53648D02*
X432396Y53327D01*
G01X439482D02*
X439268Y53051D01*
G01X439610Y53648D02*
X439482Y53327D01*
G01X446569D02*
X446355Y53051D01*
G01X446696Y53648D02*
X446569Y53327D01*
G01X389987Y53849D02*
X390033Y54309D01*
G01X389860Y53425D02*
X389987Y53849D01*
G01X389662Y53051D02*
X389860Y53425D01*
G01X397074Y53849D02*
X397119Y54309D01*
G01X396947Y53425D02*
X397074Y53849D01*
G01X396748Y53051D02*
X396947Y53425D01*
G01X404160Y53849D02*
X404206Y54309D01*
G01X404034Y53425D02*
X404160Y53849D01*
G01X403835Y53051D02*
X404034Y53425D01*
G01X411247Y53849D02*
X411293Y54309D01*
G01X411120Y53425D02*
X411247Y53849D01*
G01X410922Y53051D02*
X411120Y53425D01*
G01X418334Y53849D02*
X418379Y54309D01*
G01X418207Y53425D02*
X418334Y53849D01*
G01X418008Y53051D02*
X418207Y53425D01*
G01X425420Y53849D02*
X425466Y54309D01*
G01X425294Y53425D02*
X425420Y53849D01*
G01X425095Y53051D02*
X425294Y53425D01*
G01X432507Y53849D02*
X432552Y54309D01*
G01X432380Y53425D02*
X432507Y53849D01*
G01X432182Y53051D02*
X432380Y53425D01*
G01X439594Y53849D02*
X439639Y54309D01*
G01X439467Y53425D02*
X439594Y53849D01*
G01X439268Y53051D02*
X439467Y53425D01*
G01X446680Y53849D02*
X446726Y54309D01*
G01X446553Y53425D02*
X446680Y53849D01*
G01X446355Y53051D02*
X446553Y53425D01*
G01X438504Y53149D02*
G03I-709J0D01*
G01X443959Y53045D02*
G03X446362I1201J1018D01*
G01X436873D02*
G03X439276I1202J1018D01*
G01X424330Y53149D02*
G03I-708J0D01*
G01X429786Y53045D02*
G03X432189I1201J1018D01*
G01X422699D02*
G03X425102I1202J1018D01*
G01X415613D02*
G03X418016I1202J1018D01*
G01X410157Y53149D02*
G03I-708J0D01*
G01X408526Y53045D02*
G03X410929I1201J1018D01*
G01X401439D02*
G03X403843I1202J1018D01*
G01X395984Y53149D02*
G03I-709J0D01*
G01X394353Y53045D02*
G03X396756I1201J1018D01*
G01X387266D02*
G03X389669I1202J1018D01*
G01X444806Y61712D02*
X443625Y60531D01*
G01X437720Y61712D02*
X436539Y60531D01*
G01X430633Y61712D02*
X429452Y60531D01*
G01X423547Y61712D02*
X422365Y60531D01*
G01X416460Y61712D02*
X415279Y60531D01*
G01X409373Y61712D02*
X408192Y60531D01*
G01X402287Y61712D02*
X401106Y60531D01*
G01X395200Y61712D02*
X394019Y60531D01*
G01X446726Y60138D02*
Y53889D01*
G01X446696Y60531D02*
Y52657D01*
G01X443625D02*
Y60531D01*
G01X443596Y60138D02*
Y53889D01*
G01X439639Y60138D02*
Y53889D01*
G01X439610Y60531D02*
Y52657D01*
G01X436539D02*
Y60531D01*
G01X436509Y60138D02*
Y53889D01*
G01X432552Y60138D02*
Y53889D01*
G01X432523Y60531D02*
Y52657D01*
G01X429452D02*
Y60531D01*
G01X429423Y60138D02*
Y53889D01*
G01X425466Y60138D02*
Y53889D01*
G01X425436Y60531D02*
Y52657D01*
G01X422365D02*
Y60531D01*
G01X422336Y60138D02*
Y53889D01*
G01X418379Y60138D02*
Y53889D01*
G01X418350Y60531D02*
Y52657D01*
G01X415279D02*
Y60531D01*
G01X415249Y60138D02*
Y53889D01*
G01X411293Y60138D02*
Y53889D01*
G01X411263Y60531D02*
Y52657D01*
G01X408192D02*
Y60531D01*
G01X408163Y60138D02*
Y53889D01*
G01X404206Y60138D02*
Y53889D01*
G01X404176Y60531D02*
Y52657D01*
G01X401106D02*
Y60531D01*
G01X401076Y60138D02*
Y53889D01*
G01X397119Y60138D02*
Y53889D01*
G01X397090Y60531D02*
Y52657D01*
G01X394019D02*
Y60531D01*
G01X393989Y60138D02*
Y53889D01*
G01X390033Y60138D02*
Y53889D01*
G01X390003Y60531D02*
Y52657D01*
G01X386932D02*
Y60531D01*
G01X386903Y60138D02*
Y53889D01*
G01X445515Y61712D02*
X446696Y60531D01*
G01X438428Y61712D02*
X439610Y60531D01*
G01X431342Y61712D02*
X432523Y60531D01*
G01X424255Y61712D02*
X425436Y60531D01*
G01X417169Y61712D02*
X418350Y60531D01*
G01X410082Y61712D02*
X411263Y60531D01*
G01X402995Y61712D02*
X404176Y60531D01*
G01X395909Y61712D02*
X397090Y60531D01*
G01X388822Y61712D02*
X390003Y60531D01*
G01X392579Y62697D02*
X448717D01*
G01X388822Y61712D02*
X388113D01*
G01X395909D02*
X395200D01*
G01X402995D02*
X402287D01*
G01X410082D02*
X409373D01*
G01X417169D02*
X416460D01*
G01X424255D02*
X423547D01*
G01X431342D02*
X430633D01*
G01X438428D02*
X437720D01*
G01X445515D02*
X444806D01*
G01X390003Y60531D02*
X386932D01*
G01X397090D02*
X394019D01*
G01X404176D02*
X401106D01*
G01X411263D02*
X408192D01*
G01X418350D02*
X415279D01*
G01X425436D02*
X422365D01*
G01X432523D02*
X429452D01*
G01X439610D02*
X436539D01*
G01X446696D02*
X443625D01*
G01X392579Y58956D02*
X448717D01*
G01X394360Y53051D02*
X389662D01*
G01X401447D02*
X396748D01*
G01X408534D02*
X403835D01*
G01X415620D02*
X410922D01*
G01X422707D02*
X418008D01*
G01X429793D02*
X425095D01*
G01X436880D02*
X432182D01*
G01X443967D02*
X439268D01*
G01X451053D02*
X446355D01*
G01X446696Y52657D02*
X448717D01*
G01X439610D02*
X443625D01*
G01X432523D02*
X436539D01*
G01X425436D02*
X429452D01*
G01X418350D02*
X422365D01*
G01X411263D02*
X415279D01*
G01X404176D02*
X408192D01*
G01X397090D02*
X401106D01*
G01X392579D02*
X394019D01*
G01X390003D02*
X392024D01*
G01X387795Y328740D02*
Y198819D01*
G01D02*
X517716D01*
G01X470728Y287264D02*
X434783D01*
G01D02*
Y240295D01*
G01D02*
X470728D01*
G01X517716Y328740D02*
X387795D01*
G01X393700Y326771D02*
X389763D01*
G01D02*
Y322834D01*
G01D02*
X393700Y326771D01*
G01X417106Y422244D02*
G03I-728J0D01*
G01X425925D02*
G03I-728J0D01*
G01X417106Y407283D02*
G03I-728J0D01*
G01X420059Y410039D02*
G03I-729J0D01*
G01X425925Y407283D02*
G03I-728J0D01*
G01X423012Y412795D02*
G03I-729J0D01*
G01X414114D02*
G03I-728J0D01*
G01X408208Y407283D02*
G03I-728J0D01*
G01X411161Y410039D02*
G03I-728J0D01*
G01X402303D02*
G03I-728J0D01*
G01X405334Y412795D02*
G03I-728J0D01*
G01X408208Y422244D02*
G03I-728J0D01*
G01X424865Y423208D02*
X425565D01*
G01X416006D02*
X416706D01*
G01X407148D02*
X407848D01*
G01Y422992D02*
X407148D01*
G01X416706D02*
X416006D01*
G01X425565D02*
X424865D01*
G01X407848Y422897D02*
X407148D01*
G01X416706D02*
X416006D01*
G01X425565D02*
X424865D01*
G01X407848Y422834D02*
X407148D01*
G01X416706D02*
X416006D01*
G01X425565D02*
X424865D01*
G01X407848Y422736D02*
X407148D01*
G01X416706D02*
X416006D01*
G01X425565D02*
X424865D01*
G01Y422421D02*
X425565D01*
G01X416006D02*
X416706D01*
G01X407148D02*
X407848D01*
G01X416006Y422067D02*
X416706D01*
G01X407848D02*
X407148D01*
G01X425565D02*
X424865D01*
G01X407848Y421752D02*
X407148D01*
G01X416706D02*
X416006D01*
G01X425565D02*
X424865D01*
G01X407848Y421653D02*
X407148D01*
G01X416706D02*
X416006D01*
G01X425565D02*
X424865D01*
G01X407848Y421591D02*
X407148D01*
G01X416706D02*
X416006D01*
G01X425565D02*
X424865D01*
G01X407848Y421496D02*
X407148D01*
G01X416706D02*
X416006D01*
G01X425565D02*
X424865D01*
G01Y421279D02*
X425565D01*
G01X416006D02*
X416706D01*
G01X407148D02*
X407848D01*
G01X425206Y413991D02*
X401584D01*
G01X404895Y413760D02*
X404195D01*
G01X413754D02*
X413054D01*
G01X422612D02*
X421912D01*
G01X404895Y413543D02*
X404195D01*
G01X413754D02*
X413054D01*
G01X422612D02*
X421912D01*
G01X404195Y413448D02*
X404895D01*
G01X413754D02*
X413054D01*
G01X422612D02*
X421912D01*
G01X404195Y413386D02*
X404895D01*
G01X413754D02*
X413054D01*
G01X422612D02*
X421912D01*
G01X404195Y413287D02*
X404895D01*
G01X413754D02*
X413054D01*
G01X422612D02*
X421912D01*
G01Y412972D02*
X422612D01*
G01X413054D02*
X413754D01*
G01X404195D02*
X404895D01*
G01X404195Y412618D02*
X404895D01*
G01X413754D02*
X413054D01*
G01X422612D02*
X421912D01*
G01X404895Y412303D02*
X404195D01*
G01X413754D02*
X413054D01*
G01X422612D02*
X421912D01*
G01X404195Y412204D02*
X404895D01*
G01X413754D02*
X413054D01*
G01X422612D02*
X421912D01*
G01X404195Y412142D02*
X404895D01*
G01X413754D02*
X413054D01*
G01X422612D02*
X421912D01*
G01X404195Y412047D02*
X404895D01*
G01X413754D02*
X413054D01*
G01X422612D02*
X421912D01*
G01X404895Y411830D02*
X404195D01*
G01X413754D02*
X413054D01*
G01X422612D02*
X421912D01*
G01X401943Y411004D02*
X401243D01*
G01X410801D02*
X410101D01*
G01X419659D02*
X418959D01*
G01X401943Y410787D02*
X401243D01*
G01X410801D02*
X410101D01*
G01X419659D02*
X418959D01*
G01X401943Y410692D02*
X401243D01*
G01X410801D02*
X410101D01*
G01X419659D02*
X418959D01*
G01X401943Y410630D02*
X401243D01*
G01X410801D02*
X410101D01*
G01X419659D02*
X418959D01*
G01X401943Y410531D02*
X401243D01*
G01X410801D02*
X410101D01*
G01X419659D02*
X418959D01*
G01Y410216D02*
X419659D01*
G01X410101D02*
X410801D01*
G01X401243D02*
X401943D01*
G01Y409862D02*
X401243D01*
G01X410801D02*
X410101D01*
G01X419659D02*
X418959D01*
G01X401943Y409547D02*
X401243D01*
G01X410801D02*
X410101D01*
G01X419659D02*
X418959D01*
G01X401943Y409449D02*
X401243D01*
G01X410801D02*
X410101D01*
G01X419659D02*
X418959D01*
G01X401943Y409386D02*
X401243D01*
G01X410801D02*
X410101D01*
G01X419659D02*
X418959D01*
G01X401943Y409291D02*
X401243D01*
G01X410801D02*
X410101D01*
G01X419659D02*
X418959D01*
G01X401943Y409075D02*
X401243D01*
G01X410801D02*
X410101D01*
G01X419659D02*
X418959D01*
G01X424865Y408248D02*
X425565D01*
G01X416006D02*
X416706D01*
G01X407148D02*
X407848D01*
G01Y408031D02*
X407148D01*
G01X416706D02*
X416006D01*
G01X425565D02*
X424865D01*
G01X407848Y407936D02*
X407148D01*
G01X416706D02*
X416006D01*
G01X425565D02*
X424865D01*
G01X407848Y407874D02*
X407148D01*
G01X416706D02*
X416006D01*
G01X425565D02*
X424865D01*
G01X407848Y407775D02*
X407148D01*
G01X416706D02*
X416006D01*
G01X425565D02*
X424865D01*
G01Y407460D02*
X425565D01*
G01X416006D02*
X416706D01*
G01X407148D02*
X407848D01*
G01Y407106D02*
X407148D01*
G01X416706D02*
X416006D01*
G01X425565D02*
X424865D01*
G01X407848Y406791D02*
X407148D01*
G01X416706D02*
X416006D01*
G01X425565D02*
X424865D01*
G01X407848Y406693D02*
X407148D01*
G01X416706D02*
X416006D01*
G01X425565D02*
X424865D01*
G01X407848Y406630D02*
X407148D01*
G01X416706D02*
X416006D01*
G01X425565D02*
X424865D01*
G01X407848Y406535D02*
X407148D01*
G01X416706D02*
X416006D01*
G01X425565D02*
X424865D01*
G01Y406319D02*
X425565D01*
G01X416006D02*
X416706D01*
G01X407148D02*
X407848D01*
G01X426789Y404660D02*
X400018D01*
G01X392636Y401826D02*
X434171D01*
G01X425206Y413991D02*
X428466Y401826D01*
G01X434171Y429778D02*
Y401826D01*
G01X432597Y451139D02*
Y401826D01*
G01X431597D02*
Y451139D01*
G01X431097Y401826D02*
Y451139D01*
G01X429555D02*
Y401826D01*
G01X426789D02*
Y404660D01*
G01X425565Y421281D02*
Y423207D01*
G01Y406320D02*
Y408246D01*
G01X425206Y423991D02*
Y413991D01*
G01X424865Y421281D02*
Y423207D01*
G01Y406320D02*
Y408246D01*
G01X422612Y411832D02*
Y413758D01*
G01X421912Y411832D02*
Y413758D01*
G01X419659Y409076D02*
Y411002D01*
G01X418959Y409076D02*
Y411002D01*
G01X416706Y421281D02*
Y423207D01*
G01Y406320D02*
Y408246D01*
G01X416356Y404660D02*
Y401826D01*
G01X416006Y421281D02*
Y423207D01*
G01Y406320D02*
Y408246D01*
G01X414978Y401826D02*
Y404660D01*
G01X413754Y411832D02*
Y413758D01*
G01X413054Y411832D02*
Y413758D01*
G01X410801Y409076D02*
Y411002D01*
G01X410101Y409076D02*
Y411002D01*
G01X407848Y421281D02*
Y423207D01*
G01Y406320D02*
Y408246D01*
G01X407148Y421281D02*
Y423207D01*
G01Y406320D02*
Y408246D01*
G01X405923Y401826D02*
Y404660D01*
G01X404895Y411832D02*
Y413758D01*
G01X404545Y404660D02*
Y401826D01*
G01X404195Y411832D02*
Y413758D01*
G01X401943Y409076D02*
Y411002D01*
G01X401584Y413991D02*
Y423991D01*
G01X401243Y409076D02*
Y411002D01*
G01X400018Y404660D02*
Y401826D01*
G01X397252Y451139D02*
Y401826D01*
G01X395711Y451139D02*
Y401826D01*
G01X395211Y451139D02*
Y401826D01*
G01X394211Y451139D02*
Y401826D01*
G01X392636Y429778D02*
Y401826D01*
G01X401584Y413991D02*
X398325Y401826D01*
G01X420501Y485417D02*
G03X421486Y486401I0J985D01*
G01X420059Y425000D02*
G03I-729J0D01*
G01X423012Y427756D02*
G03I-729J0D01*
G01X414114D02*
G03I-728J0D01*
G01X417106Y437204D02*
G03I-728J0D01*
G01X420059Y439960D02*
G03I-729J0D01*
G01X425925Y437204D02*
G03I-728J0D01*
G01X423012Y442716D02*
G03I-729J0D01*
G01X414114D02*
G03I-728J0D01*
G01X417106Y452165D02*
G03I-728J0D01*
G01X420059Y454921D02*
G03I-729J0D01*
G01X425925Y452165D02*
G03I-728J0D01*
G01X423012Y457677D02*
G03I-729J0D01*
G01X414114D02*
G03I-728J0D01*
G01X440569Y460630D02*
G03I-3543J0D01*
G01X441356D02*
G03I-4330J0D01*
G01X405611Y486401D02*
G03X406596Y485417I984J0D01*
G01X411161Y425000D02*
G03I-728J0D01*
G01X402303D02*
G03I-728J0D01*
G01X405334Y427756D02*
G03I-728J0D01*
G01X408208Y437204D02*
G03I-728J0D01*
G01X411161Y439960D02*
G03I-728J0D01*
G01X402303D02*
G03I-728J0D01*
G01X405334Y442716D02*
G03I-728J0D01*
G01X408208Y452165D02*
G03I-728J0D01*
G01X411161Y454921D02*
G03I-728J0D01*
G01X402303D02*
G03I-728J0D01*
G01X405334Y457677D02*
G03I-728J0D01*
G01X401943Y485625D02*
X401243D01*
G01X407848D02*
X407148D01*
G01X404895D02*
X404195D01*
G01X410801D02*
X410101D01*
G01X413754D02*
X413054D01*
G01X416706D02*
X416006D01*
G01X419659D02*
X418959D01*
G01X422612D02*
X421912D01*
G01X425565D02*
X424865D01*
G01X420501Y485417D02*
X406596D01*
G01X401943Y482661D02*
X401243D01*
G01X407848D02*
X407148D01*
G01X404895D02*
X404195D01*
G01X410801D02*
X410101D01*
G01X413754D02*
X413054D01*
G01X416706D02*
X416006D01*
G01X419659D02*
X418959D01*
G01X422612D02*
X421912D01*
G01X425565D02*
X424865D01*
G01Y482436D02*
X425565D01*
G01X421912D02*
X422612D01*
G01X418959D02*
X419659D01*
G01X416006D02*
X416706D01*
G01X413054D02*
X413754D01*
G01X410101D02*
X410801D01*
G01X407148D02*
X407848D01*
G01X404195D02*
X404895D01*
G01X401243D02*
X401943D01*
G01X438352Y480575D02*
X388455D01*
G01X435708Y473041D02*
X441305D01*
G01X428856Y472643D02*
X397951D01*
G01X431771Y472057D02*
X395000D01*
G01X428856Y471856D02*
X397951D01*
G01X395786Y471730D02*
X431022D01*
G01X421615Y471139D02*
X405192D01*
G01X404895Y458641D02*
X404195D01*
G01X413754D02*
X413054D01*
G01X422612D02*
X421912D01*
G01X404895Y458425D02*
X404195D01*
G01X413754D02*
X413054D01*
G01X422612D02*
X421912D01*
G01X404895Y458330D02*
X404195D01*
G01X413754D02*
X413054D01*
G01X422612D02*
X421912D01*
G01X404895Y458267D02*
X404195D01*
G01X413754D02*
X413054D01*
G01X422612D02*
X421912D01*
G01X404895Y458169D02*
X404195D01*
G01X413754D02*
X413054D01*
G01X422612D02*
X421912D01*
G01Y457854D02*
X422612D01*
G01X413054D02*
X413754D01*
G01X404195D02*
X404895D01*
G01Y457500D02*
X404195D01*
G01X413754D02*
X413054D01*
G01X422612D02*
X421912D01*
G01X404895Y457185D02*
X404195D01*
G01X413754D02*
X413054D01*
G01X422612D02*
X421912D01*
G01X404895Y457086D02*
X404195D01*
G01X413754D02*
X413054D01*
G01X422612D02*
X421912D01*
G01X404895Y457024D02*
X404195D01*
G01X413754D02*
X413054D01*
G01X422612D02*
X421912D01*
G01X404895Y456929D02*
X404195D01*
G01X413754D02*
X413054D01*
G01X422612D02*
X421912D01*
G01X404895Y456712D02*
X404195D01*
G01X413754D02*
X413054D01*
G01X422612D02*
X421912D01*
G01X401943Y455886D02*
X401243D01*
G01X410801D02*
X410101D01*
G01X419659D02*
X418959D01*
G01X401943Y455669D02*
X401243D01*
G01X410801D02*
X410101D01*
G01X419659D02*
X418959D01*
G01X401943Y455574D02*
X401243D01*
G01X410801D02*
X410101D01*
G01X419659D02*
X418959D01*
G01X401943Y455512D02*
X401243D01*
G01X410801D02*
X410101D01*
G01X419659D02*
X418959D01*
G01X401943Y455413D02*
X401243D01*
G01X410801D02*
X410101D01*
G01X419659D02*
X418959D01*
G01Y455098D02*
X419659D01*
G01X410101D02*
X410801D01*
G01X401243D02*
X401943D01*
G01Y454744D02*
X401243D01*
G01X410801D02*
X410101D01*
G01X419659D02*
X418959D01*
G01X401943Y454429D02*
X401243D01*
G01X410801D02*
X410101D01*
G01X419659D02*
X418959D01*
G01X401943Y454330D02*
X401243D01*
G01X410801D02*
X410101D01*
G01X419659D02*
X418959D01*
G01X401943Y454268D02*
X401243D01*
G01X410801D02*
X410101D01*
G01X419659D02*
X418959D01*
G01X401943Y454173D02*
X401243D01*
G01X410801D02*
X410101D01*
G01X419659D02*
X418959D01*
G01X401943Y453956D02*
X401243D01*
G01X410801D02*
X410101D01*
G01X419659D02*
X418959D01*
G01X426604Y453307D02*
X426909D01*
G01X424865Y453130D02*
X425565D01*
G01X416006D02*
X416706D01*
G01X407148D02*
X407848D01*
G01Y452913D02*
X407148D01*
G01X416706D02*
X416006D01*
G01X425565D02*
X424865D01*
G01X407148Y452818D02*
X407848D01*
G01X416706D02*
X416006D01*
G01X425565D02*
X424865D01*
G01X407848Y452756D02*
X407148D01*
G01X416706D02*
X416006D01*
G01X425565D02*
X424865D01*
G01X407148Y452657D02*
X407848D01*
G01X416706D02*
X416006D01*
G01X425565D02*
X424865D01*
G01Y452342D02*
X425565D01*
G01X416006D02*
X416706D01*
G01X407148D02*
X407848D01*
G01X407148Y451988D02*
X407848D01*
G01X416706D02*
X416006D01*
G01X425565D02*
X424865D01*
G01X407848Y451673D02*
X407148D01*
G01X416706D02*
X416006D01*
G01X425565D02*
X424865D01*
G01X407848Y451575D02*
X407148D01*
G01X416706D02*
X416006D01*
G01X425565D02*
X424865D01*
G01X407148Y451512D02*
X407848D01*
G01X416706D02*
X416006D01*
G01X425565D02*
X424865D01*
G01X407848Y451417D02*
X407148D01*
G01X416706D02*
X416006D01*
G01X425565D02*
X424865D01*
G01Y451201D02*
X425565D01*
G01X416006D02*
X416706D01*
G01X407148D02*
X407848D01*
G01X426909Y450866D02*
X426604D01*
G01X404895Y443681D02*
X404195D01*
G01X413754D02*
X413054D01*
G01X422612D02*
X421912D01*
G01X404895Y443464D02*
X404195D01*
G01X413754D02*
X413054D01*
G01X422612D02*
X421912D01*
G01X404895Y443369D02*
X404195D01*
G01X413754D02*
X413054D01*
G01X422612D02*
X421912D01*
G01X404895Y443307D02*
X404195D01*
G01X413754D02*
X413054D01*
G01X422612D02*
X421912D01*
G01X404895Y443208D02*
X404195D01*
G01X413754D02*
X413054D01*
G01X422612D02*
X421912D01*
G01Y442893D02*
X422612D01*
G01X413054D02*
X413754D01*
G01X404195D02*
X404895D01*
G01Y442539D02*
X404195D01*
G01X413754D02*
X413054D01*
G01X422612D02*
X421912D01*
G01X404895Y442224D02*
X404195D01*
G01X413754D02*
X413054D01*
G01X422612D02*
X421912D01*
G01X404895Y442126D02*
X404195D01*
G01X413754D02*
X413054D01*
G01X422612D02*
X421912D01*
G01X404895Y442063D02*
X404195D01*
G01X413754D02*
X413054D01*
G01X422612D02*
X421912D01*
G01X404895Y441968D02*
X404195D01*
G01X413754D02*
X413054D01*
G01X422612D02*
X421912D01*
G01X404895Y441752D02*
X404195D01*
G01X413754D02*
X413054D01*
G01X422612D02*
X421912D01*
G01X401943Y440925D02*
X401243D01*
G01X410801D02*
X410101D01*
G01X419659D02*
X418959D01*
G01X401943Y440708D02*
X401243D01*
G01X410801D02*
X410101D01*
G01X419659D02*
X418959D01*
G01X401943Y440613D02*
X401243D01*
G01X410801D02*
X410101D01*
G01X419659D02*
X418959D01*
G01X401943Y440551D02*
X401243D01*
G01X410801D02*
X410101D01*
G01X419659D02*
X418959D01*
G01X401943Y440452D02*
X401243D01*
G01X410801D02*
X410101D01*
G01X419659D02*
X418959D01*
G01Y440138D02*
X419659D01*
G01X410101D02*
X410801D01*
G01X401243D02*
X401943D01*
G01Y439783D02*
X401243D01*
G01X410801D02*
X410101D01*
G01X419659D02*
X418959D01*
G01X401943Y439468D02*
X401243D01*
G01X410801D02*
X410101D01*
G01X419659D02*
X418959D01*
G01X401943Y439370D02*
X401243D01*
G01X410801D02*
X410101D01*
G01X419659D02*
X418959D01*
G01X401943Y439307D02*
X401243D01*
G01X410801D02*
X410101D01*
G01X419659D02*
X418959D01*
G01X401943Y439212D02*
X401243D01*
G01X410801D02*
X410101D01*
G01X419659D02*
X418959D01*
G01X401943Y438996D02*
X401243D01*
G01X410801D02*
X410101D01*
G01X419659D02*
X418959D01*
G01X424865Y438169D02*
X425565D01*
G01X416006D02*
X416706D01*
G01X407148D02*
X407848D01*
G01X441305Y470088D02*
X443228Y468165D01*
G01X435708Y473041D02*
X438661Y470088D01*
G01X432756Y471073D02*
X431771Y472057D01*
G01X405192Y471139D02*
X406243Y470088D01*
G01X407848Y437952D02*
X407148D01*
G01X416706D02*
X416006D01*
G01X425565D02*
X424865D01*
G01X407148Y437857D02*
X407848D01*
G01X416706D02*
X416006D01*
G01X425565D02*
X424865D01*
G01X407848Y437795D02*
X407148D01*
G01X416706D02*
X416006D01*
G01X425565D02*
X424865D01*
G01X407148Y437697D02*
X407848D01*
G01X416706D02*
X416006D01*
G01X425565D02*
X424865D01*
G01Y437382D02*
X425565D01*
G01X416006D02*
X416706D01*
G01X407148D02*
X407848D01*
G01X407148Y437027D02*
X407848D01*
G01X416706D02*
X416006D01*
G01X425565D02*
X424865D01*
G01X407848Y436712D02*
X407148D01*
G01X416706D02*
X416006D01*
G01X425565D02*
X424865D01*
G01X407848Y436614D02*
X407148D01*
G01X416706D02*
X416006D01*
G01X425565D02*
X424865D01*
G01X407148Y436552D02*
X407848D01*
G01X416706D02*
X416006D01*
G01X425565D02*
X424865D01*
G01X407848Y436456D02*
X407148D01*
G01X416706D02*
X416006D01*
G01X425565D02*
X424865D01*
G01Y436240D02*
X425565D01*
G01X416006D02*
X416706D01*
G01X407148D02*
X407848D01*
G01X404895Y428720D02*
X404195D01*
G01X413754D02*
X413054D01*
G01X422612D02*
X421912D01*
G01X404895Y428504D02*
X404195D01*
G01X413754D02*
X413054D01*
G01X422612D02*
X421912D01*
G01X404895Y428409D02*
X404195D01*
G01X413754D02*
X413054D01*
G01X422612D02*
X421912D01*
G01X404895Y428346D02*
X404195D01*
G01X413754D02*
X413054D01*
G01X422612D02*
X421912D01*
G01X404895Y428248D02*
X404195D01*
G01X413754D02*
X413054D01*
G01X422612D02*
X421912D01*
G01Y427933D02*
X422612D01*
G01X413054D02*
X413754D01*
G01X404195D02*
X404895D01*
G01Y427578D02*
X404195D01*
G01X413754D02*
X413054D01*
G01X422612D02*
X421912D01*
G01X404895Y427264D02*
X404195D01*
G01X413754D02*
X413054D01*
G01X422612D02*
X421912D01*
G01X404895Y427165D02*
X404195D01*
G01X413754D02*
X413054D01*
G01X422612D02*
X421912D01*
G01X404895Y427103D02*
X404195D01*
G01X413754D02*
X413054D01*
G01X422612D02*
X421912D01*
G01X404895Y427008D02*
X404195D01*
G01X413754D02*
X413054D01*
G01X422612D02*
X421912D01*
G01X404895Y426791D02*
X404195D01*
G01X413754D02*
X413054D01*
G01X422612D02*
X421912D01*
G01X401943Y425964D02*
X401243D01*
G01X410801D02*
X410101D01*
G01X419659D02*
X418959D01*
G01X401943Y425748D02*
X401243D01*
G01X410801D02*
X410101D01*
G01X419659D02*
X418959D01*
G01X410101Y425653D02*
X410801D01*
G01X401943D02*
X401243D01*
G01X419659D02*
X418959D01*
G01X410101Y425590D02*
X410801D01*
G01X401943D02*
X401243D01*
G01X419659D02*
X418959D01*
G01X410101Y425492D02*
X410801D01*
G01X401943D02*
X401243D01*
G01X419659D02*
X418959D01*
G01Y425177D02*
X419659D01*
G01X410101D02*
X410801D01*
G01X401243D02*
X401943D01*
G01X410101Y424823D02*
X410801D01*
G01X401943D02*
X401243D01*
G01X419659D02*
X418959D01*
G01X401943Y424508D02*
X401243D01*
G01X410801D02*
X410101D01*
G01X419659D02*
X418959D01*
G01X410101Y424409D02*
X410801D01*
G01X401943D02*
X401243D01*
G01X419659D02*
X418959D01*
G01X410101Y424347D02*
X410801D01*
G01X401943D02*
X401243D01*
G01X419659D02*
X418959D01*
G01X410101Y424252D02*
X410801D01*
G01X401943D02*
X401243D01*
G01X419659D02*
X418959D01*
G01X401943Y424035D02*
X401243D01*
G01X410801D02*
X410101D01*
G01X419659D02*
X418959D01*
G01X401584Y423991D02*
X425206D01*
G01X405372Y471730D02*
X406435Y470428D01*
G01X393031Y472057D02*
X395000Y470088D01*
G01X432597Y431353D02*
X434171Y429778D01*
G01X406631Y470088D02*
X406435Y470428D01*
G01X405372Y471730D02*
X406320Y470088D01*
G01X443228Y468165D02*
Y453062D01*
G01X441305Y494993D02*
Y470088D01*
G01X439927Y495978D02*
Y451139D01*
G01X438352Y495978D02*
Y451139D01*
G01X435708Y495978D02*
Y473041D01*
G01X433740Y494009D02*
Y472057D01*
G01X431771Y494009D02*
Y472057D01*
G01X431022Y495978D02*
Y470088D01*
G01X428856Y492041D02*
Y471856D01*
G01X426909Y453307D02*
Y450866D01*
G01X426604D02*
Y452891D01*
G01X426299Y452528D02*
Y452943D01*
G01X425565Y451202D02*
Y453128D01*
G01Y436242D02*
Y438168D01*
G01Y488604D02*
Y482436D01*
G01X424865Y451202D02*
Y453128D01*
G01Y436241D02*
Y438167D01*
G01Y488604D02*
Y482436D01*
G01X422612Y456714D02*
Y458640D01*
G01Y441753D02*
Y443679D01*
G01Y426793D02*
Y428719D01*
G01Y488604D02*
Y482436D01*
G01X421912Y456714D02*
Y458640D01*
G01Y441753D02*
Y443679D01*
G01Y426792D02*
Y428718D01*
G01Y488604D02*
Y482436D01*
G01X420372Y470428D02*
Y470088D01*
G01X419659Y453958D02*
Y455884D01*
G01Y438998D02*
Y440924D01*
G01Y424037D02*
Y425963D01*
G01Y488604D02*
Y482436D01*
G01X418959Y453958D02*
Y455884D01*
G01Y438997D02*
Y440923D01*
G01Y424037D02*
Y425963D01*
G01Y488604D02*
Y482436D01*
G01X416706Y451202D02*
Y453128D01*
G01Y436242D02*
Y438168D01*
G01Y488604D02*
Y482436D01*
G01X416006Y451202D02*
Y453128D01*
G01Y436241D02*
Y438167D01*
G01Y488604D02*
Y482436D01*
G01X413754Y456714D02*
Y458640D01*
G01Y441753D02*
Y443679D01*
G01Y426793D02*
Y428719D01*
G01Y488604D02*
Y482436D01*
G01X413054Y456714D02*
Y458640D01*
G01Y441753D02*
Y443679D01*
G01Y426792D02*
Y428718D01*
G01Y488604D02*
Y482436D01*
G01X410801Y453958D02*
Y455884D01*
G01Y438998D02*
Y440924D01*
G01Y424037D02*
Y425963D01*
G01Y488604D02*
Y482436D01*
G01X410101Y453958D02*
Y455884D01*
G01Y438997D02*
Y440923D01*
G01Y424037D02*
Y425963D01*
G01Y488604D02*
Y482436D01*
G01X407848Y451202D02*
Y453128D01*
G01Y436242D02*
Y438168D01*
G01Y488604D02*
Y482436D01*
G01X407148Y451202D02*
Y453128D01*
G01Y436241D02*
Y438167D01*
G01Y488604D02*
Y482436D01*
G01X406435Y470428D02*
Y470088D01*
G01X404895Y456714D02*
Y458640D01*
G01Y441753D02*
Y443679D01*
G01Y426793D02*
Y428719D01*
G01Y488604D02*
Y482436D01*
G01X404195Y456714D02*
Y458640D01*
G01Y441753D02*
Y443679D01*
G01Y426792D02*
Y428718D01*
G01Y488604D02*
Y482436D01*
G01X401943Y453958D02*
Y455884D01*
G01Y438998D02*
Y440924D01*
G01Y424037D02*
Y425963D01*
G01Y488604D02*
Y482436D01*
G01X401243Y453958D02*
Y455884D01*
G01Y438997D02*
Y440923D01*
G01Y424037D02*
Y425963D01*
G01Y488604D02*
Y482436D01*
G01X397951Y492041D02*
Y471856D01*
G01X395786Y495978D02*
Y470088D01*
G01X395000Y472057D02*
Y494009D01*
G01X393031D02*
Y472057D01*
G01X391063Y473041D02*
Y495978D01*
G01X388455D02*
Y451139D01*
G01X420487Y470088D02*
X421435Y471730D01*
G01X420372Y470428D02*
X420176Y470088D01*
G01X443228Y453062D02*
X441305Y451139D01*
G01X426604Y452891D02*
X426299Y452528D01*
G01Y452943D02*
X426604Y453307D01*
G01X421435Y471730D02*
X420372Y470428D01*
G01X394211Y431353D02*
X392636Y429778D01*
G01X433740Y472057D02*
X431771Y470088D01*
G01X420564D02*
X421615Y471139D01*
G01X394015Y471073D02*
X395000Y472057D01*
G01X388110Y470088D02*
X391063Y473041D01*
G01X415943Y539991D02*
G03I-4291J0D01*
G01X474316Y509060D02*
X442287Y503937D01*
G01X441305Y494993D02*
G03X440321Y495978I-985J0D01*
G01X421486Y490141D02*
G03X420501Y491126I-985J0D01*
G01X406596D02*
G03X405611Y490141I0J-985D01*
G01X431022Y494978D02*
X395786D01*
G01X395000Y494009D02*
X431771D01*
G01X428856Y492041D02*
X397951D01*
G01X406596Y491126D02*
X420501D01*
G01X401943Y488604D02*
X401243D01*
G01X407848D02*
X407148D01*
G01X404895D02*
X404195D01*
G01X410801D02*
X410101D01*
G01X413754D02*
X413054D01*
G01X416706D02*
X416006D01*
G01X419659D02*
X418959D01*
G01X422612D02*
X421912D01*
G01X425565D02*
X424865D01*
G01X475560Y501285D02*
X442913Y496063D01*
G01X431771Y494009D02*
X432756Y493025D01*
G01X394015D02*
X391063Y495978D01*
G01X397951Y492041D02*
X396770Y495978D01*
G01X421486Y490141D02*
Y486401D01*
G01X405611D02*
Y490141D01*
G01X430038Y495978D02*
X428856Y492041D01*
G01X435708Y495978D02*
X432756Y493025D01*
G01X394015D02*
X395000Y494009D01*
G01X496148Y-879845D02*
X1677743D01*
G01X504911Y-100963D02*
Y-103762D01*
G01X473416Y-100963D02*
Y-103762D01*
G01X506655Y-39738D02*
X506759Y-39665D01*
G01X506530Y-39764D02*
X506655Y-39738D01*
G01X457676Y-39739D02*
X457799Y-39764D01*
G01X457571Y-39666D02*
X457676Y-39739D01*
G01X471849D02*
X471972Y-39764D01*
G01X471744Y-39666D02*
X471849Y-39739D01*
G01X486022D02*
X486145Y-39764D01*
G01X485917Y-39666D02*
X486022Y-39739D01*
G01X500195D02*
X500319Y-39764D01*
G01X500090Y-39666D02*
X500195Y-39739D01*
G01X451700Y-38609D02*
X451695Y-38615D01*
G01X451716Y-38589D02*
X451700Y-38609D01*
G01X451742Y-38556D02*
X451716Y-38589D01*
G01X451776Y-38512D02*
X451742Y-38556D01*
G01X451816Y-38457D02*
X451776Y-38512D01*
G01X451861Y-38389D02*
X451816Y-38457D01*
G01X451908Y-38312D02*
X451861Y-38389D01*
G01X451951Y-38233D02*
X451908Y-38312D01*
G01X451987Y-38160D02*
X451951Y-38233D01*
G01X452015Y-38092D02*
X451987Y-38160D01*
G01X452036Y-38029D02*
X452015Y-38092D01*
G01X452048Y-37971D02*
X452036Y-38029D01*
G01X452052Y-37920D02*
X452048Y-37971D01*
G01X452046Y-37878D02*
X452052Y-37920D01*
G01X452033Y-37844D02*
X452046Y-37878D01*
G01X452016Y-37819D02*
X452033Y-37844D01*
G01X452003Y-37804D02*
X452016Y-37819D01*
G01X451997Y-37799D02*
X452003Y-37804D01*
G01X465874Y-38609D02*
X465868Y-38615D01*
G01X465890Y-38589D02*
X465874Y-38609D01*
G01X465916Y-38556D02*
X465890Y-38589D01*
G01X465949Y-38512D02*
X465916Y-38556D01*
G01X465989Y-38457D02*
X465949Y-38512D01*
G01X466034Y-38389D02*
X465989Y-38457D01*
G01X466082Y-38312D02*
X466034Y-38389D01*
G01X466125Y-38233D02*
X466082Y-38312D01*
G01X466160Y-38160D02*
X466125Y-38233D01*
G01X466188Y-38092D02*
X466160Y-38160D01*
G01X466209Y-38029D02*
X466188Y-38092D01*
G01X466221Y-37971D02*
X466209Y-38029D01*
G01X466225Y-37920D02*
X466221Y-37971D01*
G01X466219Y-37878D02*
X466225Y-37920D01*
G01X466206Y-37844D02*
X466219Y-37878D01*
G01X466190Y-37819D02*
X466206Y-37844D01*
G01X466176Y-37804D02*
X466190Y-37819D01*
G01X466170Y-37799D02*
X466176Y-37804D01*
G01X480047Y-38609D02*
X480042Y-38615D01*
G01X480063Y-38589D02*
X480047Y-38609D01*
G01X480089Y-38556D02*
X480063Y-38589D01*
G01X480122Y-38512D02*
X480089Y-38556D01*
G01X480162Y-38457D02*
X480122Y-38512D01*
G01X480207Y-38389D02*
X480162Y-38457D01*
G01X480255Y-38312D02*
X480207Y-38389D01*
G01X480298Y-38233D02*
X480255Y-38312D01*
G01X480333Y-38160D02*
X480298Y-38233D01*
G01X480361Y-38092D02*
X480333Y-38160D01*
G01X480382Y-38029D02*
X480361Y-38092D01*
G01X480395Y-37971D02*
X480382Y-38029D01*
G01X480398Y-37920D02*
X480395Y-37971D01*
G01X480392Y-37878D02*
X480398Y-37920D01*
G01X480379Y-37844D02*
X480392Y-37878D01*
G01X480363Y-37819D02*
X480379Y-37844D01*
G01X480349Y-37804D02*
X480363Y-37819D01*
G01X480343Y-37799D02*
X480349Y-37804D01*
G01X494220Y-38609D02*
X494215Y-38615D01*
G01X494236Y-38589D02*
X494220Y-38609D01*
G01X494262Y-38556D02*
X494236Y-38589D01*
G01X494296Y-38512D02*
X494262Y-38556D01*
G01X494335Y-38457D02*
X494296Y-38512D01*
G01X494380Y-38389D02*
X494335Y-38457D01*
G01X494428Y-38312D02*
X494380Y-38389D01*
G01X494471Y-38233D02*
X494428Y-38312D01*
G01X494506Y-38160D02*
X494471Y-38233D01*
G01X494535Y-38092D02*
X494506Y-38160D01*
G01X494555Y-38029D02*
X494535Y-38092D01*
G01X494568Y-37971D02*
X494555Y-38029D01*
G01X494571Y-37920D02*
X494568Y-37971D01*
G01X494566Y-37878D02*
X494571Y-37920D01*
G01X494552Y-37844D02*
X494566Y-37878D01*
G01X494536Y-37819D02*
X494552Y-37844D01*
G01X494522Y-37804D02*
X494536Y-37819D01*
G01X494517Y-37799D02*
X494522Y-37804D01*
G01X508393Y-38609D02*
X508388Y-38615D01*
G01X508409Y-38589D02*
X508393Y-38609D01*
G01X508435Y-38556D02*
X508409Y-38589D01*
G01X508469Y-38512D02*
X508435Y-38556D01*
G01X508509Y-38457D02*
X508469Y-38512D01*
G01X508554Y-38389D02*
X508509Y-38457D01*
G01X508601Y-38312D02*
X508554Y-38389D01*
G01X508644Y-38233D02*
X508601Y-38312D01*
G01X508680Y-38160D02*
X508644Y-38233D01*
G01X508708Y-38092D02*
X508680Y-38160D01*
G01X508729Y-38029D02*
X508708Y-38092D01*
G01X508741Y-37971D02*
X508729Y-38029D01*
G01X508744Y-37920D02*
X508741Y-37971D01*
G01X508739Y-37878D02*
X508744Y-37920D01*
G01X508726Y-37844D02*
X508739Y-37878D01*
G01X508709Y-37819D02*
X508726Y-37844D01*
G01X508696Y-37804D02*
X508709Y-37819D01*
G01X508690Y-37799D02*
X508696Y-37804D01*
G01X455596Y-37808D02*
X455601Y-37803D01*
G01X455582Y-37823D02*
X455596Y-37808D01*
G01X455566Y-37848D02*
X455582Y-37823D01*
G01X455554Y-37881D02*
X455566Y-37848D01*
G01X455548Y-37923D02*
X455554Y-37881D01*
G01X455551Y-37973D02*
X455548Y-37923D01*
G01X455564Y-38030D02*
X455551Y-37973D01*
G01X455584Y-38092D02*
X455564Y-38030D01*
G01X455612Y-38160D02*
X455584Y-38092D01*
G01X455648Y-38235D02*
X455612Y-38160D01*
G01X455692Y-38315D02*
X455648Y-38235D01*
G01X455738Y-38390D02*
X455692Y-38315D01*
G01X455781Y-38455D02*
X455738Y-38390D01*
G01X455820Y-38510D02*
X455781Y-38455D01*
G01X455854Y-38553D02*
X455820Y-38510D01*
G01X455879Y-38586D02*
X455854Y-38553D01*
G01X455895Y-38605D02*
X455879Y-38586D01*
G01X455900Y-38611D02*
X455895Y-38605D01*
G01X469769Y-37808D02*
X469775Y-37803D01*
G01X469756Y-37823D02*
X469769Y-37808D01*
G01X469740Y-37848D02*
X469756Y-37823D01*
G01X469727Y-37881D02*
X469740Y-37848D01*
G01X469722Y-37923D02*
X469727Y-37881D01*
G01X469725Y-37973D02*
X469722Y-37923D01*
G01X469737Y-38030D02*
X469725Y-37973D01*
G01X469757Y-38092D02*
X469737Y-38030D01*
G01X469785Y-38160D02*
X469757Y-38092D01*
G01X469821Y-38235D02*
X469785Y-38160D01*
G01X469865Y-38315D02*
X469821Y-38235D01*
G01X469911Y-38390D02*
X469865Y-38315D01*
G01X469955Y-38455D02*
X469911Y-38390D01*
G01X469994Y-38510D02*
X469955Y-38455D01*
G01X470027Y-38553D02*
X469994Y-38510D01*
G01X470053Y-38586D02*
X470027Y-38553D01*
G01X470068Y-38605D02*
X470053Y-38586D01*
G01X470073Y-38611D02*
X470068Y-38605D01*
G01X483942Y-37808D02*
X483948Y-37803D01*
G01X483929Y-37823D02*
X483942Y-37808D01*
G01X483913Y-37848D02*
X483929Y-37823D01*
G01X483900Y-37881D02*
X483913Y-37848D01*
G01X483895Y-37923D02*
X483900Y-37881D01*
G01X483898Y-37973D02*
X483895Y-37923D01*
G01X483910Y-38030D02*
X483898Y-37973D01*
G01X483930Y-38092D02*
X483910Y-38030D01*
G01X483958Y-38160D02*
X483930Y-38092D01*
G01X483994Y-38235D02*
X483958Y-38160D01*
G01X484038Y-38315D02*
X483994Y-38235D01*
G01X484085Y-38390D02*
X484038Y-38315D01*
G01X484128Y-38455D02*
X484085Y-38390D01*
G01X484167Y-38510D02*
X484128Y-38455D01*
G01X484200Y-38553D02*
X484167Y-38510D01*
G01X484226Y-38586D02*
X484200Y-38553D01*
G01X484242Y-38605D02*
X484226Y-38586D01*
G01X484247Y-38611D02*
X484242Y-38605D01*
G01X498115Y-37808D02*
X498121Y-37803D01*
G01X498102Y-37823D02*
X498115Y-37808D01*
G01X498086Y-37848D02*
X498102Y-37823D01*
G01X498074Y-37881D02*
X498086Y-37848D01*
G01X498068Y-37923D02*
X498074Y-37881D01*
G01X498071Y-37973D02*
X498068Y-37923D01*
G01X498083Y-38030D02*
X498071Y-37973D01*
G01X498104Y-38092D02*
X498083Y-38030D01*
G01X498132Y-38160D02*
X498104Y-38092D01*
G01X498168Y-38235D02*
X498132Y-38160D01*
G01X498212Y-38315D02*
X498168Y-38235D01*
G01X498258Y-38390D02*
X498212Y-38315D01*
G01X498301Y-38455D02*
X498258Y-38390D01*
G01X498340Y-38510D02*
X498301Y-38455D01*
G01X498373Y-38553D02*
X498340Y-38510D01*
G01X498399Y-38586D02*
X498373Y-38553D01*
G01X498415Y-38605D02*
X498399Y-38586D01*
G01X498420Y-38611D02*
X498415Y-38605D01*
G01X451306Y-39375D02*
X451123Y-39494D01*
G01X451430Y-39251D02*
X451306Y-39375D01*
G01X451509Y-39119D02*
X451430Y-39251D01*
G01X465479Y-39375D02*
X465296Y-39494D01*
G01X465603Y-39251D02*
X465479Y-39375D01*
G01X465682Y-39119D02*
X465603Y-39251D01*
G01X450066Y-39666D02*
X449962Y-39739D01*
G01X450133Y-39558D02*
X450066Y-39666D01*
G01X464239D02*
X464135Y-39739D01*
G01X464306Y-39558D02*
X464239Y-39666D01*
G01X507999Y-39375D02*
X507816Y-39494D01*
G01X508123Y-39251D02*
X507999Y-39375D01*
G01X508202Y-39119D02*
X508123Y-39251D01*
G01X479652Y-39375D02*
X479469Y-39494D01*
G01X479776Y-39251D02*
X479652Y-39375D01*
G01X479855Y-39119D02*
X479776Y-39251D01*
G01X493825Y-39375D02*
X493642Y-39494D01*
G01X493950Y-39251D02*
X493825Y-39375D01*
G01X494029Y-39119D02*
X493950Y-39251D01*
G01X478412Y-39666D02*
X478308Y-39739D01*
G01X478479Y-39558D02*
X478412Y-39666D01*
G01X492585D02*
X492481Y-39739D01*
G01X492653Y-39558D02*
X492585Y-39666D01*
G01X450261Y-39706D02*
X449793Y-39764D01*
G01X450670Y-39559D02*
X450261Y-39706D01*
G01X451043Y-39339D02*
X450670Y-39559D01*
G01X464434Y-39706D02*
X463967Y-39764D01*
G01X464844Y-39559D02*
X464434Y-39706D01*
G01X465216Y-39339D02*
X464844Y-39559D01*
G01X478607Y-39706D02*
X478140Y-39764D01*
G01X479017Y-39559D02*
X478607Y-39706D01*
G01X479389Y-39339D02*
X479017Y-39559D01*
G01X492781Y-39706D02*
X492313Y-39764D01*
G01X493190Y-39559D02*
X492781Y-39706D01*
G01X493562Y-39339D02*
X493190Y-39559D01*
G01X506954Y-39706D02*
X506486Y-39764D01*
G01X507363Y-39559D02*
X506954Y-39706D01*
G01X507736Y-39339D02*
X507363Y-39559D01*
G01X451070Y-39519D02*
X451043Y-39531D01*
G01X451097Y-39507D02*
X451070Y-39519D01*
G01X451123Y-39494D02*
X451097Y-39507D01*
G01X465243Y-39519D02*
X465216Y-39531D01*
G01X465270Y-39507D02*
X465243Y-39519D01*
G01X465296Y-39494D02*
X465270Y-39507D01*
G01X479417Y-39519D02*
X479389Y-39531D01*
G01X479443Y-39507D02*
X479417Y-39519D01*
G01X479469Y-39494D02*
X479443Y-39507D01*
G01X493590Y-39519D02*
X493562Y-39531D01*
G01X493617Y-39507D02*
X493590Y-39519D01*
G01X493642Y-39494D02*
X493617Y-39507D01*
G01X507763Y-39519D02*
X507736Y-39531D01*
G01X507790Y-39507D02*
X507763Y-39519D01*
G01X507816Y-39494D02*
X507790Y-39507D01*
G01X450152Y-39549D02*
X450133Y-39558D01*
G01X450206Y-39525D02*
X450152Y-39549D01*
G01X450287Y-39490D02*
X450206Y-39525D01*
G01X450383Y-39449D02*
X450287Y-39490D01*
G01X464326Y-39549D02*
X464306Y-39558D01*
G01X464380Y-39525D02*
X464326Y-39549D01*
G01X464460Y-39490D02*
X464380Y-39525D01*
G01X464556Y-39449D02*
X464460Y-39490D01*
G01X478499Y-39549D02*
X478479Y-39558D01*
G01X478553Y-39525D02*
X478499Y-39549D01*
G01X478634Y-39490D02*
X478553Y-39525D01*
G01X478730Y-39449D02*
X478634Y-39490D01*
G01X492672Y-39549D02*
X492653Y-39558D01*
G01X492726Y-39525D02*
X492672Y-39549D01*
G01X492807Y-39490D02*
X492726Y-39525D01*
G01X492903Y-39449D02*
X492807Y-39490D01*
G01X506845Y-39549D02*
X506826Y-39558D01*
G01X506899Y-39525D02*
X506845Y-39549D01*
G01X506980Y-39490D02*
X506899Y-39525D01*
G01X507076Y-39449D02*
X506980Y-39490D01*
G01X507658Y-36172D02*
G03X507755Y-35626I-1478J544D01*
G01X508027Y-36308D02*
G03X508149Y-35626I-1847J682D01*
G01X508212Y-36377D02*
G03X508346Y-35626I-2032J750D01*
G01X507733Y-39325D02*
G03X508388Y-38615I-1372J1923D01*
G01X508690Y-37797D02*
G03X508723Y-37402I-2329J393D01*
G01X506530Y-39764D02*
G03X506826Y-39558I0J316D01*
G01X499094Y-35626D02*
G03X499191Y-36172I1575J-2D01*
G01X493484D02*
G03X493582Y-35626I-1477J547D01*
G01X484921D02*
G03X485018Y-36172I1574J-2D01*
G01X484527Y-35626D02*
G03X484649Y-36308I1967J0D01*
G01X498700Y-35626D02*
G03X498822Y-36308I1969J0D01*
G01X493854D02*
G03X493976Y-35626I-1847J682D01*
G01X484330D02*
G03X484464Y-36377I2165J-1D01*
G01X498503Y-35626D02*
G03X498637Y-36377I2166J-1D01*
G01X494038D02*
G03X494173Y-35626I-2031J753D01*
G01X483913Y-37402D02*
G03X483948Y-37803I2363J4D01*
G01X484247Y-38611D02*
G03X486276Y-39764I2029J1209D01*
G01X493560Y-39325D02*
G03X494215Y-38615I-1372J1923D01*
G01X494517Y-37799D02*
G03X494550Y-37402I-2329J393D01*
G01X498087D02*
G03X498121Y-37803I2362J-2D01*
G01X498420Y-38611D02*
G03X500449Y-39764I2029J1209D01*
G01X500023Y-39558D02*
G03X500319Y-39764I296J110D01*
G01X492357D02*
G03X492653Y-39558I0J316D01*
G01X485850D02*
G03X486145Y-39764I295J108D01*
G01X479311Y-36172D02*
G03X479409Y-35626I-1477J547D01*
G01X470747D02*
G03X470845Y-36172I1575J1D01*
G01X465138D02*
G03X465236Y-35626I-1477J547D01*
G01X470354D02*
G03X470476Y-36308I1967J0D01*
G01X465507D02*
G03X465629Y-35626I-1845J682D01*
G01X479680Y-36308D02*
G03X479802Y-35626I-1845J682D01*
G01X470157D02*
G03X470291Y-36377I2165J-1D01*
G01X465692D02*
G03X465826Y-35626I-2031J750D01*
G01X479865Y-36377D02*
G03X479999Y-35626I-2031J750D01*
G01X465213Y-39325D02*
G03X465869Y-38615I-1371J1924D01*
G01X466170Y-37797D02*
G03X466204Y-37402I-2329J399D01*
G01X469740D02*
G03X469775Y-37803I2362J4D01*
G01X470073Y-38611D02*
G03X472102Y-39764I2029J1209D01*
G01X479386Y-39325D02*
G03X480042Y-38615I-1370J1924D01*
G01X480343Y-37799D02*
G03X480377Y-37402I-2328J399D01*
G01X478184Y-39764D02*
G03X478479Y-39558I0J314D01*
G01X471677D02*
G03X471972Y-39764I295J108D01*
G01X464011D02*
G03X464306Y-39558I0J314D01*
G01X456574Y-35626D02*
G03X456672Y-36172I1575J1D01*
G01X450965D02*
G03X451062Y-35626I-1477J544D01*
G01X456180D02*
G03X456302Y-36308I1969J0D01*
G01X451334D02*
G03X451456Y-35626I-1845J682D01*
G01X451519Y-36377D02*
G03X451653Y-35626I-2031J750D01*
G01X455984D02*
G03X456118Y-36377I2165J-1D01*
G01X451040Y-39325D02*
G03X451695Y-38615I-1372J1923D01*
G01X451997Y-37799D02*
G03X452030Y-37402I-2329J393D01*
G01X455567D02*
G03X455601Y-37803I2362J-2D01*
G01X455900Y-38611D02*
G03X457929Y-39764I2029J1209D01*
G01X457504Y-39558D02*
G03X457799Y-39764I295J108D01*
G01X449837D02*
G03X450133Y-39558I0J316D01*
G01X500023D02*
X500403Y-39449D01*
G01X485850Y-39558D02*
X486229Y-39449D01*
G01X471677Y-39558D02*
X472056Y-39449D01*
G01X457504Y-39558D02*
X457883Y-39449D01*
G01X498638Y-36377D02*
X499191Y-36172D01*
G01X484464Y-36377D02*
X485018Y-36172D01*
G01X470291Y-36377D02*
X470845Y-36172D01*
G01X456118Y-36377D02*
X456672Y-36172D01*
G01X506826Y-39558D02*
X506759Y-39666D01*
G01X508723Y-37708D02*
X508202Y-39119D01*
G01X508330Y-37637D02*
X507736Y-39245D01*
G01X508211Y-36377D02*
X507076Y-39449D01*
G01X508027Y-36308D02*
X506826Y-39558D01*
G01X506446Y-39449D02*
X507658Y-36172D01*
G01X494550Y-37708D02*
X494029Y-39119D01*
G01X494156Y-37637D02*
X493562Y-39245D01*
G01X494038Y-36377D02*
X492903Y-39449D01*
G01X493854Y-36308D02*
X492653Y-39558D01*
G01X492273Y-39449D02*
X493484Y-36172D01*
G01X479855Y-39119D02*
X480377Y-37708D01*
G01X479983Y-37637D02*
X479389Y-39245D01*
G01X479865Y-36377D02*
X478730Y-39449D01*
G01X479680Y-36308D02*
X478479Y-39558D01*
G01X478100Y-39449D02*
X479311Y-36172D01*
G01X465682Y-39119D02*
X466204Y-37708D01*
G01X465810Y-37637D02*
X465216Y-39245D01*
G01X465692Y-36377D02*
X464556Y-39449D01*
G01X465507Y-36308D02*
X464306Y-39558D01*
G01X463927Y-39449D02*
X465138Y-36172D01*
G01X452030Y-37708D02*
X451509Y-39119D01*
G01X451637Y-37637D02*
X451043Y-39245D01*
G01X451519Y-36377D02*
X450383Y-39449D01*
G01X451334Y-36308D02*
X450133Y-39558D01*
G01X449753Y-39449D02*
X450965Y-36172D01*
G01X509117Y-7577D02*
Y-39764D01*
G01X508723Y-7577D02*
Y-37708D01*
G01X508346Y-35626D02*
Y-7499D01*
G01X508330Y-37637D02*
Y-7577D01*
G01X508149Y-7499D02*
Y-35626D01*
G01X507755Y-7499D02*
Y-35626D01*
G01X507736Y-39531D02*
Y-31890D01*
G01X507076Y-39449D02*
Y-39764D01*
G01X506446Y-39449D02*
Y-39764D01*
G01X506293Y-1181D02*
Y-39764D01*
G01X505965Y62697D02*
Y-12828D01*
G01X505899Y-39764D02*
Y-1181D01*
G01X505410Y-12828D02*
Y62697D01*
G01X500486Y-31890D02*
Y-39764D01*
G01X500403Y-39449D02*
Y-39764D01*
G01X499773Y-39449D02*
Y-39764D01*
G01X499094Y-35626D02*
Y-7499D01*
G01X498700D02*
Y-35626D01*
G01X498503Y-7499D02*
Y-35626D01*
G01X498480Y-7577D02*
Y-37640D01*
G01X498087Y-7577D02*
Y-37402D01*
G01X497693Y-7577D02*
Y-39764D01*
G01X494944Y-7577D02*
Y-39764D01*
G01X494550Y-7577D02*
Y-37708D01*
G01X494173Y-35626D02*
Y-7499D01*
G01X494156Y-37637D02*
Y-7577D01*
G01X493976Y-7499D02*
Y-35626D01*
G01X493582Y-7499D02*
Y-35626D01*
G01X493562Y-31890D02*
Y-39531D01*
G01X492903Y-39449D02*
Y-39764D01*
G01X492273Y-39449D02*
Y-39764D01*
G01X491200Y-31890D02*
Y-39764D01*
G01X490840Y-31890D02*
Y-39764D01*
G01X486312Y-31890D02*
Y-39764D01*
G01X486229Y-39449D02*
Y-39764D01*
G01X485600Y-39449D02*
Y-39764D01*
G01X484921Y-35626D02*
Y-7499D01*
G01X484527D02*
Y-35626D01*
G01X484330Y-7499D02*
Y-35626D01*
G01X484307Y-7577D02*
Y-37640D01*
G01X483913Y-7577D02*
Y-37402D01*
G01X483520Y-39764D02*
Y-7577D01*
G01X480771D02*
Y-39764D01*
G01X480377Y-37708D02*
Y-7577D01*
G01X479999Y-35626D02*
Y-7499D01*
G01X479983Y-37637D02*
Y-7577D01*
G01X479802Y-7499D02*
Y-35626D01*
G01X479409Y-7499D02*
Y-35626D01*
G01X479389Y-39531D02*
Y-31890D01*
G01X478730Y-39449D02*
Y-39764D01*
G01X478100Y-39449D02*
Y-39764D01*
G01X477027Y-31890D02*
Y-39764D01*
G01X476667Y-31890D02*
Y-39764D01*
G01X472139Y-31890D02*
Y-39764D01*
G01X472056Y-39449D02*
Y-39764D01*
G01X471427Y-39449D02*
Y-39764D01*
G01X470747Y-35626D02*
Y-7499D01*
G01X470354D02*
Y-35626D01*
G01X470157Y-7499D02*
Y-35626D01*
G01X470134Y-7577D02*
Y-37640D01*
G01X469740Y-7577D02*
Y-37402D01*
G01X469347Y-39764D02*
Y-7577D01*
G01X466597D02*
Y-39764D01*
G01X466204Y-37708D02*
Y-7577D01*
G01X465826Y-35626D02*
Y-7499D01*
G01X465810Y-37637D02*
Y-7577D01*
G01X465629Y-7499D02*
Y-35626D01*
G01X465236Y-7499D02*
Y-35626D01*
G01X465216Y-39531D02*
Y-31890D01*
G01X464556Y-39449D02*
Y-39764D01*
G01X463927Y-39449D02*
Y-39764D01*
G01X462854Y-31890D02*
Y-39764D01*
G01X462493Y-31890D02*
Y-39764D01*
G01X457966Y-31890D02*
Y-39764D01*
G01X457883D02*
Y-39449D01*
G01X457253D02*
Y-39764D01*
G01X456574Y-35626D02*
Y-7499D01*
G01X456180Y-35626D02*
Y-7499D01*
G01X455984D02*
Y-35626D01*
G01X455961Y-7577D02*
Y-37640D01*
G01X455567Y-7577D02*
Y-37402D01*
G01X455173Y-7577D02*
Y-39764D01*
G01X452424Y-7577D02*
Y-39764D01*
G01X452030Y-7577D02*
Y-37708D01*
G01X451653Y-35626D02*
Y-7499D01*
G01X451637Y-37637D02*
Y-7577D01*
G01X451456Y-7499D02*
Y-35626D01*
G01X451062Y-7499D02*
Y-35626D01*
G01X451043Y-39531D02*
Y-31890D01*
G01X450383Y-39449D02*
Y-39764D01*
G01X449753Y-39449D02*
Y-39764D01*
G01X449600Y-1181D02*
Y-39764D01*
G01X449272Y62697D02*
Y-12828D01*
G01X449206Y-39764D02*
Y-1181D01*
G01X499191Y-36172D02*
X500403Y-39449D01*
G01X500023Y-39558D02*
X498822Y-36308D01*
G01X499773Y-39449D02*
X498638Y-36377D01*
G01X499112Y-39350D02*
X498480Y-37640D01*
G01X498121Y-37803D02*
X498420Y-38611D01*
G01X485018Y-36172D02*
X486229Y-39449D01*
G01X485850Y-39558D02*
X484649Y-36308D01*
G01X485600Y-39449D02*
X484464Y-36377D01*
G01X484939Y-39350D02*
X484307Y-37640D01*
G01X483948Y-37803D02*
X484247Y-38611D01*
G01X470845Y-36172D02*
X472056Y-39449D01*
G01X471677Y-39558D02*
X470476Y-36308D01*
G01X471427Y-39449D02*
X470291Y-36377D01*
G01X470766Y-39350D02*
X470134Y-37640D01*
G01X469775Y-37803D02*
X470073Y-38611D01*
G01X456672Y-36172D02*
X457883Y-39449D01*
G01X456302Y-36308D02*
X457504Y-39558D01*
G01X457253Y-39449D02*
X456118Y-36377D01*
G01X456593Y-39350D02*
X455961Y-37640D01*
G01X455601Y-37803D02*
X455900Y-38611D01*
G01X500090Y-39666D02*
X500023Y-39558D01*
G01X485917Y-39666D02*
X485850Y-39558D01*
G01X471744Y-39666D02*
X471677Y-39558D01*
G01X457571Y-39666D02*
X457504Y-39558D01*
G01X499773Y-39449D02*
X500023Y-39558D01*
G01X485600Y-39449D02*
X485850Y-39558D01*
G01X471427Y-39449D02*
X471677Y-39558D01*
G01X457253Y-39449D02*
X457504Y-39558D01*
G01X507658Y-36172D02*
X508211Y-36377D01*
G01X493484Y-36172D02*
X494038Y-36377D01*
G01X479311Y-36172D02*
X479865Y-36377D01*
G01X465138Y-36172D02*
X465692Y-36377D01*
G01X450965Y-36172D02*
X451519Y-36377D01*
G01X507736Y-39471D02*
X507816Y-39494D01*
G01X506446Y-39449D02*
X506826Y-39558D01*
G01X493562Y-39471D02*
X493642Y-39494D01*
G01X492273Y-39449D02*
X492653Y-39558D01*
G01X479389Y-39471D02*
X479469Y-39494D01*
G01X478100Y-39449D02*
X478479Y-39558D01*
G01X465216Y-39471D02*
X465296Y-39494D01*
G01X463927Y-39449D02*
X464306Y-39558D01*
G01X451043Y-39471D02*
X451123Y-39494D01*
G01X449753Y-39449D02*
X450133Y-39558D01*
G01X508723Y-37708D02*
X508330Y-37637D01*
G01X494550Y-37708D02*
X494156Y-37637D01*
G01X480377Y-37708D02*
X479983Y-37637D01*
G01X466204Y-37708D02*
X465810Y-37637D01*
G01X452030Y-37708D02*
X451637Y-37637D01*
G01X449600Y-12828D02*
X449272D01*
G01X506293D02*
X505965D01*
G01X505899D02*
X505410D01*
G01X491200Y-31890D02*
X493562D01*
G01X477027D02*
X479389D01*
G01X462854D02*
X465216D01*
G01X451043D02*
X449600D01*
G01X462493D02*
X457966D01*
G01X476667D02*
X472139D01*
G01X490840D02*
X486312D01*
G01X505899D02*
X500486D01*
G01X507736D02*
X506293D01*
G01X507755Y-35626D02*
X508346D01*
G01X498503D02*
X499094D01*
G01X484330D02*
X484921D01*
G01X470157D02*
X470747D01*
G01X455984D02*
X456574D01*
G01X451062D02*
X451653D01*
G01X465826D02*
X465236D01*
G01X479999D02*
X479409D01*
G01X494173D02*
X493582D01*
G01X508723Y-37402D02*
X512260D01*
G01X494550D02*
X498087D01*
G01X480377D02*
X483913D01*
G01X466204D02*
X469740D01*
G01X452030D02*
X455567D01*
G01X500486Y-39276D02*
X505899D01*
G01X486312D02*
X490840D01*
G01X472139D02*
X476667D01*
G01X457966D02*
X462493D01*
G01X451043D02*
X449600D01*
G01X465216D02*
X462854D01*
G01X479389D02*
X477027D01*
G01X493562D02*
X491200D01*
G01X507736D02*
X506293D01*
G01X507076Y-39449D02*
X520620D01*
G01X506293D02*
X506446D01*
G01X492903D02*
X505899D01*
G01X478730D02*
X492273D01*
G01X464556D02*
X478100D01*
G01X450383D02*
X463927D01*
G01X449600D02*
X449753D01*
G01X506293Y-39764D02*
X548419D01*
G01X449600D02*
X505899D01*
G01X455961Y-37640D02*
X455587Y-37706D01*
G01X469760D02*
X470134Y-37640D01*
G01X449837Y-39764D02*
X449961Y-39738D01*
G01X464011Y-39764D02*
X464134Y-39738D01*
G01X483933Y-37706D02*
X484307Y-37640D01*
G01X498106Y-37706D02*
X498480Y-37640D01*
G01X506655Y-39739D02*
X506530Y-39764D01*
G01X478184D02*
X478308Y-39738D01*
G01X492357Y-39764D02*
X492481Y-39738D01*
G01X452404Y-7354D02*
X452456Y-7480D01*
G01X452363Y-7224D02*
X452404Y-7354D01*
G01X452336Y-7124D02*
X452363Y-7224D01*
G01X452326Y-7087D02*
X452336Y-7124D01*
G01X466577Y-7354D02*
X466630Y-7480D01*
G01X466536Y-7224D02*
X466577Y-7354D01*
G01X466509Y-7124D02*
X466536Y-7224D01*
G01X466500Y-7087D02*
X466509Y-7124D01*
G01X480750Y-7354D02*
X480803Y-7480D01*
G01X480709Y-7224D02*
X480750Y-7354D01*
G01X480682Y-7124D02*
X480709Y-7224D01*
G01X480673Y-7087D02*
X480682Y-7124D01*
G01X466455Y-6892D02*
X466416Y-6693D01*
G01X466487Y-7035D02*
X466455Y-6892D01*
G01X466500Y-7087D02*
X466487Y-7035D01*
G01X480628Y-6892D02*
X480589Y-6693D01*
G01X480660Y-7035D02*
X480628Y-6892D01*
G01X480673Y-7087D02*
X480660Y-7035D01*
G01X452314D02*
X452326Y-7087D01*
G01X452282Y-6890D02*
X452314Y-7035D01*
G01X452242Y-6693D02*
X452282Y-6890D01*
G01X494924Y-7354D02*
X494976Y-7480D01*
G01X494883Y-7224D02*
X494924Y-7354D01*
G01X494855Y-7124D02*
X494883Y-7224D01*
G01X494846Y-7087D02*
X494855Y-7124D01*
G01X509097Y-7354D02*
X509149Y-7480D01*
G01X509056Y-7224D02*
X509097Y-7354D01*
G01X509029Y-7124D02*
X509056Y-7224D01*
G01X509019Y-7087D02*
X509029Y-7124D01*
G01X494802Y-6892D02*
X494762Y-6693D01*
G01X494833Y-7035D02*
X494802Y-6892D01*
G01X494846Y-7087D02*
X494833Y-7035D01*
G01X509007D02*
X509019Y-7087D01*
G01X508974Y-6890D02*
X509007Y-7035D01*
G01X508935Y-6693D02*
X508974Y-6890D01*
G01X455284Y-7035D02*
X455271Y-7087D01*
G01X455316Y-6890D02*
X455284Y-7035D01*
G01X455355Y-6693D02*
X455316Y-6890D01*
G01X469489Y-6892D02*
X469528Y-6693D01*
G01X469457Y-7034D02*
X469489Y-6892D01*
G01X469444Y-7087D02*
X469457Y-7034D01*
G01X483662Y-6892D02*
X483701Y-6693D01*
G01X483630Y-7034D02*
X483662Y-6892D01*
G01X483618Y-7087D02*
X483630Y-7034D01*
G01X455263Y-7120D02*
X455271Y-7087D01*
G01X455237Y-7214D02*
X455263Y-7120D01*
G01X455196Y-7346D02*
X455237Y-7214D01*
G01X455141Y-7480D02*
X455196Y-7346D01*
G01X497835Y-6892D02*
X497875Y-6693D01*
G01X497803Y-7034D02*
X497835Y-6892D01*
G01X497791Y-7087D02*
X497803Y-7034D01*
G01X469436Y-7120D02*
X469444Y-7087D01*
G01X469411Y-7214D02*
X469436Y-7120D01*
G01X469369Y-7346D02*
X469411Y-7214D01*
G01X469314Y-7480D02*
X469369Y-7346D01*
G01X483609Y-7120D02*
X483618Y-7087D01*
G01X483584Y-7214D02*
X483609Y-7120D01*
G01X483542Y-7346D02*
X483584Y-7214D01*
G01X483487Y-7480D02*
X483542Y-7346D01*
G01X497782Y-7120D02*
X497791Y-7087D01*
G01X497757Y-7214D02*
X497782Y-7120D01*
G01X497716Y-7346D02*
X497757Y-7214D01*
G01X497661Y-7480D02*
X497716Y-7346D01*
G01X509370Y48819D02*
G03I-709J0D01*
G01X510909Y46771D02*
G03I-1969J0D01*
G01X509370Y43307D02*
G03I-709J0D01*
G01X507562Y45039D02*
G03X506578Y44055I0J-984D01*
G01X511302D02*
G03X510318Y45039I-984J0D01*
G01X504216Y44055D02*
G03X503232Y45039I-984J0D01*
G01X510515Y39478D02*
G03X507365I-1575J0D01*
G01X509370Y34645D02*
G03I-709J0D01*
G01Y38976D02*
G03I-709J0D01*
G01X507405Y36087D02*
G03Y34307I1299J-890D01*
G01X510476D02*
G03Y36087I-1300J890D01*
G01X503389Y34307D02*
G03Y36087I-1299J890D01*
G01X509370Y29134D02*
G03I-709J0D01*
G01X507405Y29000D02*
G03Y27220I1299J-890D01*
G01X510476D02*
G03Y29000I-1300J890D01*
G01X503389Y27220D02*
G03Y29000I-1299J890D01*
G01X509370Y20472D02*
G03I-709J0D01*
G01Y24803D02*
G03I-709J0D01*
G01Y14960D02*
G03I-709J0D01*
G01X509152Y-7482D02*
G03X509120Y-7577I125J-95D01*
G01X508561Y-7302D02*
G03X508364Y-7499I0J-197D01*
G01X508561Y-7105D02*
G03X508167Y-7499I0J-394D01*
G01X509021Y-7089D02*
G03X508726Y-7577I256J-488D01*
G01X508561Y-6711D02*
G03X507773Y-7499I0J-788D01*
G01X508937Y-6696D02*
G03X508333Y-7577I341J-881D01*
G01X495197Y48819D02*
G03I-709J0D01*
G01X502283Y48425D02*
G03I-708J0D01*
G01X503822Y46771D02*
G03I-1968J0D01*
G01X496736D02*
G03I-1969J0D01*
G01X488110Y48425D02*
G03I-709J0D01*
G01X489649Y46771D02*
G03I-1969J0D01*
G01X482562D02*
G03I-1968J0D01*
G01X502283Y44094D02*
G03I-708J0D01*
G01X495197Y43307D02*
G03I-709J0D01*
G01X493389Y45039D02*
G03X492405Y44055I0J-984D01*
G01X497129D02*
G03X496145Y45039I-984J0D01*
G01X500476D02*
G03X499491Y44055I0J-985D01*
G01X496342Y39478D02*
G03X493192I-1575J0D01*
G01X503428D02*
G03X500279I-1574J0D01*
G01X502283Y38582D02*
G03I-708J0D01*
G01X495197Y38976D02*
G03I-709J0D01*
G01Y34645D02*
G03I-709J0D01*
G01X502283Y34252D02*
G03I-708J0D01*
G01X500318Y36087D02*
G03Y34307I1299J-890D01*
G01X496302D02*
G03Y36087I-1299J890D01*
G01X493232D02*
G03Y34307I1299J-890D01*
G01X488110Y44094D02*
G03I-709J0D01*
G01X482956Y44055D02*
G03X481972Y45039I-984J0D01*
G01X486302D02*
G03X485318Y44055I0J-984D01*
G01X490043D02*
G03X489058Y45039I-984J0D01*
G01X482169Y39478D02*
G03X479019I-1575J0D01*
G01X489255D02*
G03X486106I-1574J0D01*
G01X488110Y38582D02*
G03I-709J0D01*
G01Y34252D02*
G03I-709J0D01*
G01X489216Y34307D02*
G03Y36087I-1299J890D01*
G01X486145D02*
G03Y34307I1299J-890D01*
G01X482129D02*
G03Y36087I-1299J890D01*
G01X481023Y48819D02*
G03I-708J0D01*
G01X473937Y48425D02*
G03I-709J0D01*
G01X475476Y46771D02*
G03I-1969J0D01*
G01X466850Y48819D02*
G03I-709J0D01*
G01X459763Y48425D02*
G03I-708J0D01*
G01X468389Y46771D02*
G03I-1968J0D01*
G01X461302D02*
G03I-1968J0D01*
G01X481023Y43307D02*
G03I-708J0D01*
G01X473937Y44094D02*
G03I-709J0D01*
G01X472129Y45039D02*
G03X471145Y44055I0J-984D01*
G01X475869D02*
G03X474885Y45039I-984J0D01*
G01X479216D02*
G03X478232Y44055I0J-984D01*
G01X475082Y39478D02*
G03X471932I-1575J0D01*
G01X481023Y38976D02*
G03I-708J0D01*
G01Y34645D02*
G03I-708J0D01*
G01X473937Y38582D02*
G03I-709J0D01*
G01Y34252D02*
G03I-709J0D01*
G01X479058Y36087D02*
G03Y34307I1300J-890D01*
G01X475043D02*
G03Y36087I-1300J890D01*
G01X471972D02*
G03Y34307I1299J-890D01*
G01X466850Y43307D02*
G03I-709J0D01*
G01X459763Y44094D02*
G03I-708J0D01*
G01X461696Y44055D02*
G03X460712Y45039I-984J0D01*
G01X465043D02*
G03X464058Y44055I0J-985D01*
G01X468783D02*
G03X467799Y45039I-984J0D01*
G01X460909Y39478D02*
G03X457759I-1575J0D01*
G01X467995D02*
G03X464846I-1574J0D01*
G01X466850Y38976D02*
G03I-709J0D01*
G01Y34645D02*
G03I-709J0D01*
G01X459763Y38582D02*
G03I-708J0D01*
G01Y34252D02*
G03I-708J0D01*
G01X457799Y36087D02*
G03Y34307I1299J-890D01*
G01X460869D02*
G03Y36087I-1299J890D01*
G01X467956Y34307D02*
G03Y36087I-1299J890D01*
G01X464885D02*
G03Y34307I1299J-890D01*
G01X502283Y29921D02*
G03I-708J0D01*
G01X495197Y29134D02*
G03I-709J0D01*
G01X500318Y29000D02*
G03Y27220I1299J-890D01*
G01X496302D02*
G03Y29000I-1299J890D01*
G01X493232D02*
G03Y27220I1299J-890D01*
G01X495197Y24803D02*
G03I-709J0D01*
G01X502283Y24409D02*
G03I-708J0D01*
G01X495197Y20472D02*
G03I-709J0D01*
G01X502283Y20078D02*
G03I-708J0D01*
G01X488110Y29921D02*
G03I-709J0D01*
G01X489216Y27220D02*
G03Y29000I-1299J890D01*
G01X486145D02*
G03Y27220I1299J-890D01*
G01X482129D02*
G03Y29000I-1299J890D01*
G01X479058D02*
G03Y27220I1300J-890D01*
G01X488110Y24409D02*
G03I-709J0D01*
G01Y20078D02*
G03I-709J0D01*
G01X495197Y14960D02*
G03I-709J0D01*
G01X502283Y15748D02*
G03I-708J0D01*
G01Y10236D02*
G03I-708J0D01*
G01X488110Y15748D02*
G03I-709J0D01*
G01Y10236D02*
G03I-709J0D01*
G01X481023Y29134D02*
G03I-708J0D01*
G01X473937Y29921D02*
G03I-709J0D01*
G01X475043Y27220D02*
G03Y29000I-1300J890D01*
G01X471972D02*
G03Y27220I1299J-890D01*
G01X481023Y24803D02*
G03I-708J0D01*
G01Y20472D02*
G03I-708J0D01*
G01X473937Y24409D02*
G03I-709J0D01*
G01Y20078D02*
G03I-709J0D01*
G01X466850Y29134D02*
G03I-709J0D01*
G01X459763Y29921D02*
G03I-708J0D01*
G01X457799Y29000D02*
G03Y27220I1299J-890D01*
G01X460869D02*
G03Y29000I-1299J890D01*
G01X467956Y27220D02*
G03Y29000I-1299J890D01*
G01X464885D02*
G03Y27220I1299J-890D01*
G01X466850Y24803D02*
G03I-709J0D01*
G01Y20472D02*
G03I-709J0D01*
G01X459763Y24409D02*
G03I-708J0D01*
G01Y20078D02*
G03I-708J0D01*
G01X481023Y14960D02*
G03I-708J0D01*
G01X466850D02*
G03I-709J0D01*
G01X473937Y15748D02*
G03I-709J0D01*
G01Y10236D02*
G03I-709J0D01*
G01X459763Y15748D02*
G03I-708J0D01*
G01Y10236D02*
G03I-708J0D01*
G01X452677Y48819D02*
G03I-709J0D01*
G01X454216Y46771D02*
G03I-1969J0D01*
G01X452677Y43307D02*
G03I-709J0D01*
G01X450869Y45039D02*
G03X449885Y44055I0J-984D01*
G01X454610D02*
G03X453625Y45039I-984J0D01*
G01X457956D02*
G03X456972Y44055I0J-984D01*
G01X453822Y39478D02*
G03X450673I-1574J0D01*
G01X452677Y38976D02*
G03I-709J0D01*
G01Y34645D02*
G03I-709J0D01*
G01X450712Y36087D02*
G03Y34307I1299J-890D01*
G01X453783D02*
G03Y36087I-1299J890D01*
G01X452677Y29134D02*
G03I-709J0D01*
G01X450712Y29000D02*
G03Y27220I1299J-890D01*
G01X453783D02*
G03Y29000I-1299J890D01*
G01X452677Y24803D02*
G03I-709J0D01*
G01Y20472D02*
G03I-709J0D01*
G01Y14960D02*
G03I-709J0D01*
G01X488110Y5905D02*
G03I-709J0D01*
G01X502283D02*
G03I-708J0D01*
G01X483517Y-7577D02*
G03X483485Y-7482I-157J0D01*
G01X480805D02*
G03X480774Y-7577I126J-94D01*
G01X497690D02*
G03X497658Y-7482I-157J0D01*
G01X494979D02*
G03X494947Y-7577I125J-95D01*
G01X484312Y-7499D02*
G03X484115Y-7302I-197J0D01*
G01X494388D02*
G03X494191Y-7499I0J-197D01*
G01X498485D02*
G03X498288Y-7302I-197J0D01*
G01X484509Y-7499D02*
G03X484115Y-7105I-394J0D01*
G01X498682Y-7499D02*
G03X498288Y-7105I-394J0D01*
G01X494388D02*
G03X493994Y-7499I0J-394D01*
G01X494847Y-7089D02*
G03X494553Y-7577I258J-488D01*
G01X498084D02*
G03X497789Y-7089I-551J0D01*
G01X480674D02*
G03X480380Y-7577I258J-488D01*
G01X483910D02*
G03X483616Y-7089I-552J0D01*
G01X499076Y-7499D02*
G03X498288Y-6711I-788J0D01*
G01X494388D02*
G03X493600Y-7499I0J-788D01*
G01X484902D02*
G03X484115Y-6711I-788J0D01*
G01X480590Y-6696D02*
G03X479986Y-7577I341J-881D01*
G01X484304D02*
G03X483700Y-6696I-945J0D01*
G01X494763D02*
G03X494160Y-7577I342J-881D01*
G01X498477D02*
G03X497873Y-6696I-945J0D01*
G01X473937Y5905D02*
G03I-709J0D01*
G01X459763D02*
G03I-708J0D01*
G01X469343Y-7577D02*
G03X469312Y-7482I-157J1D01*
G01X466632D02*
G03X466600Y-7577I125J-95D01*
G01X466041Y-7302D02*
G03X465844Y-7499I0J-197D01*
G01X470139D02*
G03X469942Y-7302I-197J0D01*
G01X480214D02*
G03X480017Y-7499I0J-197D01*
G01X470336D02*
G03X469942Y-7105I-394J0D01*
G01X466041D02*
G03X465647Y-7499I0J-394D01*
G01X480214Y-7105D02*
G03X479821Y-7499I0J-393D01*
G01X466501Y-7089D02*
G03X466207Y-7577I258J-488D01*
G01X469737D02*
G03X469443Y-7089I-552J0D01*
G01X480214Y-6711D02*
G03X479427Y-7499I0J-787D01*
G01X470729D02*
G03X469942Y-6711I-788J0D01*
G01X466041D02*
G03X465254Y-7499I0J-787D01*
G01X466417Y-6696D02*
G03X465813Y-7577I341J-881D01*
G01X470131D02*
G03X469527Y-6696I-945J0D01*
G01X455170Y-7577D02*
G03X455138Y-7482I-157J0D01*
G01X452459D02*
G03X452427Y-7577I125J-95D01*
G01X451868Y-7302D02*
G03X451671Y-7499I0J-197D01*
G01X455965D02*
G03X455769Y-7302I-197J0D01*
G01X456162Y-7499D02*
G03X455769Y-7105I-394J0D01*
G01X451868D02*
G03X451474Y-7499I0J-394D01*
G01X455564Y-7577D02*
G03X455270Y-7089I-552J0D01*
G01X452328D02*
G03X452034Y-7577I258J-488D01*
G01X456556Y-7499D02*
G03X455769Y-6711I-788J0D01*
G01X451868D02*
G03X451080Y-7499I0J-788D01*
G01X452244Y-6696D02*
G03X451640Y-7577I341J-881D01*
G01X455958D02*
G03X455354Y-6696I-945J0D01*
G01X507375Y25730D02*
X505988Y23327D01*
G01X500289Y25730D02*
X498901Y23327D01*
G01X508192Y39921D02*
X507405Y38557D01*
G01X493202Y25730D02*
X491814Y23327D01*
G01X501106Y39921D02*
X500318Y38557D01*
G01X486115Y25730D02*
X484728Y23327D01*
G01X494019Y39921D02*
X493232Y38557D01*
G01X479029Y25730D02*
X477641Y23327D01*
G01X486932Y39921D02*
X486145Y38557D01*
G01X471942Y25730D02*
X470554Y23327D01*
G01X479846Y39921D02*
X479058Y38557D01*
G01X464856Y25730D02*
X463468Y23327D01*
G01X472759Y39921D02*
X471972Y38557D01*
G01X457769Y25730D02*
X456381Y23327D01*
G01X465673Y39921D02*
X464885Y38557D01*
G01X450682Y25730D02*
X449295Y23327D01*
G01X458586Y39921D02*
X457799Y38557D01*
G01X451499Y39921D02*
X450712Y38557D01*
G01X510505Y36042D02*
Y39478D01*
G01Y28955D02*
Y34351D01*
G01Y25730D02*
Y27265D01*
G01X510476Y27220D02*
Y22204D01*
G01Y34307D02*
Y29000D01*
G01Y38557D02*
Y36087D01*
G01X508561Y-7284D02*
Y-6693D01*
G01X507405Y36087D02*
Y38557D01*
G01Y29000D02*
Y34307D01*
G01Y22204D02*
Y27220D01*
G01X507375Y27265D02*
Y25730D01*
G01Y34351D02*
Y28955D01*
G01Y39478D02*
Y36042D01*
G01X506578Y44055D02*
Y22204D01*
G01X504216D02*
Y44055D01*
G01X503419Y36042D02*
Y39478D01*
G01Y28955D02*
Y34351D01*
G01Y25730D02*
Y27265D01*
G01X503389Y27220D02*
Y22204D01*
G01Y34307D02*
Y29000D01*
G01Y38557D02*
Y36087D01*
G01X500318Y27220D02*
Y22204D01*
G01Y34307D02*
Y29000D01*
G01Y38557D02*
Y36087D01*
G01X500289Y27265D02*
Y25730D01*
G01Y34351D02*
Y28955D01*
G01Y39478D02*
Y36042D01*
G01X499491Y44055D02*
Y22204D01*
G01X498288Y-7284D02*
Y-6693D01*
G01X497129Y44055D02*
Y22204D01*
G01X496332Y36042D02*
Y39478D01*
G01Y28955D02*
Y34351D01*
G01Y25730D02*
Y27265D01*
G01X496302Y27220D02*
Y22204D01*
G01Y34307D02*
Y29000D01*
G01Y38557D02*
Y36087D01*
G01X494388Y-7284D02*
Y-6693D01*
G01X493232Y36087D02*
Y38557D01*
G01Y29000D02*
Y34307D01*
G01Y22204D02*
Y27220D01*
G01X493202Y27265D02*
Y25730D01*
G01Y34351D02*
Y28955D01*
G01Y39478D02*
Y36042D01*
G01X492405Y44055D02*
Y22204D01*
G01X490043Y44055D02*
Y22204D01*
G01X489245Y36042D02*
Y39478D01*
G01Y28955D02*
Y34351D01*
G01Y25730D02*
Y27265D01*
G01X489216Y27220D02*
Y22204D01*
G01Y34307D02*
Y29000D01*
G01Y38557D02*
Y36087D01*
G01X486145D02*
Y38557D01*
G01Y29000D02*
Y34307D01*
G01Y22204D02*
Y27220D01*
G01X486115Y27265D02*
Y25730D01*
G01Y34351D02*
Y28955D01*
G01Y39478D02*
Y36042D01*
G01X485318Y44055D02*
Y22204D01*
G01X484115Y-7284D02*
Y-6693D01*
G01X482956Y44055D02*
Y22204D01*
G01X482159Y36042D02*
Y39478D01*
G01Y28955D02*
Y34351D01*
G01Y25730D02*
Y27265D01*
G01X482129Y27220D02*
Y22204D01*
G01Y34307D02*
Y29000D01*
G01Y38557D02*
Y36087D01*
G01X480214Y-7284D02*
Y-6693D01*
G01X479058Y36087D02*
Y38557D01*
G01Y29000D02*
Y34307D01*
G01Y22204D02*
Y27220D01*
G01X479029Y27265D02*
Y25730D01*
G01Y34351D02*
Y28955D01*
G01Y39478D02*
Y36042D01*
G01X478232Y44055D02*
Y22204D01*
G01X475869Y44055D02*
Y22204D01*
G01X475072Y36042D02*
Y39478D01*
G01Y28955D02*
Y34351D01*
G01Y25730D02*
Y27265D01*
G01X475043Y27220D02*
Y22204D01*
G01Y34307D02*
Y29000D01*
G01Y38557D02*
Y36087D01*
G01X471972D02*
Y38557D01*
G01Y29000D02*
Y34307D01*
G01Y22204D02*
Y27220D01*
G01X471942Y27265D02*
Y25730D01*
G01Y34351D02*
Y28955D01*
G01Y39478D02*
Y36042D01*
G01X471145Y44055D02*
Y22204D01*
G01X469942Y-7284D02*
Y-6693D01*
G01X468783Y44055D02*
Y22204D01*
G01X467986Y36042D02*
Y39478D01*
G01Y28955D02*
Y34351D01*
G01Y25730D02*
Y27265D01*
G01X467956Y27220D02*
Y22204D01*
G01Y34307D02*
Y29000D01*
G01Y38557D02*
Y36087D01*
G01X466041Y-7284D02*
Y-6693D01*
G01X464885Y36087D02*
Y38557D01*
G01Y29000D02*
Y34307D01*
G01Y22204D02*
Y27220D01*
G01X464856Y27265D02*
Y25730D01*
G01Y34351D02*
Y28955D01*
G01Y39478D02*
Y36042D01*
G01X464058Y44055D02*
Y22204D01*
G01X461696D02*
Y44055D01*
G01X460899Y36042D02*
Y39478D01*
G01Y28955D02*
Y34351D01*
G01Y25730D02*
Y27265D01*
G01X460869Y27220D02*
Y22204D01*
G01Y34307D02*
Y29000D01*
G01Y38557D02*
Y36087D01*
G01X457799D02*
Y38557D01*
G01Y29000D02*
Y34307D01*
G01Y22204D02*
Y27220D01*
G01X457769Y27265D02*
Y25730D01*
G01Y34351D02*
Y28955D01*
G01Y39478D02*
Y36042D01*
G01X456972Y44055D02*
Y22204D01*
G01X455769Y-7284D02*
Y-6693D01*
G01X454610Y22204D02*
Y44055D01*
G01X453812Y36042D02*
Y39478D01*
G01Y28955D02*
Y34351D01*
G01Y25730D02*
Y27265D01*
G01X453783Y27220D02*
Y22204D01*
G01Y34307D02*
Y29000D01*
G01Y38557D02*
Y36087D01*
G01X451868Y-7284D02*
Y-6693D01*
G01X450712Y36087D02*
Y38557D01*
G01Y29000D02*
Y34307D01*
G01Y22204D02*
Y27220D01*
G01X450682Y27265D02*
Y25730D01*
G01Y34351D02*
Y28955D01*
G01Y39478D02*
Y36042D01*
G01X449885Y44055D02*
Y22204D01*
G01X509688Y39921D02*
X510476Y38557D01*
G01X502602Y39921D02*
X503389Y38557D01*
G01X511893Y23327D02*
X510505Y25730D01*
G01X495515Y39921D02*
X496302Y38557D01*
G01X504806Y23327D02*
X503419Y25730D01*
G01X488428Y39921D02*
X489216Y38557D01*
G01X497720Y23327D02*
X496332Y25730D01*
G01X481342Y39921D02*
X482129Y38557D01*
G01X490633Y23327D02*
X489245Y25730D01*
G01X474255Y39921D02*
X475043Y38557D01*
G01X483547Y23327D02*
X482159Y25730D01*
G01X467169Y39921D02*
X467956Y38557D01*
G01X476460Y23327D02*
X475072Y25730D01*
G01X460082Y39921D02*
X460869Y38557D01*
G01X469373Y23327D02*
X467986Y25730D01*
G01X452995Y39921D02*
X453783Y38557D01*
G01X462287Y23327D02*
X460899Y25730D01*
G01X455200Y23327D02*
X453812Y25730D01*
G01X453625Y45039D02*
X450869D01*
G01X460712D02*
X457956D01*
G01X467799D02*
X465043D01*
G01X474885D02*
X472129D01*
G01X481972D02*
X479216D01*
G01X489058D02*
X486302D01*
G01X496145D02*
X493389D01*
G01X503232D02*
X500476D01*
G01X510318D02*
X507562D01*
G01X492405Y42516D02*
X497129D01*
G01X485318D02*
X490043D01*
G01X478232D02*
X482956D01*
G01X471145D02*
X475869D01*
G01X464058D02*
X468783D01*
G01X454610D02*
X449885D01*
G01X461696D02*
X456972D01*
G01X504216D02*
X499491D01*
G01X511302D02*
X506578D01*
G01X508192Y39921D02*
X509688D01*
G01X458586D02*
X460082D01*
G01X451499D02*
X452995D01*
G01X467169D02*
X465673D01*
G01X474255D02*
X472759D01*
G01X481342D02*
X479846D01*
G01X488428D02*
X486932D01*
G01X495515D02*
X494019D01*
G01X502602D02*
X501106D01*
G01X510712Y25372D02*
X514255D01*
G01X503625D02*
X507169D01*
G01X496539D02*
X500082D01*
G01X489452D02*
X492995D01*
G01X482365D02*
X485909D01*
G01X475279D02*
X478822D01*
G01X468192D02*
X471736D01*
G01X461106D02*
X464649D01*
G01X454019D02*
X457562D01*
G01X456381Y23327D02*
X455200D01*
G01X463468D02*
X462287D01*
G01X470554D02*
X469373D01*
G01X477641D02*
X476460D01*
G01X484728D02*
X483547D01*
G01X491814D02*
X490633D01*
G01X498901D02*
X497720D01*
G01X505988D02*
X504806D01*
G01X510476Y22204D02*
X514491D01*
G01X505965D02*
X507405D01*
G01X503389D02*
X505410D01*
G01X489216D02*
X493232D01*
G01X482129D02*
X486145D01*
G01X475043D02*
X479058D01*
G01X467956D02*
X471972D01*
G01X460869D02*
X464885D01*
G01X453783D02*
X457799D01*
G01X449272D02*
X450712D01*
G01X500318D02*
X496302D01*
G01X505899Y-1181D02*
X449272D01*
G01X548419D02*
X505965D01*
G01X505899Y-1772D02*
X449600D01*
G01X548419D02*
X506293D01*
G01X505899Y-4394D02*
X449600D01*
G01X548419D02*
X506293D01*
G01X505899Y-4591D02*
X449600D01*
G01X548419D02*
X506293D01*
G01X455769Y-6693D02*
X451868D01*
G01X469942D02*
X466041D01*
G01X484115D02*
X480214D01*
G01X498288D02*
X494388D01*
G01X512462D02*
X508561D01*
G01X455769Y-7087D02*
X451868D01*
G01X469942D02*
X466041D01*
G01X484115D02*
X480214D01*
G01X498288D02*
X494388D01*
G01X512462D02*
X508561D01*
G01Y-7284D02*
X512462D01*
G01X494388D02*
X498288D01*
G01X480214D02*
X484115D01*
G01X466041D02*
X469942D01*
G01X451868D02*
X455769D01*
G01X455141Y-7480D02*
X452456D01*
G01X469314D02*
X466630D01*
G01X483487D02*
X480803D01*
G01X497661D02*
X494976D01*
G01X511834D02*
X509149D01*
G01X498503Y-7499D02*
X499094D01*
G01X493582D02*
X494173D01*
G01X484330D02*
X484921D01*
G01X479409D02*
X479999D01*
G01X470157D02*
X470747D01*
G01X465236D02*
X465826D01*
G01X455984D02*
X456574D01*
G01X451653D02*
X451062D01*
G01X508346D02*
X507755D01*
G01X508330Y-7577D02*
X509117D01*
G01X497693D02*
X498480D01*
G01X483520D02*
X484307D01*
G01X469347D02*
X470134D01*
G01X455173D02*
X455961D01*
G01X451637D02*
X452424D01*
G01X466597D02*
X465810D01*
G01X480771D02*
X479983D01*
G01X494944D02*
X494156D01*
G01X450837Y53330D02*
X450712Y53648D01*
G01X451053Y53051D02*
X450837Y53330D01*
G01X457924D02*
X457799Y53648D01*
G01X458140Y53051D02*
X457924Y53330D01*
G01X465010D02*
X464885Y53648D01*
G01X465227Y53051D02*
X465010Y53330D01*
G01X472097D02*
X471972Y53648D01*
G01X472313Y53051D02*
X472097Y53330D01*
G01X479184D02*
X479058Y53648D01*
G01X479400Y53051D02*
X479184Y53330D01*
G01X486270D02*
X486145Y53648D01*
G01X486486Y53051D02*
X486270Y53330D01*
G01X493357D02*
X493232Y53648D01*
G01X493573Y53051D02*
X493357Y53330D01*
G01X500443D02*
X500318Y53648D01*
G01X500660Y53051D02*
X500443Y53330D01*
G01X507530D02*
X507405Y53648D01*
G01X507746Y53051D02*
X507530Y53330D01*
G01X450855Y53425D02*
X451053Y53051D01*
G01X450728Y53849D02*
X450855Y53425D01*
G01X450682Y54309D02*
X450728Y53849D01*
G01X457941Y53425D02*
X458140Y53051D01*
G01X457815Y53849D02*
X457941Y53425D01*
G01X457769Y54309D02*
X457815Y53849D01*
G01X465028Y53425D02*
X465227Y53051D01*
G01X464901Y53849D02*
X465028Y53425D01*
G01X464856Y54309D02*
X464901Y53849D01*
G01X472115Y53425D02*
X472313Y53051D01*
G01X471988Y53849D02*
X472115Y53425D01*
G01X471942Y54309D02*
X471988Y53849D01*
G01X450690Y53766D02*
X450712Y53643D01*
G01X450682Y53889D02*
X450690Y53766D01*
G01X457776D02*
X457799Y53643D01*
G01X457769Y53889D02*
X457776Y53766D01*
G01X464863D02*
X464885Y53643D01*
G01X464856Y53889D02*
X464863Y53766D01*
G01X479201Y53425D02*
X479400Y53051D01*
G01X479074Y53849D02*
X479201Y53425D01*
G01X479029Y54309D02*
X479074Y53849D01*
G01X486288Y53425D02*
X486486Y53051D01*
G01X486161Y53849D02*
X486288Y53425D01*
G01X486115Y54309D02*
X486161Y53849D01*
G01X493375Y53425D02*
X493573Y53051D01*
G01X493248Y53849D02*
X493375Y53425D01*
G01X493202Y54309D02*
X493248Y53849D01*
G01X500461Y53425D02*
X500660Y53051D01*
G01X500334Y53849D02*
X500461Y53425D01*
G01X500289Y54309D02*
X500334Y53849D01*
G01X507548Y53425D02*
X507746Y53051D01*
G01X507421Y53849D02*
X507548Y53425D01*
G01X507375Y54309D02*
X507421Y53849D01*
G01X471950Y53766D02*
X471972Y53643D01*
G01X471942Y53889D02*
X471950Y53766D01*
G01X479036D02*
X479058Y53643D01*
G01X479029Y53889D02*
X479036Y53766D01*
G01X486123D02*
X486145Y53643D01*
G01X486115Y53889D02*
X486123Y53766D01*
G01X493210D02*
X493232Y53643D01*
G01X493202Y53889D02*
X493210Y53766D01*
G01X453805Y53767D02*
X453783Y53643D01*
G01X453812Y53889D02*
X453805Y53767D01*
G01X460892D02*
X460869Y53643D01*
G01X460899Y53889D02*
X460892Y53767D01*
G01X467978D02*
X467956Y53643D01*
G01X467986Y53889D02*
X467978Y53767D01*
G01X500296Y53766D02*
X500318Y53643D01*
G01X500289Y53889D02*
X500296Y53766D01*
G01X507383D02*
X507405Y53643D01*
G01X507375Y53889D02*
X507383Y53766D01*
G01X475065Y53767D02*
X475043Y53643D01*
G01X475072Y53889D02*
X475065Y53767D01*
G01X482151D02*
X482129Y53643D01*
G01X482159Y53889D02*
X482151Y53767D01*
G01X489238D02*
X489216Y53643D01*
G01X489245Y53889D02*
X489238Y53767D01*
G01X496325D02*
X496302Y53643D01*
G01X496332Y53889D02*
X496325Y53767D01*
G01X503411D02*
X503389Y53643D01*
G01X503419Y53889D02*
X503411Y53767D01*
G01X510498D02*
X510476Y53643D01*
G01X510505Y53889D02*
X510498Y53767D01*
G01X453656Y53327D02*
X453441Y53051D01*
G01X453783Y53648D02*
X453656Y53327D01*
G01X460742D02*
X460528Y53051D01*
G01X460869Y53648D02*
X460742Y53327D01*
G01X467829D02*
X467615Y53051D01*
G01X467956Y53648D02*
X467829Y53327D01*
G01X474915D02*
X474701Y53051D01*
G01X475043Y53648D02*
X474915Y53327D01*
G01X482002D02*
X481788Y53051D01*
G01X482129Y53648D02*
X482002Y53327D01*
G01X453767Y53849D02*
X453812Y54309D01*
G01X453640Y53425D02*
X453767Y53849D01*
G01X453441Y53051D02*
X453640Y53425D01*
G01X460853Y53849D02*
X460899Y54309D01*
G01X460727Y53425D02*
X460853Y53849D01*
G01X460528Y53051D02*
X460727Y53425D01*
G01X489089Y53327D02*
X488874Y53051D01*
G01X489216Y53648D02*
X489089Y53327D01*
G01X496175D02*
X495961Y53051D01*
G01X496302Y53648D02*
X496175Y53327D01*
G01X503262D02*
X503048Y53051D01*
G01X503389Y53648D02*
X503262Y53327D01*
G01X510348D02*
X510134Y53051D01*
G01X510476Y53648D02*
X510348Y53327D01*
G01X467940Y53849D02*
X467986Y54309D01*
G01X467813Y53425D02*
X467940Y53849D01*
G01X467615Y53051D02*
X467813Y53425D01*
G01X475027Y53849D02*
X475072Y54309D01*
G01X474900Y53425D02*
X475027Y53849D01*
G01X474701Y53051D02*
X474900Y53425D01*
G01X482113Y53849D02*
X482159Y54309D01*
G01X481986Y53425D02*
X482113Y53849D01*
G01X481788Y53051D02*
X481986Y53425D01*
G01X489200Y53849D02*
X489245Y54309D01*
G01X489073Y53425D02*
X489200Y53849D01*
G01X488874Y53051D02*
X489073Y53425D01*
G01X496286Y53849D02*
X496332Y54309D01*
G01X496160Y53425D02*
X496286Y53849D01*
G01X495961Y53051D02*
X496160Y53425D01*
G01X503373Y53849D02*
X503419Y54309D01*
G01X503246Y53425D02*
X503373Y53849D01*
G01X503048Y53051D02*
X503246Y53425D01*
G01X510460Y53849D02*
X510505Y54309D01*
G01X510333Y53425D02*
X510460Y53849D01*
G01X510134Y53051D02*
X510333Y53425D01*
G01X509370Y53149D02*
G03I-709J0D01*
G01X507739Y53045D02*
G03X510142I1201J1018D01*
G01X495197Y53149D02*
G03I-709J0D01*
G01X500652Y53045D02*
G03X503055I1201J1018D01*
G01X493565D02*
G03X495969I1202J1018D01*
G01X486479D02*
G03X488882I1201J1018D01*
G01X479392D02*
G03X481795I1202J1018D01*
G01X481023Y53149D02*
G03I-708J0D01*
G01X472306Y53045D02*
G03X474709I1201J1018D01*
G01X466850Y53149D02*
G03I-709J0D01*
G01X465219Y53045D02*
G03X467622I1201J1018D01*
G01X458132D02*
G03X460536I1202J1018D01*
G01X452677Y53149D02*
G03I-709J0D01*
G01X451046Y53045D02*
G03X453449I1201J1018D01*
G01X508586Y61712D02*
X507405Y60531D01*
G01X501499Y61712D02*
X500318Y60531D01*
G01X494413Y61712D02*
X493232Y60531D01*
G01X487326Y61712D02*
X486145Y60531D01*
G01X480239Y61712D02*
X479058Y60531D01*
G01X473153Y61712D02*
X471972Y60531D01*
G01X466066Y61712D02*
X464885Y60531D01*
G01X458980Y61712D02*
X457799Y60531D01*
G01X451893Y61712D02*
X450712Y60531D01*
G01X510505Y60138D02*
Y53889D01*
G01X510476Y60531D02*
Y52657D01*
G01X507405D02*
Y60531D01*
G01X507375Y60138D02*
Y53889D01*
G01X503419Y60138D02*
Y53889D01*
G01X503389Y60531D02*
Y52657D01*
G01X500318D02*
Y60531D01*
G01X500289Y60138D02*
Y53889D01*
G01X496332Y60138D02*
Y53889D01*
G01X496302Y60531D02*
Y52657D01*
G01X493232D02*
Y60531D01*
G01X493202Y60138D02*
Y53889D01*
G01X489245Y60138D02*
Y53889D01*
G01X489216Y60531D02*
Y52657D01*
G01X486145D02*
Y60531D01*
G01X486115Y60138D02*
Y53889D01*
G01X482159Y60138D02*
Y53889D01*
G01X482129Y60531D02*
Y52657D01*
G01X479058D02*
Y60531D01*
G01X479029Y60138D02*
Y53889D01*
G01X475072Y60138D02*
Y53889D01*
G01X475043Y60531D02*
Y52657D01*
G01X471972D02*
Y60531D01*
G01X471942Y60138D02*
Y53889D01*
G01X467986Y60138D02*
Y53889D01*
G01X467956Y60531D02*
Y52657D01*
G01X464885D02*
Y60531D01*
G01X464856Y60138D02*
Y53889D01*
G01X460899Y60138D02*
Y53889D01*
G01X460869Y60531D02*
Y52657D01*
G01X457799D02*
Y60531D01*
G01X457769Y60138D02*
Y53889D01*
G01X453812Y60138D02*
Y53889D01*
G01X453783Y60531D02*
Y52657D01*
G01X450712D02*
Y60531D01*
G01X450682Y60138D02*
Y53889D01*
G01X509295Y61712D02*
X510476Y60531D01*
G01X502208Y61712D02*
X503389Y60531D01*
G01X495121Y61712D02*
X496302Y60531D01*
G01X488035Y61712D02*
X489216Y60531D01*
G01X480948Y61712D02*
X482129Y60531D01*
G01X473862Y61712D02*
X475043Y60531D01*
G01X466775Y61712D02*
X467956Y60531D01*
G01X459688Y61712D02*
X460869Y60531D01*
G01X452602Y61712D02*
X453783Y60531D01*
G01X505965Y62697D02*
X547930D01*
G01X449272D02*
X505410D01*
G01X452602Y61712D02*
X451893D01*
G01X459688D02*
X458980D01*
G01X466775D02*
X466066D01*
G01X473862D02*
X473153D01*
G01X480948D02*
X480239D01*
G01X488035D02*
X487326D01*
G01X495121D02*
X494413D01*
G01X502208D02*
X501499D01*
G01X509295D02*
X508586D01*
G01X453783Y60531D02*
X450712D01*
G01X460869D02*
X457799D01*
G01X467956D02*
X464885D01*
G01X475043D02*
X471972D01*
G01X482129D02*
X479058D01*
G01X489216D02*
X486145D01*
G01X496302D02*
X493232D01*
G01X503389D02*
X500318D01*
G01X510476D02*
X507405D01*
G01X505965Y58956D02*
X547930D01*
G01X449272D02*
X505410D01*
G01X458140Y53051D02*
X453441D01*
G01X465227D02*
X460528D01*
G01X472313D02*
X467615D01*
G01X479400D02*
X474701D01*
G01X486486D02*
X481788D01*
G01X493573D02*
X488874D01*
G01X500660D02*
X495961D01*
G01X507746D02*
X503048D01*
G01X514833D02*
X510134D01*
G01X510476Y52657D02*
X514491D01*
G01X505965D02*
X507405D01*
G01X503389D02*
X505410D01*
G01X496302D02*
X500318D01*
G01X489216D02*
X493232D01*
G01X482129D02*
X486145D01*
G01X475043D02*
X479058D01*
G01X467956D02*
X471972D01*
G01X460869D02*
X464885D01*
G01X453783D02*
X457799D01*
G01X449272D02*
X450712D01*
G01X470728Y240295D02*
Y287264D01*
G01X484262Y530315D02*
Y520723D01*
G01X492136Y530315D02*
G03X484262I-3937J0D01*
G01X474316Y509060D02*
G03X484262Y520723I-1865J11663D01*
G01X475560Y501285D02*
G03X492136Y520723I-3109J19438D01*
G01Y562992D02*
Y520723D01*
G01X484262Y566929D02*
G03X480325Y570866I-3937J0D01*
G01X484262Y555512D02*
G03X492136I3937J0D01*
G01X484262Y566929D02*
Y555512D01*
G01X500010Y570866D02*
G03X492136Y562992I0J-7874D01*
G01X500010Y570866D02*
X818897D01*
G01X515565Y-879845D02*
Y-898782D01*
G01X563347Y-39738D02*
X563452Y-39665D01*
G01X563223Y-39764D02*
X563347Y-39738D01*
G01X549174D02*
X549279Y-39665D01*
G01X549050Y-39764D02*
X549174Y-39738D01*
G01X535001D02*
X535106Y-39665D01*
G01X534877Y-39764D02*
X535001Y-39738D01*
G01X520828D02*
X520932Y-39665D01*
G01X520704Y-39764D02*
X520828Y-39738D01*
G01X514369Y-39739D02*
X514492Y-39764D01*
G01X514263Y-39666D02*
X514369Y-39739D01*
G01X528542D02*
X528665Y-39764D01*
G01X528437Y-39666D02*
X528542Y-39739D01*
G01X542715D02*
X542838Y-39764D01*
G01X542610Y-39666D02*
X542715Y-39739D01*
G01X556888D02*
X557012Y-39764D01*
G01X556783Y-39666D02*
X556888Y-39739D01*
G01X571061D02*
X571185Y-39764D01*
G01X570956Y-39666D02*
X571061Y-39739D01*
G01X522566Y-38609D02*
X522561Y-38615D01*
G01X522583Y-38589D02*
X522566Y-38609D01*
G01X522608Y-38556D02*
X522583Y-38589D01*
G01X522642Y-38512D02*
X522608Y-38556D01*
G01X522682Y-38457D02*
X522642Y-38512D01*
G01X522727Y-38389D02*
X522682Y-38457D01*
G01X522774Y-38312D02*
X522727Y-38389D01*
G01X522817Y-38233D02*
X522774Y-38312D01*
G01X522853Y-38160D02*
X522817Y-38233D01*
G01X522881Y-38092D02*
X522853Y-38160D01*
G01X522902Y-38029D02*
X522881Y-38092D01*
G01X522914Y-37971D02*
X522902Y-38029D01*
G01X522918Y-37920D02*
X522914Y-37971D01*
G01X522912Y-37878D02*
X522918Y-37920D01*
G01X522899Y-37844D02*
X522912Y-37878D01*
G01X522883Y-37819D02*
X522899Y-37844D01*
G01X522869Y-37804D02*
X522883Y-37819D01*
G01X522863Y-37799D02*
X522869Y-37804D01*
G01X536740Y-38609D02*
X536735Y-38615D01*
G01X536756Y-38589D02*
X536740Y-38609D01*
G01X536782Y-38556D02*
X536756Y-38589D01*
G01X536815Y-38512D02*
X536782Y-38556D01*
G01X536855Y-38457D02*
X536815Y-38512D01*
G01X536900Y-38389D02*
X536855Y-38457D01*
G01X536948Y-38312D02*
X536900Y-38389D01*
G01X536991Y-38233D02*
X536948Y-38312D01*
G01X537026Y-38160D02*
X536991Y-38233D01*
G01X537054Y-38092D02*
X537026Y-38160D01*
G01X537075Y-38029D02*
X537054Y-38092D01*
G01X537088Y-37971D02*
X537075Y-38029D01*
G01X537091Y-37920D02*
X537088Y-37971D01*
G01X537085Y-37878D02*
X537091Y-37920D01*
G01X537072Y-37844D02*
X537085Y-37878D01*
G01X537056Y-37819D02*
X537072Y-37844D01*
G01X537042Y-37804D02*
X537056Y-37819D01*
G01X537036Y-37799D02*
X537042Y-37804D01*
G01X550913Y-38609D02*
X550908Y-38615D01*
G01X550929Y-38589D02*
X550913Y-38609D01*
G01X550955Y-38556D02*
X550929Y-38589D01*
G01X550989Y-38512D02*
X550955Y-38556D01*
G01X551028Y-38457D02*
X550989Y-38512D01*
G01X551073Y-38389D02*
X551028Y-38457D01*
G01X551121Y-38312D02*
X551073Y-38389D01*
G01X551164Y-38233D02*
X551121Y-38312D01*
G01X551199Y-38160D02*
X551164Y-38233D01*
G01X551227Y-38092D02*
X551199Y-38160D01*
G01X551248Y-38029D02*
X551227Y-38092D01*
G01X551261Y-37971D02*
X551248Y-38029D01*
G01X551264Y-37920D02*
X551261Y-37971D01*
G01X551258Y-37878D02*
X551264Y-37920D01*
G01X551245Y-37844D02*
X551258Y-37878D01*
G01X551229Y-37819D02*
X551245Y-37844D01*
G01X551215Y-37804D02*
X551229Y-37819D01*
G01X551209Y-37799D02*
X551215Y-37804D01*
G01X565086Y-38609D02*
X565081Y-38615D01*
G01X565102Y-38589D02*
X565086Y-38609D01*
G01X565128Y-38556D02*
X565102Y-38589D01*
G01X565162Y-38512D02*
X565128Y-38556D01*
G01X565202Y-38457D02*
X565162Y-38512D01*
G01X565247Y-38389D02*
X565202Y-38457D01*
G01X565294Y-38312D02*
X565247Y-38389D01*
G01X565337Y-38233D02*
X565294Y-38312D01*
G01X565373Y-38160D02*
X565337Y-38233D01*
G01X565401Y-38092D02*
X565373Y-38160D01*
G01X565421Y-38029D02*
X565401Y-38092D01*
G01X565434Y-37971D02*
X565421Y-38029D01*
G01X565437Y-37920D02*
X565434Y-37971D01*
G01X565432Y-37878D02*
X565437Y-37920D01*
G01X565419Y-37844D02*
X565432Y-37878D01*
G01X565402Y-37819D02*
X565419Y-37844D01*
G01X565388Y-37804D02*
X565402Y-37819D01*
G01X565383Y-37799D02*
X565388Y-37804D01*
G01X512289Y-37808D02*
X512294Y-37803D01*
G01X512275Y-37823D02*
X512289Y-37808D01*
G01X512259Y-37848D02*
X512275Y-37823D01*
G01X512247Y-37881D02*
X512259Y-37848D01*
G01X512241Y-37923D02*
X512247Y-37881D01*
G01X512244Y-37973D02*
X512241Y-37923D01*
G01X512257Y-38030D02*
X512244Y-37973D01*
G01X512277Y-38092D02*
X512257Y-38030D01*
G01X512305Y-38160D02*
X512277Y-38092D01*
G01X512341Y-38235D02*
X512305Y-38160D01*
G01X512385Y-38315D02*
X512341Y-38235D01*
G01X512431Y-38390D02*
X512385Y-38315D01*
G01X512474Y-38455D02*
X512431Y-38390D01*
G01X512513Y-38510D02*
X512474Y-38455D01*
G01X512547Y-38553D02*
X512513Y-38510D01*
G01X512572Y-38586D02*
X512547Y-38553D01*
G01X512588Y-38605D02*
X512572Y-38586D01*
G01X512593Y-38611D02*
X512588Y-38605D01*
G01X526462Y-37808D02*
X526467Y-37803D01*
G01X526448Y-37823D02*
X526462Y-37808D01*
G01X526433Y-37848D02*
X526448Y-37823D01*
G01X526420Y-37881D02*
X526433Y-37848D01*
G01X526414Y-37923D02*
X526420Y-37881D01*
G01X526418Y-37973D02*
X526414Y-37923D01*
G01X526430Y-38030D02*
X526418Y-37973D01*
G01X526450Y-38092D02*
X526430Y-38030D01*
G01X526478Y-38160D02*
X526450Y-38092D01*
G01X526514Y-38235D02*
X526478Y-38160D01*
G01X526558Y-38315D02*
X526514Y-38235D01*
G01X526604Y-38390D02*
X526558Y-38315D01*
G01X526648Y-38455D02*
X526604Y-38390D01*
G01X526687Y-38510D02*
X526648Y-38455D01*
G01X526720Y-38553D02*
X526687Y-38510D01*
G01X526745Y-38586D02*
X526720Y-38553D01*
G01X526761Y-38605D02*
X526745Y-38586D01*
G01X526766Y-38611D02*
X526761Y-38605D01*
G01X540635Y-37808D02*
X540641Y-37803D01*
G01X540622Y-37823D02*
X540635Y-37808D01*
G01X540606Y-37848D02*
X540622Y-37823D01*
G01X540593Y-37881D02*
X540606Y-37848D01*
G01X540588Y-37923D02*
X540593Y-37881D01*
G01X540591Y-37973D02*
X540588Y-37923D01*
G01X540603Y-38030D02*
X540591Y-37973D01*
G01X540623Y-38092D02*
X540603Y-38030D01*
G01X540651Y-38160D02*
X540623Y-38092D01*
G01X540687Y-38235D02*
X540651Y-38160D01*
G01X540731Y-38315D02*
X540687Y-38235D01*
G01X540777Y-38390D02*
X540731Y-38315D01*
G01X540821Y-38455D02*
X540777Y-38390D01*
G01X540860Y-38510D02*
X540821Y-38455D01*
G01X540893Y-38553D02*
X540860Y-38510D01*
G01X540919Y-38586D02*
X540893Y-38553D01*
G01X540934Y-38605D02*
X540919Y-38586D01*
G01X540939Y-38611D02*
X540934Y-38605D01*
G01X554808Y-37808D02*
X554814Y-37803D01*
G01X554795Y-37823D02*
X554808Y-37808D01*
G01X554779Y-37848D02*
X554795Y-37823D01*
G01X554766Y-37881D02*
X554779Y-37848D01*
G01X554761Y-37923D02*
X554766Y-37881D01*
G01X554764Y-37973D02*
X554761Y-37923D01*
G01X554776Y-38030D02*
X554764Y-37973D01*
G01X554797Y-38092D02*
X554776Y-38030D01*
G01X554824Y-38160D02*
X554797Y-38092D01*
G01X554861Y-38235D02*
X554824Y-38160D01*
G01X554904Y-38315D02*
X554861Y-38235D01*
G01X554951Y-38390D02*
X554904Y-38315D01*
G01X554994Y-38455D02*
X554951Y-38390D01*
G01X555033Y-38510D02*
X554994Y-38455D01*
G01X555066Y-38553D02*
X555033Y-38510D01*
G01X555092Y-38586D02*
X555066Y-38553D01*
G01X555108Y-38605D02*
X555092Y-38586D01*
G01X555113Y-38611D02*
X555108Y-38605D01*
G01X568982Y-37808D02*
X568987Y-37803D01*
G01X568968Y-37823D02*
X568982Y-37808D01*
G01X568952Y-37848D02*
X568968Y-37823D01*
G01X568940Y-37881D02*
X568952Y-37848D01*
G01X568934Y-37923D02*
X568940Y-37881D01*
G01X568937Y-37973D02*
X568934Y-37923D01*
G01X568949Y-38030D02*
X568937Y-37973D01*
G01X568970Y-38092D02*
X568949Y-38030D01*
G01X568998Y-38160D02*
X568970Y-38092D01*
G01X569034Y-38235D02*
X568998Y-38160D01*
G01X569078Y-38315D02*
X569034Y-38235D01*
G01X569124Y-38390D02*
X569078Y-38315D01*
G01X569167Y-38455D02*
X569124Y-38390D01*
G01X569206Y-38510D02*
X569167Y-38455D01*
G01X569240Y-38553D02*
X569206Y-38510D01*
G01X569265Y-38586D02*
X569240Y-38553D01*
G01X569281Y-38605D02*
X569265Y-38586D01*
G01X569286Y-38611D02*
X569281Y-38605D01*
G01X522172Y-39375D02*
X521989Y-39494D01*
G01X522296Y-39251D02*
X522172Y-39375D01*
G01X522375Y-39119D02*
X522296Y-39251D01*
G01X536345Y-39375D02*
X536162Y-39494D01*
G01X536469Y-39251D02*
X536345Y-39375D01*
G01X536548Y-39119D02*
X536469Y-39251D01*
G01X550518Y-39375D02*
X550335Y-39494D01*
G01X550642Y-39251D02*
X550518Y-39375D01*
G01X550721Y-39119D02*
X550642Y-39251D01*
G01X564692Y-39375D02*
X564508Y-39494D01*
G01X564816Y-39251D02*
X564692Y-39375D01*
G01X564895Y-39119D02*
X564816Y-39251D01*
G01X521127Y-39706D02*
X520660Y-39764D01*
G01X521536Y-39559D02*
X521127Y-39706D01*
G01X521909Y-39339D02*
X521536Y-39559D01*
G01X535301Y-39706D02*
X534833Y-39764D01*
G01X535709Y-39559D02*
X535301Y-39706D01*
G01X536082Y-39339D02*
X535709Y-39559D01*
G01X549474Y-39706D02*
X549006Y-39764D01*
G01X549883Y-39559D02*
X549474Y-39706D01*
G01X550255Y-39339D02*
X549883Y-39559D01*
G01X563647Y-39706D02*
X563179Y-39764D01*
G01X564056Y-39559D02*
X563647Y-39706D01*
G01X564428Y-39339D02*
X564056Y-39559D01*
G01X521936Y-39519D02*
X521909Y-39531D01*
G01X521963Y-39507D02*
X521936Y-39519D01*
G01X521989Y-39494D02*
X521963Y-39507D01*
G01X536110Y-39519D02*
X536082Y-39531D01*
G01X536136Y-39507D02*
X536110Y-39519D01*
G01X536162Y-39494D02*
X536136Y-39507D01*
G01X550283Y-39519D02*
X550255Y-39531D01*
G01X550309Y-39507D02*
X550283Y-39519D01*
G01X550335Y-39494D02*
X550309Y-39507D01*
G01X564456Y-39519D02*
X564428Y-39531D01*
G01X564483Y-39507D02*
X564456Y-39519D01*
G01X564508Y-39494D02*
X564483Y-39507D01*
G01X521019Y-39549D02*
X520999Y-39558D01*
G01X521073Y-39525D02*
X521019Y-39549D01*
G01X521153Y-39490D02*
X521073Y-39525D01*
G01X521249Y-39449D02*
X521153Y-39490D01*
G01X535192Y-39549D02*
X535172Y-39558D01*
G01X535246Y-39525D02*
X535192Y-39549D01*
G01X535327Y-39490D02*
X535246Y-39525D01*
G01X535422Y-39449D02*
X535327Y-39490D01*
G01X549365Y-39549D02*
X549345Y-39558D01*
G01X549419Y-39525D02*
X549365Y-39549D01*
G01X549500Y-39490D02*
X549419Y-39525D01*
G01X549596Y-39449D02*
X549500Y-39490D01*
G01X563538Y-39549D02*
X563519Y-39558D01*
G01X563592Y-39525D02*
X563538Y-39549D01*
G01X563673Y-39490D02*
X563592Y-39525D01*
G01X563769Y-39449D02*
X563673Y-39490D01*
G01X569960Y-35626D02*
G03X570058Y-36172I1575J1D01*
G01X569566Y-35626D02*
G03X569688Y-36308I1969J0D01*
G01X569369Y-35626D02*
G03X569504Y-36377I2166J2D01*
G01X568953Y-37402D02*
G03X568987Y-37803I2362J-2D01*
G01X569286Y-38611D02*
G03X571315Y-39764I2029J1209D01*
G01X570889Y-39558D02*
G03X571185Y-39764I296J110D01*
G01X555787Y-35626D02*
G03X555884Y-36172I1575J-2D01*
G01X550177D02*
G03X550275Y-35626I-1477J547D01*
G01X564351Y-36172D02*
G03X564448Y-35626I-1478J544D01*
G01X564720Y-36308D02*
G03X564842Y-35626I-1847J682D01*
G01X555393D02*
G03X555515Y-36308I1969J0D01*
G01X550547D02*
G03X550669Y-35626I-1847J682D01*
G01X564904Y-36377D02*
G03X565039Y-35626I-2031J753D01*
G01X550731Y-36377D02*
G03X550865Y-35626I-2031J750D01*
G01X555196D02*
G03X555330Y-36377I2166J-1D01*
G01X564426Y-39325D02*
G03X565081Y-38615I-1372J1923D01*
G01X565383Y-37797D02*
G03X565416Y-37402I-2329J393D01*
G01X550253Y-39325D02*
G03X550908Y-38615I-1372J1923D01*
G01X551209Y-37799D02*
G03X551243Y-37402I-2328J399D01*
G01X554780D02*
G03X554814Y-37803I2362J-2D01*
G01X555113Y-38611D02*
G03X557142Y-39764I2029J1209D01*
G01X563223D02*
G03X563519Y-39558I0J316D01*
G01X556716D02*
G03X557012Y-39764I296J110D01*
G01X549050D02*
G03X549345Y-39558I0J314D01*
G01X541613Y-35626D02*
G03X541711Y-36172I1575J1D01*
G01X536004D02*
G03X536102Y-35626I-1477J547D01*
G01X527440D02*
G03X527538Y-36172I1575J1D01*
G01X527047Y-35626D02*
G03X527169Y-36308I1967J0D01*
G01X541220Y-35626D02*
G03X541342Y-36308I1967J0D01*
G01X536373D02*
G03X536495Y-35626I-1845J682D01*
G01X526850D02*
G03X526984Y-36377I2165J-1D01*
G01X541023Y-35626D02*
G03X541157Y-36377I2165J-1D01*
G01X536558D02*
G03X536692Y-35626I-2031J750D01*
G01X526433Y-37402D02*
G03X526467Y-37803I2362J-2D01*
G01X526766Y-38611D02*
G03X528795Y-39764I2029J1209D01*
G01X536079Y-39325D02*
G03X536735Y-38615I-1370J1924D01*
G01X537037Y-37797D02*
G03X537070Y-37402I-2329J393D01*
G01X540606D02*
G03X540641Y-37803I2363J4D01*
G01X540940Y-38611D02*
G03X542969Y-39764I2029J1209D01*
G01X542543Y-39558D02*
G03X542838Y-39764I295J108D01*
G01X534877D02*
G03X535172Y-39558I0J314D01*
G01X528370D02*
G03X528665Y-39764I295J108D01*
G01X513267Y-35626D02*
G03X513365Y-36172I1575J1D01*
G01X521831D02*
G03X521928Y-35626I-1477J544D01*
G01X522200Y-36308D02*
G03X522322Y-35626I-1845J682D01*
G01X512873D02*
G03X512995Y-36308I1969J0D01*
G01X522385Y-36377D02*
G03X522519Y-35626I-2031J750D01*
G01X512676D02*
G03X512811Y-36377I2166J2D01*
G01X521906Y-39325D02*
G03X522561Y-38615I-1372J1923D01*
G01X522863Y-37797D02*
G03X522897Y-37402I-2329J399D01*
G01X512260D02*
G03X512294Y-37803I2362J-2D01*
G01X512593Y-38611D02*
G03X514622Y-39764I2029J1209D01*
G01X520704D02*
G03X520999Y-39558I0J314D01*
G01X514196D02*
G03X514492Y-39764I296J110D01*
G01X570889Y-39558D02*
X571269Y-39449D01*
G01X556716Y-39558D02*
X557096Y-39449D01*
G01X542543Y-39558D02*
X542922Y-39449D01*
G01X528370Y-39558D02*
X528749Y-39449D01*
G01X514196Y-39558D02*
X514576Y-39449D01*
G01X569504Y-36377D02*
X570058Y-36172D01*
G01X555330Y-36377D02*
X555884Y-36172D01*
G01X541157Y-36377D02*
X541711Y-36172D01*
G01X526984Y-36377D02*
X527538Y-36172D01*
G01X512811Y-36377D02*
X513365Y-36172D01*
G01X563519Y-39558D02*
X563452Y-39666D01*
G01X549345Y-39558D02*
X549278Y-39666D01*
G01X535172Y-39558D02*
X535105Y-39666D01*
G01X520999Y-39558D02*
X520932Y-39666D01*
G01X564895Y-39119D02*
X565416Y-37708D01*
G01X565023Y-37637D02*
X564428Y-39245D01*
G01X564904Y-36377D02*
X563769Y-39449D01*
G01X564720Y-36308D02*
X563519Y-39558D01*
G01X563139Y-39449D02*
X564350Y-36172D01*
G01X551243Y-37708D02*
X550721Y-39119D01*
G01X550849Y-37637D02*
X550255Y-39245D01*
G01X550731Y-36377D02*
X549596Y-39449D01*
G01X550547Y-36308D02*
X549345Y-39558D01*
G01X548966Y-39449D02*
X550177Y-36172D01*
G01X536548Y-39119D02*
X537070Y-37708D01*
G01X536676Y-37637D02*
X536082Y-39245D01*
G01X536558Y-36377D02*
X535422Y-39449D01*
G01X536373Y-36308D02*
X535172Y-39558D01*
G01X534793Y-39449D02*
X536004Y-36172D01*
G01X522375Y-39119D02*
X522897Y-37708D01*
G01X522503Y-37637D02*
X521909Y-39245D01*
G01X522385Y-36377D02*
X521249Y-39449D01*
G01X522200Y-36308D02*
X520999Y-39558D01*
G01X520620Y-39449D02*
X521831Y-36172D01*
G01X571352Y-31890D02*
Y-39764D01*
G01X571269Y-39449D02*
Y-39764D01*
G01X570639Y-39449D02*
Y-39764D01*
G01X569960Y-35626D02*
Y-7499D01*
G01X569566D02*
Y-35626D01*
G01X569369Y-7499D02*
Y-35626D01*
G01X569347Y-7577D02*
Y-37640D01*
G01X568953Y-7577D02*
Y-37402D01*
G01X568559Y-39764D02*
Y-7577D01*
G01X565810D02*
Y-39764D01*
G01X565416Y-37708D02*
Y-7577D01*
G01X565039Y-35626D02*
Y-7499D01*
G01X565023Y-37637D02*
Y-7577D01*
G01X564842Y-7499D02*
Y-35626D01*
G01X564448Y-7499D02*
Y-35626D01*
G01X564428Y-39531D02*
Y-31890D01*
G01X563769Y-39449D02*
Y-39764D01*
G01X563139Y-39449D02*
Y-39764D01*
G01X562066Y-31890D02*
Y-39764D01*
G01X561706Y-31890D02*
Y-39764D01*
G01X557178Y-31890D02*
Y-39764D01*
G01X557096D02*
Y-39449D01*
G01X556466D02*
Y-39764D01*
G01X555787Y-35626D02*
Y-7499D01*
G01X555393Y-35626D02*
Y-7499D01*
G01X555196D02*
Y-35626D01*
G01X555173Y-7577D02*
Y-37640D01*
G01X554780Y-7577D02*
Y-37402D01*
G01X554386Y-7577D02*
Y-39764D01*
G01X551637Y-7577D02*
Y-39764D01*
G01X551243Y-7577D02*
Y-37708D01*
G01X550865Y-35626D02*
Y-7499D01*
G01X550849Y-37637D02*
Y-7577D01*
G01X550669Y-7499D02*
Y-35626D01*
G01X550275Y-7499D02*
Y-35626D01*
G01X550255Y-39531D02*
Y-31890D01*
G01X549596Y-39449D02*
Y-39764D01*
G01X548966Y-39449D02*
Y-39764D01*
G01X548812Y-1181D02*
Y-39764D01*
G01X548485Y62697D02*
Y-12828D01*
G01X548419Y-39764D02*
Y-1181D01*
G01X547930Y-12828D02*
Y62697D01*
G01X543005Y-31890D02*
Y-39764D01*
G01X542922Y-39449D02*
Y-39764D01*
G01X542293Y-39449D02*
Y-39764D01*
G01X541613Y-35626D02*
Y-7499D01*
G01X541220D02*
Y-35626D01*
G01X541023Y-7499D02*
Y-35626D01*
G01X541000Y-7577D02*
Y-37640D01*
G01X540606Y-7577D02*
Y-37402D01*
G01X540213Y-39764D02*
Y-7577D01*
G01X537463D02*
Y-39764D01*
G01X537070Y-37708D02*
Y-7577D01*
G01X536692Y-35626D02*
Y-7499D01*
G01X536676Y-37637D02*
Y-7577D01*
G01X536495Y-7499D02*
Y-35626D01*
G01X536102Y-7499D02*
Y-35626D01*
G01X536082Y-39531D02*
Y-31890D01*
G01X535422Y-39449D02*
Y-39764D01*
G01X534793Y-39449D02*
Y-39764D01*
G01X533720Y-31890D02*
Y-39764D01*
G01X533360Y-31890D02*
Y-39764D01*
G01X528832Y-31890D02*
Y-39764D01*
G01X528749Y-39449D02*
Y-39764D01*
G01X528119Y-39449D02*
Y-39764D01*
G01X527440Y-35626D02*
Y-7499D01*
G01X527047D02*
Y-35626D01*
G01X526850Y-7499D02*
Y-35626D01*
G01X526827Y-7577D02*
Y-37640D01*
G01X526433Y-7577D02*
Y-37402D01*
G01X526039Y-39764D02*
Y-7577D01*
G01X523290D02*
Y-39764D01*
G01X522897Y-37708D02*
Y-7577D01*
G01X522519Y-35626D02*
Y-7499D01*
G01X522503Y-37637D02*
Y-7577D01*
G01X522322Y-7499D02*
Y-35626D01*
G01X521928Y-7499D02*
Y-35626D01*
G01X521909Y-39531D02*
Y-31890D01*
G01X521249Y-39449D02*
Y-39764D01*
G01X520620Y-39449D02*
Y-39764D01*
G01X519547Y-31890D02*
Y-39764D01*
G01X519186Y-31890D02*
Y-39764D01*
G01X514659Y-31890D02*
Y-39764D01*
G01X514576D02*
Y-39449D01*
G01X513946D02*
Y-39764D01*
G01X513267Y-35626D02*
Y-7499D01*
G01X512873Y-35626D02*
Y-7499D01*
G01X512676D02*
Y-35626D01*
G01X512654Y-7577D02*
Y-37640D01*
G01X512260Y-7577D02*
Y-37402D01*
G01X511866Y-7577D02*
Y-39764D01*
G01X570058Y-36172D02*
X571269Y-39449D01*
G01X570889Y-39558D02*
X569688Y-36308D01*
G01X570639Y-39449D02*
X569504Y-36377D01*
G01X569979Y-39350D02*
X569347Y-37640D01*
G01X568987Y-37803D02*
X569286Y-38611D01*
G01X555884Y-36172D02*
X557096Y-39449D01*
G01X555515Y-36308D02*
X556716Y-39558D01*
G01X556466Y-39449D02*
X555330Y-36377D01*
G01X555805Y-39350D02*
X555173Y-37640D01*
G01X554814Y-37803D02*
X555113Y-38611D01*
G01X541711Y-36172D02*
X542922Y-39449D01*
G01X542543Y-39558D02*
X541342Y-36308D01*
G01X542293Y-39449D02*
X541157Y-36377D01*
G01X541632Y-39350D02*
X541000Y-37640D01*
G01X540641Y-37803D02*
X540939Y-38611D01*
G01X527538Y-36172D02*
X528749Y-39449D01*
G01X528370Y-39558D02*
X527169Y-36308D01*
G01X528119Y-39449D02*
X526984Y-36377D01*
G01X527459Y-39350D02*
X526827Y-37640D01*
G01X526467Y-37803D02*
X526766Y-38611D01*
G01X513365Y-36172D02*
X514576Y-39449D01*
G01X512995Y-36308D02*
X514196Y-39558D01*
G01X513946Y-39449D02*
X512811Y-36377D01*
G01X513286Y-39350D02*
X512654Y-37640D01*
G01X512294Y-37803D02*
X512593Y-38611D01*
G01X570956Y-39666D02*
X570889Y-39558D01*
G01X556783Y-39666D02*
X556716Y-39558D01*
G01X542610Y-39666D02*
X542543Y-39558D01*
G01X528437Y-39666D02*
X528370Y-39558D01*
G01X514264Y-39666D02*
X514196Y-39558D01*
G01X570639Y-39449D02*
X570889Y-39558D01*
G01X556466Y-39449D02*
X556716Y-39558D01*
G01X542293Y-39449D02*
X542543Y-39558D01*
G01X528119Y-39449D02*
X528370Y-39558D01*
G01X513946Y-39449D02*
X514196Y-39558D01*
G01X564350Y-36172D02*
X564904Y-36377D01*
G01X550177Y-36172D02*
X550731Y-36377D01*
G01X536004Y-36172D02*
X536558Y-36377D01*
G01X521831Y-36172D02*
X522385Y-36377D01*
G01X564428Y-39471D02*
X564508Y-39494D01*
G01X563139Y-39449D02*
X563519Y-39558D01*
G01X550255Y-39471D02*
X550335Y-39494D01*
G01X548966Y-39449D02*
X549345Y-39558D01*
G01X536082Y-39471D02*
X536162Y-39494D01*
G01X534793Y-39449D02*
X535172Y-39558D01*
G01X521909Y-39471D02*
X521989Y-39494D01*
G01X520620Y-39449D02*
X520999Y-39558D01*
G01X565416Y-37708D02*
X565023Y-37637D01*
G01X551243Y-37708D02*
X550849Y-37637D01*
G01X537070Y-37708D02*
X536676Y-37637D01*
G01X522897Y-37708D02*
X522503Y-37637D01*
G01X548812Y-12828D02*
X548485D01*
G01X548419D02*
X547930D01*
G01X562066Y-31890D02*
X564428D01*
G01X533720D02*
X536082D01*
G01X519547D02*
X521909D01*
G01X519186D02*
X514659D01*
G01X533360D02*
X528832D01*
G01X548419D02*
X543005D01*
G01X550255D02*
X548812D01*
G01X561706D02*
X557178D01*
G01X575879D02*
X571352D01*
G01X569369Y-35626D02*
X569960D01*
G01X555196D02*
X555787D01*
G01X550275D02*
X550865D01*
G01X541023D02*
X541613D01*
G01X526850D02*
X527440D01*
G01X512676D02*
X513267D01*
G01X522519D02*
X521928D01*
G01X536692D02*
X536102D01*
G01X565039D02*
X564448D01*
G01X565416Y-37402D02*
X568953D01*
G01X551243D02*
X554780D01*
G01X537070D02*
X540606D01*
G01X522897D02*
X526433D01*
G01X571352Y-39276D02*
X575879D01*
G01X557178D02*
X561706D01*
G01X543005D02*
X548419D01*
G01X528832D02*
X533360D01*
G01X514659D02*
X519186D01*
G01X521909D02*
X519547D01*
G01X536082D02*
X533720D01*
G01X550255D02*
X548812D01*
G01X564428D02*
X562066D01*
G01X563769Y-39449D02*
X577313D01*
G01X549596D02*
X563139D01*
G01X548812D02*
X548966D01*
G01X535422D02*
X548419D01*
G01X521249D02*
X534793D01*
G01X548812Y-39764D02*
X590938D01*
G01X512654Y-37640D02*
X512280Y-37706D01*
G01X526453D02*
X526827Y-37640D01*
G01X540626Y-37706D02*
X541000Y-37640D01*
G01X555173D02*
X554799Y-37706D01*
G01X568973D02*
X569347Y-37640D01*
G01X520828Y-39739D02*
X520704Y-39764D01*
G01X535001Y-39739D02*
X534877Y-39764D01*
G01X549174Y-39739D02*
X549050Y-39764D01*
G01X563347Y-39739D02*
X563223Y-39764D01*
G01X523270Y-7354D02*
X523323Y-7480D01*
G01X523229Y-7224D02*
X523270Y-7354D01*
G01X523202Y-7124D02*
X523229Y-7224D01*
G01X523192Y-7087D02*
X523202Y-7124D01*
G01X537443Y-7354D02*
X537496Y-7480D01*
G01X537402Y-7224D02*
X537443Y-7354D01*
G01X537375Y-7124D02*
X537402Y-7224D01*
G01X537366Y-7087D02*
X537375Y-7124D01*
G01X551617Y-7354D02*
X551669Y-7480D01*
G01X551575Y-7224D02*
X551617Y-7354D01*
G01X551548Y-7124D02*
X551575Y-7224D01*
G01X551539Y-7087D02*
X551548Y-7124D01*
G01X523148Y-6892D02*
X523109Y-6693D01*
G01X523180Y-7035D02*
X523148Y-6892D01*
G01X523192Y-7087D02*
X523180Y-7035D01*
G01X537321Y-6892D02*
X537282Y-6693D01*
G01X537353Y-7035D02*
X537321Y-6892D01*
G01X537366Y-7087D02*
X537353Y-7035D01*
G01X565790Y-7354D02*
X565842Y-7480D01*
G01X565749Y-7224D02*
X565790Y-7354D01*
G01X565722Y-7124D02*
X565749Y-7224D01*
G01X565712Y-7087D02*
X565722Y-7124D01*
G01X565668Y-6892D02*
X565628Y-6693D01*
G01X565700Y-7035D02*
X565668Y-6892D01*
G01X565712Y-7087D02*
X565700Y-7035D01*
G01X551526D02*
X551539Y-7087D01*
G01X551494Y-6890D02*
X551526Y-7035D01*
G01X551455Y-6693D02*
X551494Y-6890D01*
G01X511977Y-7035D02*
X511964Y-7087D01*
G01X512009Y-6890D02*
X511977Y-7035D01*
G01X512048Y-6693D02*
X512009Y-6890D01*
G01X526182Y-6892D02*
X526221Y-6693D01*
G01X526150Y-7034D02*
X526182Y-6892D01*
G01X526137Y-7087D02*
X526150Y-7034D01*
G01X554496Y-7035D02*
X554484Y-7087D01*
G01X554528Y-6890D02*
X554496Y-7035D01*
G01X554568Y-6693D02*
X554528Y-6890D01*
G01X540355Y-6892D02*
X540394Y-6693D01*
G01X540323Y-7034D02*
X540355Y-6892D01*
G01X540311Y-7087D02*
X540323Y-7034D01*
G01X511956Y-7120D02*
X511964Y-7087D01*
G01X511930Y-7214D02*
X511956Y-7120D01*
G01X511889Y-7346D02*
X511930Y-7214D01*
G01X511834Y-7480D02*
X511889Y-7346D01*
G01X526129Y-7120D02*
X526137Y-7087D01*
G01X526103Y-7214D02*
X526129Y-7120D01*
G01X526062Y-7346D02*
X526103Y-7214D01*
G01X526007Y-7480D02*
X526062Y-7346D01*
G01X568701Y-6892D02*
X568741Y-6693D01*
G01X568670Y-7034D02*
X568701Y-6892D01*
G01X568657Y-7087D02*
X568670Y-7034D01*
G01X540302Y-7120D02*
X540311Y-7087D01*
G01X540277Y-7214D02*
X540302Y-7120D01*
G01X540235Y-7346D02*
X540277Y-7214D01*
G01X540180Y-7480D02*
X540235Y-7346D01*
G01X554475Y-7120D02*
X554484Y-7087D01*
G01X554450Y-7214D02*
X554475Y-7120D01*
G01X554408Y-7346D02*
X554450Y-7214D01*
G01X554354Y-7480D02*
X554408Y-7346D01*
G01X568649Y-7120D02*
X568657Y-7087D01*
G01X568623Y-7214D02*
X568649Y-7120D01*
G01X568582Y-7346D02*
X568623Y-7214D01*
G01X568527Y-7480D02*
X568582Y-7346D01*
G01X573149Y48425D02*
G03I-708J0D01*
G01X574688Y46771D02*
G03I-1968J0D01*
G01X573149Y44094D02*
G03I-708J0D01*
G01X571342Y45039D02*
G03X570358Y44055I0J-984D01*
G01X574295Y39478D02*
G03X571145I-1575J0D01*
G01X573149Y34252D02*
G03I-708J0D01*
G01Y38582D02*
G03I-708J0D01*
G01X571184Y36087D02*
G03Y34307I1300J-890D01*
G01X566063Y48819D02*
G03I-709J0D01*
G01X551889D02*
G03I-708J0D01*
G01X558976Y48425D02*
G03I-709J0D01*
G01X567602Y46771D02*
G03I-1969J0D01*
G01X560515D02*
G03I-1968J0D01*
G01X553428D02*
G03I-1968J0D01*
G01X566063Y43307D02*
G03I-709J0D01*
G01X558976Y44094D02*
G03I-709J0D01*
G01X557169Y45039D02*
G03X556184Y44055I0J-985D01*
G01X560909D02*
G03X559925Y45039I-984J0D01*
G01X564255D02*
G03X563271Y44055I0J-984D01*
G01X567995D02*
G03X567011Y45039I-984J0D01*
G01X560121Y39478D02*
G03X556972I-1574J0D01*
G01X567208D02*
G03X564058I-1575J0D01*
G01X566063Y34645D02*
G03I-709J0D01*
G01Y38976D02*
G03I-709J0D01*
G01X558976Y34252D02*
G03I-709J0D01*
G01Y38582D02*
G03I-709J0D01*
G01X557011Y36087D02*
G03Y34307I1299J-890D01*
G01X560082D02*
G03Y36087I-1299J890D01*
G01X567169Y34307D02*
G03Y36087I-1300J890D01*
G01X564098D02*
G03Y34307I1299J-890D01*
G01X551889Y43307D02*
G03I-708J0D01*
G01X550082Y45039D02*
G03X549098Y44055I0J-984D01*
G01X553822D02*
G03X552838Y45039I-984J0D01*
G01X546736Y44055D02*
G03X545751Y45039I-984J0D01*
G01X553035Y39478D02*
G03X549885I-1575J0D01*
G01X551889Y34645D02*
G03I-708J0D01*
G01Y38976D02*
G03I-708J0D01*
G01X549924Y36087D02*
G03Y34307I1300J-890D01*
G01X552995D02*
G03Y36087I-1299J890D01*
G01X573149Y29921D02*
G03I-708J0D01*
G01X571184Y29000D02*
G03Y27220I1300J-890D01*
G01X573149Y20078D02*
G03I-708J0D01*
G01Y24409D02*
G03I-708J0D01*
G01Y10236D02*
G03I-708J0D01*
G01Y15748D02*
G03I-708J0D01*
G01X566063Y29134D02*
G03I-709J0D01*
G01X560082Y27220D02*
G03Y29000I-1299J890D01*
G01X567169Y27220D02*
G03Y29000I-1300J890D01*
G01X564098D02*
G03Y27220I1299J-890D01*
G01X566063Y20472D02*
G03I-709J0D01*
G01Y24803D02*
G03I-709J0D01*
G01X551889Y29134D02*
G03I-708J0D01*
G01X558976Y29921D02*
G03I-709J0D01*
G01X549924Y29000D02*
G03Y27220I1300J-890D01*
G01X552995D02*
G03Y29000I-1299J890D01*
G01X557011D02*
G03Y27220I1299J-890D01*
G01X551889Y20472D02*
G03I-708J0D01*
G01X558976Y20078D02*
G03I-709J0D01*
G01X551889Y24803D02*
G03I-708J0D01*
G01X558976Y24409D02*
G03I-709J0D01*
G01X566063Y14960D02*
G03I-709J0D01*
G01X558976Y10236D02*
G03I-709J0D01*
G01Y15748D02*
G03I-709J0D01*
G01X551889Y14960D02*
G03I-708J0D01*
G01X537716Y48819D02*
G03I-708J0D01*
G01X530630Y48425D02*
G03I-709J0D01*
G01X544803D02*
G03I-709J0D01*
G01X546342Y46771D02*
G03I-1969J0D01*
G01X539255D02*
G03I-1968J0D01*
G01X532169D02*
G03I-1969J0D01*
G01X537716Y43307D02*
G03I-708J0D01*
G01X544803Y44094D02*
G03I-709J0D01*
G01X535909Y45039D02*
G03X534925Y44055I0J-984D01*
G01X539649D02*
G03X538665Y45039I-984J0D01*
G01X542995D02*
G03X542011Y44055I0J-984D01*
G01X538862Y39478D02*
G03X535712I-1575J0D01*
G01X545948D02*
G03X542799I-1574J0D01*
G01X537716Y34645D02*
G03I-708J0D01*
G01X544803Y34252D02*
G03I-709J0D01*
G01X537716Y38976D02*
G03I-708J0D01*
G01X544803Y38582D02*
G03I-709J0D01*
G01X542838Y36087D02*
G03Y34307I1299J-890D01*
G01X545909D02*
G03Y36087I-1299J890D01*
G01X538822Y34307D02*
G03Y36087I-1299J890D01*
G01X535751D02*
G03Y34307I1300J-890D01*
G01X530630Y44094D02*
G03I-709J0D01*
G01X525476Y44055D02*
G03X524491Y45039I-984J0D01*
G01X528822D02*
G03X527838Y44055I0J-984D01*
G01X532562D02*
G03X531578Y45039I-984J0D01*
G01X531775Y39478D02*
G03X528625I-1575J0D01*
G01X530630Y34252D02*
G03I-709J0D01*
G01Y38582D02*
G03I-709J0D01*
G01X531736Y34307D02*
G03Y36087I-1300J890D01*
G01X528665D02*
G03Y34307I1299J-890D01*
G01X524649D02*
G03Y36087I-1299J890D01*
G01X523543Y48819D02*
G03I-709J0D01*
G01X516456Y48425D02*
G03I-708J0D01*
G01X525082Y46771D02*
G03I-1969J0D01*
G01X517995D02*
G03I-1968J0D01*
G01X523543Y43307D02*
G03I-709J0D01*
G01X516456Y44094D02*
G03I-708J0D01*
G01X514649Y45039D02*
G03X513665Y44055I0J-984D01*
G01X518389D02*
G03X517405Y45039I-984J0D01*
G01X521736D02*
G03X520751Y44055I0J-985D01*
G01X517602Y39478D02*
G03X514452I-1575J0D01*
G01X524688D02*
G03X521539I-1574J0D01*
G01X523543Y34645D02*
G03I-709J0D01*
G01Y38976D02*
G03I-709J0D01*
G01X516456Y34252D02*
G03I-708J0D01*
G01Y38582D02*
G03I-708J0D01*
G01X514491Y36087D02*
G03Y34307I1300J-890D01*
G01X517562D02*
G03Y36087I-1299J890D01*
G01X521578D02*
G03Y34307I1299J-890D01*
G01X537716Y29134D02*
G03I-708J0D01*
G01X544803Y29921D02*
G03I-709J0D01*
G01X545909Y27220D02*
G03Y29000I-1299J890D01*
G01X542838D02*
G03Y27220I1299J-890D01*
G01X538822D02*
G03Y29000I-1299J890D01*
G01X535751D02*
G03Y27220I1300J-890D01*
G01X537716Y20472D02*
G03I-708J0D01*
G01X544803Y20078D02*
G03I-709J0D01*
G01X537716Y24803D02*
G03I-708J0D01*
G01X544803Y24409D02*
G03I-709J0D01*
G01X530630Y29921D02*
G03I-709J0D01*
G01X531736Y27220D02*
G03Y29000I-1300J890D01*
G01X528665D02*
G03Y27220I1299J-890D01*
G01X524649D02*
G03Y29000I-1299J890D01*
G01X530630Y20078D02*
G03I-709J0D01*
G01Y24409D02*
G03I-709J0D01*
G01X544803Y10236D02*
G03I-709J0D01*
G01X537716Y14960D02*
G03I-708J0D01*
G01X544803Y15748D02*
G03I-709J0D01*
G01X530630Y10236D02*
G03I-709J0D01*
G01Y15748D02*
G03I-709J0D01*
G01X523543Y29134D02*
G03I-709J0D01*
G01X516456Y29921D02*
G03I-708J0D01*
G01X514491Y29000D02*
G03Y27220I1300J-890D01*
G01X517562D02*
G03Y29000I-1299J890D01*
G01X521578D02*
G03Y27220I1299J-890D01*
G01X523543Y20472D02*
G03I-709J0D01*
G01Y24803D02*
G03I-709J0D01*
G01X516456Y20078D02*
G03I-708J0D01*
G01Y24409D02*
G03I-708J0D01*
G01X523543Y14960D02*
G03I-709J0D01*
G01X516456Y10236D02*
G03I-708J0D01*
G01Y15748D02*
G03I-708J0D01*
G01X573149Y5905D02*
G03I-708J0D01*
G01X569351Y-7499D02*
G03X569154Y-7302I-197J0D01*
G01X569548Y-7499D02*
G03X569154Y-7105I-394J0D01*
G01X569942Y-7499D02*
G03X569154Y-6711I-788J0D01*
G01X558976Y5905D02*
G03I-709J0D01*
G01X568556Y-7577D02*
G03X568524Y-7482I-157J0D01*
G01X565845D02*
G03X565813Y-7577I125J-95D01*
G01X554383D02*
G03X554351Y-7482I-157J0D01*
G01X551672D02*
G03X551640Y-7577I125J-95D01*
G01X565254Y-7302D02*
G03X565057Y-7499I0J-197D01*
G01X551080Y-7302D02*
G03X550884Y-7499I0J-196D01*
G01X555178D02*
G03X554981Y-7302I-197J0D01*
G01X565254Y-7105D02*
G03X564860Y-7499I0J-394D01*
G01X555375D02*
G03X554981Y-7105I-394J0D01*
G01X551080D02*
G03X550687Y-7499I0J-393D01*
G01X565714Y-7089D02*
G03X565419Y-7577I256J-488D01*
G01X568950D02*
G03X568656Y-7089I-552J0D01*
G01X554776Y-7577D02*
G03X554482Y-7089I-552J0D01*
G01X551540D02*
G03X551246Y-7577I258J-488D01*
G01X555769Y-7499D02*
G03X554981Y-6711I-788J0D01*
G01X551080D02*
G03X550293Y-7499I0J-787D01*
G01X565254Y-6711D02*
G03X564466Y-7499I0J-788D01*
G01X565629Y-6696D02*
G03X565026Y-7577I342J-881D01*
G01X569343D02*
G03X568740Y-6696I-945J0D01*
G01X551456D02*
G03X550852Y-7577I341J-881D01*
G01X555170D02*
G03X554566Y-6696I-945J0D01*
G01X530630Y5905D02*
G03I-709J0D01*
G01X544803D02*
G03I-709J0D01*
G01X540210Y-7577D02*
G03X540178Y-7482I-157J0D01*
G01X537498D02*
G03X537467Y-7577I126J-94D01*
G01X526832Y-7499D02*
G03X526635Y-7302I-197J0D01*
G01X536907D02*
G03X536710Y-7499I0J-197D01*
G01X541005D02*
G03X540808Y-7302I-197J0D01*
G01X527028Y-7499D02*
G03X526635Y-7105I-394J0D01*
G01X541202Y-7499D02*
G03X540808Y-7105I-394J0D01*
G01X536907D02*
G03X536513Y-7499I0J-394D01*
G01X537367Y-7089D02*
G03X537073Y-7577I258J-488D01*
G01X540603D02*
G03X540309Y-7089I-552J0D01*
G01X541595Y-7499D02*
G03X540808Y-6711I-788J0D01*
G01X536907D02*
G03X536120Y-7499I0J-787D01*
G01X527422D02*
G03X526635Y-6711I-788J0D01*
G01X537283Y-6696D02*
G03X536679Y-7577I341J-881D01*
G01X540997D02*
G03X540393Y-6696I-945J0D01*
G01X516456Y5905D02*
G03I-708J0D01*
G01X526036Y-7577D02*
G03X526005Y-7482I-157J1D01*
G01X523325D02*
G03X523293Y-7577I125J-95D01*
G01X511863D02*
G03X511831Y-7482I-157J0D01*
G01X522734Y-7302D02*
G03X522537Y-7499I0J-197D01*
G01X512658D02*
G03X512462Y-7302I-197J0D01*
G01X522734Y-7105D02*
G03X522340Y-7499I0J-394D01*
G01X512855D02*
G03X512462Y-7105I-394J0D01*
G01X523194Y-7089D02*
G03X522900Y-7577I258J-488D01*
G01X526430D02*
G03X526136Y-7089I-552J0D01*
G01X512257Y-7577D02*
G03X511963Y-7089I-552J0D01*
G01X513249Y-7499D02*
G03X512462Y-6711I-788J0D01*
G01X522734D02*
G03X521947Y-7499I0J-787D01*
G01X523110Y-6696D02*
G03X522506Y-7577I341J-881D01*
G01X526824D02*
G03X526220Y-6696I-945J0D01*
G01X512650Y-7577D02*
G03X512047Y-6696I-945J0D01*
G01X571155Y25730D02*
X569767Y23327D01*
G01X564068Y25730D02*
X562680Y23327D01*
G01X571972Y39921D02*
X571184Y38557D01*
G01X556982Y25730D02*
X555594Y23327D01*
G01X564885Y39921D02*
X564098Y38557D01*
G01X549895Y25730D02*
X548507Y23327D01*
G01X557799Y39921D02*
X557011Y38557D01*
G01X542808Y25730D02*
X541421Y23327D01*
G01X550712Y39921D02*
X549925Y38557D01*
G01X535722Y25730D02*
X534334Y23327D01*
G01X543625Y39921D02*
X542838Y38557D01*
G01X528635Y25730D02*
X527247Y23327D01*
G01X536539Y39921D02*
X535751Y38557D01*
G01X521549Y25730D02*
X520161Y23327D01*
G01X529452Y39921D02*
X528665Y38557D01*
G01X514462Y25730D02*
X513074Y23327D01*
G01X522365Y39921D02*
X521578Y38557D01*
G01X515279Y39921D02*
X514491Y38557D01*
G01X571184Y36087D02*
Y38557D01*
G01Y29000D02*
Y34307D01*
G01Y22204D02*
Y27220D01*
G01X571155Y27265D02*
Y25730D01*
G01Y34351D02*
Y28955D01*
G01Y39478D02*
Y36042D01*
G01X570358Y44055D02*
Y22204D01*
G01X569154Y-7284D02*
Y-6693D01*
G01X567995Y44055D02*
Y22204D01*
G01X567198Y36042D02*
Y39478D01*
G01Y28955D02*
Y34351D01*
G01Y25730D02*
Y27265D01*
G01X567169Y27220D02*
Y22204D01*
G01Y34307D02*
Y29000D01*
G01Y38557D02*
Y36087D01*
G01X565254Y-7284D02*
Y-6693D01*
G01X564098Y36087D02*
Y38557D01*
G01Y29000D02*
Y34307D01*
G01Y22204D02*
Y27220D01*
G01X564068Y27265D02*
Y25730D01*
G01Y34351D02*
Y28955D01*
G01Y39478D02*
Y36042D01*
G01X563271Y44055D02*
Y22204D01*
G01X560909D02*
Y44055D01*
G01X560112Y36042D02*
Y39478D01*
G01Y28955D02*
Y34351D01*
G01Y25730D02*
Y27265D01*
G01X560082Y27220D02*
Y22204D01*
G01Y34307D02*
Y29000D01*
G01Y38557D02*
Y36087D01*
G01X557011D02*
Y38557D01*
G01Y29000D02*
Y34307D01*
G01Y22204D02*
Y27220D01*
G01X556982Y27265D02*
Y25730D01*
G01Y34351D02*
Y28955D01*
G01Y39478D02*
Y36042D01*
G01X556184Y44055D02*
Y22204D01*
G01X554981Y-7284D02*
Y-6693D01*
G01X553822Y22204D02*
Y44055D01*
G01X553025Y36042D02*
Y39478D01*
G01Y28955D02*
Y34351D01*
G01Y25730D02*
Y27265D01*
G01X552995Y27220D02*
Y22204D01*
G01Y34307D02*
Y29000D01*
G01Y38557D02*
Y36087D01*
G01X551080Y-7284D02*
Y-6693D01*
G01X549925Y36087D02*
Y38557D01*
G01Y29000D02*
Y34307D01*
G01Y22204D02*
Y27220D01*
G01X549895Y27265D02*
Y25730D01*
G01Y34351D02*
Y28955D01*
G01Y39478D02*
Y36042D01*
G01X549098Y44055D02*
Y22204D01*
G01X546736D02*
Y44055D01*
G01X545938Y36042D02*
Y39478D01*
G01Y28955D02*
Y34351D01*
G01Y25730D02*
Y27265D01*
G01X545909Y27220D02*
Y22204D01*
G01Y34307D02*
Y29000D01*
G01Y38557D02*
Y36087D01*
G01X542838Y27220D02*
Y22204D01*
G01Y34307D02*
Y29000D01*
G01Y38557D02*
Y36087D01*
G01X542808Y27265D02*
Y25730D01*
G01Y34351D02*
Y28955D01*
G01Y39478D02*
Y36042D01*
G01X542011Y44055D02*
Y22204D01*
G01X540808Y-7284D02*
Y-6693D01*
G01X539649Y44055D02*
Y22204D01*
G01X538852Y36042D02*
Y39478D01*
G01Y28955D02*
Y34351D01*
G01Y25730D02*
Y27265D01*
G01X538822Y27220D02*
Y22204D01*
G01Y34307D02*
Y29000D01*
G01Y38557D02*
Y36087D01*
G01X536907Y-7284D02*
Y-6693D01*
G01X535751Y36087D02*
Y38557D01*
G01Y29000D02*
Y34307D01*
G01Y22204D02*
Y27220D01*
G01X535722Y27265D02*
Y25730D01*
G01Y34351D02*
Y28955D01*
G01Y39478D02*
Y36042D01*
G01X534925Y44055D02*
Y22204D01*
G01X532562Y44055D02*
Y22204D01*
G01X531765Y36042D02*
Y39478D01*
G01Y28955D02*
Y34351D01*
G01Y25730D02*
Y27265D01*
G01X531736Y27220D02*
Y22204D01*
G01Y34307D02*
Y29000D01*
G01Y38557D02*
Y36087D01*
G01X528665D02*
Y38557D01*
G01Y29000D02*
Y34307D01*
G01Y22204D02*
Y27220D01*
G01X528635Y27265D02*
Y25730D01*
G01Y34351D02*
Y28955D01*
G01Y39478D02*
Y36042D01*
G01X527838Y44055D02*
Y22204D01*
G01X526635Y-7284D02*
Y-6693D01*
G01X525476Y44055D02*
Y22204D01*
G01X524678Y36042D02*
Y39478D01*
G01Y28955D02*
Y34351D01*
G01Y25730D02*
Y27265D01*
G01X524649Y27220D02*
Y22204D01*
G01Y34307D02*
Y29000D01*
G01Y38557D02*
Y36087D01*
G01X522734Y-7284D02*
Y-6693D01*
G01X521578Y36087D02*
Y38557D01*
G01Y29000D02*
Y34307D01*
G01Y22204D02*
Y27220D01*
G01X521549Y27265D02*
Y25730D01*
G01Y34351D02*
Y28955D01*
G01Y39478D02*
Y36042D01*
G01X520751Y44055D02*
Y22204D01*
G01X518389D02*
Y44055D01*
G01X517592Y36042D02*
Y39478D01*
G01Y28955D02*
Y34351D01*
G01Y25730D02*
Y27265D01*
G01X517562Y27220D02*
Y22204D01*
G01Y34307D02*
Y29000D01*
G01Y38557D02*
Y36087D01*
G01X514491D02*
Y38557D01*
G01Y29000D02*
Y34307D01*
G01Y22204D02*
Y27220D01*
G01X514462Y27265D02*
Y25730D01*
G01Y34351D02*
Y28955D01*
G01Y39478D02*
Y36042D01*
G01X513665Y44055D02*
Y22204D01*
G01X512462Y-7284D02*
Y-6693D01*
G01X511302Y22204D02*
Y44055D01*
G01X566381Y39921D02*
X567169Y38557D01*
G01X559295Y39921D02*
X560082Y38557D01*
G01X568586Y23327D02*
X567198Y25730D01*
G01X552208Y39921D02*
X552995Y38557D01*
G01X561499Y23327D02*
X560112Y25730D01*
G01X545121Y39921D02*
X545909Y38557D01*
G01X554413Y23327D02*
X553025Y25730D01*
G01X538035Y39921D02*
X538822Y38557D01*
G01X547326Y23327D02*
X545938Y25730D01*
G01X530948Y39921D02*
X531736Y38557D01*
G01X540239Y23327D02*
X538852Y25730D01*
G01X523862Y39921D02*
X524649Y38557D01*
G01X533153Y23327D02*
X531765Y25730D01*
G01X516775Y39921D02*
X517562Y38557D01*
G01X526066Y23327D02*
X524678Y25730D01*
G01X518980Y23327D02*
X517592Y25730D01*
G01X517405Y45039D02*
X514649D01*
G01X524491D02*
X521736D01*
G01X531578D02*
X528822D01*
G01X538665D02*
X535909D01*
G01X545751D02*
X542995D01*
G01X552838D02*
X550082D01*
G01X559925D02*
X557169D01*
G01X567011D02*
X564255D01*
G01X574098D02*
X571342D01*
G01X570358Y42516D02*
X575082D01*
G01X563271D02*
X567995D01*
G01X534925D02*
X539649D01*
G01X527838D02*
X532562D01*
G01X520751D02*
X525476D01*
G01X518389D02*
X513665D01*
G01X546736D02*
X542011D01*
G01X553822D02*
X549098D01*
G01X560909D02*
X556184D01*
G01X557799Y39921D02*
X559295D01*
G01X550712D02*
X552208D01*
G01X515279D02*
X516775D01*
G01X523862D02*
X522365D01*
G01X530948D02*
X529452D01*
G01X538035D02*
X536539D01*
G01X545121D02*
X543625D01*
G01X566381D02*
X564885D01*
G01X573468D02*
X571972D01*
G01X567405Y25372D02*
X570948D01*
G01X560318D02*
X563862D01*
G01X553232D02*
X556775D01*
G01X546145D02*
X549688D01*
G01X539058D02*
X542602D01*
G01X531972D02*
X535515D01*
G01X524885D02*
X528428D01*
G01X517799D02*
X521342D01*
G01X513074Y23327D02*
X511893D01*
G01X520161D02*
X518980D01*
G01X527247D02*
X526066D01*
G01X534334D02*
X533153D01*
G01X541421D02*
X540239D01*
G01X548507D02*
X547326D01*
G01X555594D02*
X554413D01*
G01X562680D02*
X561499D01*
G01X569767D02*
X568586D01*
G01X567169Y22204D02*
X571184D01*
G01X560082D02*
X564098D01*
G01X552995D02*
X557011D01*
G01X548485D02*
X549925D01*
G01X545909D02*
X547930D01*
G01X531736D02*
X535751D01*
G01X524649D02*
X528665D01*
G01X517562D02*
X521578D01*
G01X542838D02*
X538822D01*
G01X590938Y-1181D02*
X548485D01*
G01X590938Y-1772D02*
X548812D01*
G01X590938Y-4394D02*
X548812D01*
G01X590938Y-4591D02*
X548812D01*
G01X526635Y-6693D02*
X522734D01*
G01X540808D02*
X536907D01*
G01X554981D02*
X551080D01*
G01X569154D02*
X565254D01*
G01X526635Y-7087D02*
X522734D01*
G01X540808D02*
X536907D01*
G01X554981D02*
X551080D01*
G01X569154D02*
X565254D01*
G01Y-7284D02*
X569154D01*
G01X551080D02*
X554981D01*
G01X536907D02*
X540808D01*
G01X522734D02*
X526635D01*
G01X526007Y-7480D02*
X523323D01*
G01X540180D02*
X537496D01*
G01X554354D02*
X551669D01*
G01X568527D02*
X565842D01*
G01X569369Y-7499D02*
X569960D01*
G01X564448D02*
X565039D01*
G01X555196D02*
X555787D01*
G01X541023D02*
X541613D01*
G01X536102D02*
X536692D01*
G01X526850D02*
X527440D01*
G01X521928D02*
X522519D01*
G01X512676D02*
X513267D01*
G01X550865D02*
X550275D01*
G01X568559Y-7577D02*
X569347D01*
G01X554386D02*
X555173D01*
G01X550849D02*
X551637D01*
G01X540213D02*
X541000D01*
G01X526039D02*
X526827D01*
G01X511866D02*
X512654D01*
G01X523290D02*
X522503D01*
G01X537463D02*
X536676D01*
G01X565810D02*
X565023D01*
G01X514617Y53330D02*
X514491Y53648D01*
G01X514833Y53051D02*
X514617Y53330D01*
G01X521703D02*
X521578Y53648D01*
G01X521919Y53051D02*
X521703Y53330D01*
G01X528790D02*
X528665Y53648D01*
G01X529006Y53051D02*
X528790Y53330D01*
G01X535877D02*
X535751Y53648D01*
G01X536093Y53051D02*
X535877Y53330D01*
G01X542963D02*
X542838Y53648D01*
G01X543179Y53051D02*
X542963Y53330D01*
G01X550050D02*
X549925Y53648D01*
G01X550266Y53051D02*
X550050Y53330D01*
G01X557136D02*
X557011Y53648D01*
G01X557353Y53051D02*
X557136Y53330D01*
G01X564223D02*
X564098Y53648D01*
G01X564439Y53051D02*
X564223Y53330D01*
G01X571310D02*
X571184Y53648D01*
G01X571526Y53051D02*
X571310Y53330D01*
G01X514634Y53425D02*
X514833Y53051D01*
G01X514508Y53849D02*
X514634Y53425D01*
G01X514462Y54309D02*
X514508Y53849D01*
G01X521721Y53425D02*
X521919Y53051D01*
G01X521594Y53849D02*
X521721Y53425D01*
G01X521549Y54309D02*
X521594Y53849D01*
G01X528808Y53425D02*
X529006Y53051D01*
G01X528681Y53849D02*
X528808Y53425D01*
G01X528635Y54309D02*
X528681Y53849D01*
G01X535894Y53425D02*
X536093Y53051D01*
G01X535767Y53849D02*
X535894Y53425D01*
G01X535722Y54309D02*
X535767Y53849D01*
G01X514469Y53766D02*
X514491Y53643D01*
G01X514462Y53889D02*
X514469Y53766D01*
G01X521556D02*
X521578Y53643D01*
G01X521549Y53889D02*
X521556Y53766D01*
G01X528643D02*
X528665Y53643D01*
G01X528635Y53889D02*
X528643Y53766D01*
G01X542981Y53425D02*
X543179Y53051D01*
G01X542854Y53849D02*
X542981Y53425D01*
G01X542808Y54309D02*
X542854Y53849D01*
G01X550067Y53425D02*
X550266Y53051D01*
G01X549941Y53849D02*
X550067Y53425D01*
G01X549895Y54309D02*
X549941Y53849D01*
G01X557154Y53425D02*
X557353Y53051D01*
G01X557027Y53849D02*
X557154Y53425D01*
G01X556982Y54309D02*
X557027Y53849D01*
G01X564241Y53425D02*
X564439Y53051D01*
G01X564114Y53849D02*
X564241Y53425D01*
G01X564068Y54309D02*
X564114Y53849D01*
G01X571327Y53425D02*
X571526Y53051D01*
G01X571200Y53849D02*
X571327Y53425D01*
G01X571155Y54309D02*
X571200Y53849D01*
G01X535729Y53766D02*
X535751Y53643D01*
G01X535722Y53889D02*
X535729Y53766D01*
G01X542816D02*
X542838Y53643D01*
G01X542808Y53889D02*
X542816Y53766D01*
G01X549902D02*
X549925Y53643D01*
G01X549895Y53889D02*
X549902Y53766D01*
G01X556989D02*
X557011Y53643D01*
G01X556982Y53889D02*
X556989Y53766D01*
G01X564076D02*
X564098Y53643D01*
G01X564068Y53889D02*
X564076Y53766D01*
G01X517584Y53767D02*
X517562Y53643D01*
G01X517592Y53889D02*
X517584Y53767D01*
G01X524671D02*
X524649Y53643D01*
G01X524678Y53889D02*
X524671Y53767D01*
G01X531758D02*
X531736Y53643D01*
G01X531765Y53889D02*
X531758Y53767D01*
G01X538844D02*
X538822Y53643D01*
G01X538852Y53889D02*
X538844Y53767D01*
G01X571162Y53766D02*
X571184Y53643D01*
G01X571155Y53889D02*
X571162Y53766D01*
G01X545931Y53767D02*
X545909Y53643D01*
G01X545938Y53889D02*
X545931Y53767D01*
G01X553018D02*
X552995Y53643D01*
G01X553025Y53889D02*
X553018Y53767D01*
G01X560104D02*
X560082Y53643D01*
G01X560112Y53889D02*
X560104Y53767D01*
G01X567191D02*
X567169Y53643D01*
G01X567198Y53889D02*
X567191Y53767D01*
G01X517435Y53327D02*
X517221Y53051D01*
G01X517562Y53648D02*
X517435Y53327D01*
G01X524522D02*
X524308Y53051D01*
G01X524649Y53648D02*
X524522Y53327D01*
G01X531608D02*
X531394Y53051D01*
G01X531736Y53648D02*
X531608Y53327D01*
G01X538695D02*
X538481Y53051D01*
G01X538822Y53648D02*
X538695Y53327D01*
G01X545782D02*
X545567Y53051D01*
G01X545909Y53648D02*
X545782Y53327D01*
G01X552868D02*
X552654Y53051D01*
G01X552995Y53648D02*
X552868Y53327D01*
G01X517546Y53849D02*
X517592Y54309D01*
G01X517420Y53425D02*
X517546Y53849D01*
G01X517221Y53051D02*
X517420Y53425D01*
G01X524633Y53849D02*
X524678Y54309D01*
G01X524506Y53425D02*
X524633Y53849D01*
G01X524308Y53051D02*
X524506Y53425D01*
G01X531720Y53849D02*
X531765Y54309D01*
G01X531593Y53425D02*
X531720Y53849D01*
G01X531394Y53051D02*
X531593Y53425D01*
G01X538806Y53849D02*
X538852Y54309D01*
G01X538679Y53425D02*
X538806Y53849D01*
G01X538481Y53051D02*
X538679Y53425D01*
G01X559955Y53327D02*
X559741Y53051D01*
G01X560082Y53648D02*
X559955Y53327D01*
G01X567041D02*
X566827Y53051D01*
G01X567169Y53648D02*
X567041Y53327D01*
G01X545893Y53849D02*
X545938Y54309D01*
G01X545766Y53425D02*
X545893Y53849D01*
G01X545567Y53051D02*
X545766Y53425D01*
G01X552979Y53849D02*
X553025Y54309D01*
G01X552853Y53425D02*
X552979Y53849D01*
G01X552654Y53051D02*
X552853Y53425D01*
G01X560066Y53849D02*
X560112Y54309D01*
G01X559939Y53425D02*
X560066Y53849D01*
G01X559741Y53051D02*
X559939Y53425D01*
G01X567153Y53849D02*
X567198Y54309D01*
G01X567026Y53425D02*
X567153Y53849D01*
G01X566827Y53051D02*
X567026Y53425D01*
G01X571518Y53045D02*
G03X573921I1201J1018D01*
G01X566063Y53149D02*
G03I-709J0D01*
G01X551889D02*
G03I-708J0D01*
G01X564432Y53045D02*
G03X566835I1202J1018D01*
G01X557345D02*
G03X559748I1201J1018D01*
G01X550258D02*
G03X552662I1202J1018D01*
G01X537716Y53149D02*
G03I-708J0D01*
G01X543172Y53045D02*
G03X545575I1201J1018D01*
G01X536085D02*
G03X538488I1201J1018D01*
G01X528999D02*
G03X531402I1202J1018D01*
G01X523543Y53149D02*
G03I-709J0D01*
G01X521912Y53045D02*
G03X524315I1201J1018D01*
G01X514825D02*
G03X517228I1202J1018D01*
G01X572365Y61712D02*
X571184Y60531D01*
G01X565279Y61712D02*
X564098Y60531D01*
G01X558192Y61712D02*
X557011Y60531D01*
G01X551106Y61712D02*
X549925Y60531D01*
G01X544019Y61712D02*
X542838Y60531D01*
G01X536932Y61712D02*
X535751Y60531D01*
G01X529846Y61712D02*
X528665Y60531D01*
G01X522759Y61712D02*
X521578Y60531D01*
G01X515673Y61712D02*
X514491Y60531D01*
G01X571184Y52657D02*
Y60531D01*
G01X571155Y60138D02*
Y53889D01*
G01X567198Y60138D02*
Y53889D01*
G01X567169Y60531D02*
Y52657D01*
G01X564098D02*
Y60531D01*
G01X564068Y60138D02*
Y53889D01*
G01X560112Y60138D02*
Y53889D01*
G01X560082Y60531D02*
Y52657D01*
G01X557011D02*
Y60531D01*
G01X556982Y60138D02*
Y53889D01*
G01X553025Y60138D02*
Y53889D01*
G01X552995Y60531D02*
Y52657D01*
G01X549925D02*
Y60531D01*
G01X549895Y60138D02*
Y53889D01*
G01X545938Y60138D02*
Y53889D01*
G01X545909Y60531D02*
Y52657D01*
G01X542838D02*
Y60531D01*
G01X542808Y60138D02*
Y53889D01*
G01X538852Y60138D02*
Y53889D01*
G01X538822Y60531D02*
Y52657D01*
G01X535751D02*
Y60531D01*
G01X535722Y60138D02*
Y53889D01*
G01X531765Y60138D02*
Y53889D01*
G01X531736Y60531D02*
Y52657D01*
G01X528665D02*
Y60531D01*
G01X528635Y60138D02*
Y53889D01*
G01X524678Y60138D02*
Y53889D01*
G01X524649Y60531D02*
Y52657D01*
G01X521578D02*
Y60531D01*
G01X521549Y60138D02*
Y53889D01*
G01X517592Y60138D02*
Y53889D01*
G01X517562Y60531D02*
Y52657D01*
G01X514491D02*
Y60531D01*
G01X514462Y60138D02*
Y53889D01*
G01X573074Y61712D02*
X574255Y60531D01*
G01X565988Y61712D02*
X567169Y60531D01*
G01X558901Y61712D02*
X560082Y60531D01*
G01X551814Y61712D02*
X552995Y60531D01*
G01X544728Y61712D02*
X545909Y60531D01*
G01X537641Y61712D02*
X538822Y60531D01*
G01X530554Y61712D02*
X531736Y60531D01*
G01X523468Y61712D02*
X524649Y60531D01*
G01X516381Y61712D02*
X517562Y60531D01*
G01X548485Y62697D02*
X590449D01*
G01X516381Y61712D02*
X515673D01*
G01X523468D02*
X522759D01*
G01X530554D02*
X529846D01*
G01X537641D02*
X536932D01*
G01X544728D02*
X544019D01*
G01X551814D02*
X551106D01*
G01X558901D02*
X558192D01*
G01X565988D02*
X565279D01*
G01X573074D02*
X572365D01*
G01X517562Y60531D02*
X514491D01*
G01X524649D02*
X521578D01*
G01X531736D02*
X528665D01*
G01X538822D02*
X535751D01*
G01X545909D02*
X542838D01*
G01X552995D02*
X549925D01*
G01X560082D02*
X557011D01*
G01X567169D02*
X564098D01*
G01X574255D02*
X571184D01*
G01X548485Y58956D02*
X590449D01*
G01X521919Y53051D02*
X517221D01*
G01X529006D02*
X524308D01*
G01X536093D02*
X531394D01*
G01X543179D02*
X538481D01*
G01X550266D02*
X545567D01*
G01X557353D02*
X552654D01*
G01X564439D02*
X559741D01*
G01X571526D02*
X566827D01*
G01X567169Y52657D02*
X571184D01*
G01X560082D02*
X564098D01*
G01X552995D02*
X557011D01*
G01X548485D02*
X549925D01*
G01X545909D02*
X547930D01*
G01X538822D02*
X542838D01*
G01X531736D02*
X535751D01*
G01X524649D02*
X528665D01*
G01X517562D02*
X521578D01*
G01X517716Y198819D02*
Y328740D01*
G01X543307Y371299D02*
G03I-11811J0D01*
G01X537401D02*
G03I-5905J0D01*
G01X538386Y531496D02*
G03I-6890J0D01*
G01X550197D02*
G03I-18701J0D01*
G01X515565Y1297911D02*
Y1278974D01*
G01X577521Y-39738D02*
X577625Y-39665D01*
G01X577396Y-39764D02*
X577521Y-39738D01*
G01X585235Y-39739D02*
X585358Y-39764D01*
G01X585130Y-39666D02*
X585235Y-39739D01*
G01X579259Y-38609D02*
X579254Y-38615D01*
G01X579275Y-38589D02*
X579259Y-38609D01*
G01X579301Y-38556D02*
X579275Y-38589D01*
G01X579335Y-38512D02*
X579301Y-38556D01*
G01X579375Y-38457D02*
X579335Y-38512D01*
G01X579420Y-38389D02*
X579375Y-38457D01*
G01X579467Y-38312D02*
X579420Y-38389D01*
G01X579510Y-38233D02*
X579467Y-38312D01*
G01X579546Y-38160D02*
X579510Y-38233D01*
G01X579574Y-38092D02*
X579546Y-38160D01*
G01X579595Y-38029D02*
X579574Y-38092D01*
G01X579607Y-37971D02*
X579595Y-38029D01*
G01X579611Y-37920D02*
X579607Y-37971D01*
G01X579605Y-37878D02*
X579611Y-37920D01*
G01X579592Y-37844D02*
X579605Y-37878D01*
G01X579576Y-37819D02*
X579592Y-37844D01*
G01X579562Y-37804D02*
X579576Y-37819D01*
G01X579556Y-37799D02*
X579562Y-37804D01*
G01X583155Y-37808D02*
X583160Y-37803D01*
G01X583141Y-37823D02*
X583155Y-37808D01*
G01X583126Y-37848D02*
X583141Y-37823D01*
G01X583113Y-37881D02*
X583126Y-37848D01*
G01X583107Y-37923D02*
X583113Y-37881D01*
G01X583111Y-37973D02*
X583107Y-37923D01*
G01X583123Y-38030D02*
X583111Y-37973D01*
G01X583143Y-38092D02*
X583123Y-38030D01*
G01X583171Y-38160D02*
X583143Y-38092D01*
G01X583207Y-38235D02*
X583171Y-38160D01*
G01X583251Y-38315D02*
X583207Y-38235D01*
G01X583297Y-38390D02*
X583251Y-38315D01*
G01X583341Y-38455D02*
X583297Y-38390D01*
G01X583380Y-38510D02*
X583341Y-38455D01*
G01X583413Y-38553D02*
X583380Y-38510D01*
G01X583438Y-38586D02*
X583413Y-38553D01*
G01X583454Y-38605D02*
X583438Y-38586D01*
G01X583459Y-38611D02*
X583454Y-38605D01*
G01X578865Y-39375D02*
X578682Y-39494D01*
G01X578989Y-39251D02*
X578865Y-39375D01*
G01X579068Y-39119D02*
X578989Y-39251D01*
G01X577820Y-39706D02*
X577352Y-39764D01*
G01X578229Y-39559D02*
X577820Y-39706D01*
G01X578602Y-39339D02*
X578229Y-39559D01*
G01X578629Y-39519D02*
X578602Y-39531D01*
G01X578656Y-39507D02*
X578629Y-39519D01*
G01X578682Y-39494D02*
X578656Y-39507D01*
G01X577711Y-39549D02*
X577692Y-39558D01*
G01X577766Y-39525D02*
X577711Y-39549D01*
G01X577846Y-39490D02*
X577766Y-39525D01*
G01X577942Y-39449D02*
X577846Y-39490D01*
G01X584133Y-35626D02*
G03X584231Y-36172I1575J1D01*
G01X578524D02*
G03X578621Y-35626I-1477J544D01*
G01X583739D02*
G03X583861Y-36308I1969J0D01*
G01X578893D02*
G03X579015Y-35626I-1845J682D01*
G01X583543D02*
G03X583677Y-36377I2165J-1D01*
G01X579078D02*
G03X579212Y-35626I-2031J750D01*
G01X578599Y-39325D02*
G03X579254Y-38615I-1372J1923D01*
G01X579556Y-37797D02*
G03X579589Y-37402I-2329J393D01*
G01X583126D02*
G03X583160Y-37803I2362J-2D01*
G01X583459Y-38611D02*
G03X585488Y-39764I2029J1209D01*
G01X585063Y-39558D02*
G03X585358Y-39764I295J108D01*
G01X577396D02*
G03X577692Y-39558I0J316D01*
G01X585063D02*
X585442Y-39449D01*
G01X583677Y-36377D02*
X584231Y-36172D01*
G01X577692Y-39558D02*
X577625Y-39666D01*
G01X579068Y-39119D02*
X579589Y-37708D01*
G01X579196Y-37637D02*
X578602Y-39245D01*
G01X579078Y-36377D02*
X577942Y-39449D01*
G01X578893Y-36308D02*
X577692Y-39558D01*
G01X577313Y-39449D02*
X578524Y-36172D01*
G01X590938Y-39764D02*
Y-1181D01*
G01X590449Y-12828D02*
Y62697D01*
G01X585525Y-31890D02*
Y-39764D01*
G01X585442Y-39449D02*
Y-39764D01*
G01X584812Y-39449D02*
Y-39764D01*
G01X584133Y-35626D02*
Y-7499D01*
G01X583739D02*
Y-35626D01*
G01X583543Y-7499D02*
Y-35626D01*
G01X583520Y-7577D02*
Y-37640D01*
G01X583126Y-7577D02*
Y-37402D01*
G01X582732Y-39764D02*
Y-7577D01*
G01X579983D02*
Y-39764D01*
G01X579589Y-37708D02*
Y-7577D01*
G01X579212Y-35626D02*
Y-7499D01*
G01X579196Y-37637D02*
Y-7577D01*
G01X579015Y-7499D02*
Y-35626D01*
G01X578621Y-7499D02*
Y-35626D01*
G01X578602Y-39531D02*
Y-31890D01*
G01X577942Y-39449D02*
Y-39764D01*
G01X577313Y-39449D02*
Y-39764D01*
G01X576239Y-31890D02*
Y-39764D01*
G01X575879Y-31890D02*
Y-39764D01*
G01X584231Y-36172D02*
X585442Y-39449D01*
G01X585063Y-39558D02*
X583862Y-36308D01*
G01X584812Y-39449D02*
X583677Y-36377D01*
G01X584152Y-39350D02*
X583520Y-37640D01*
G01X583160Y-37803D02*
X583459Y-38611D01*
G01X585130Y-39666D02*
X585063Y-39558D01*
G01X584812Y-39449D02*
X585063Y-39558D01*
G01X578524Y-36172D02*
X579078Y-36377D01*
G01X578602Y-39471D02*
X578682Y-39494D01*
G01X577313Y-39449D02*
X577692Y-39558D01*
G01X579589Y-37708D02*
X579196Y-37637D01*
G01X590938Y-12828D02*
X590449D01*
G01X576239Y-31890D02*
X578602D01*
G01X590938D02*
X585525D01*
G01X583543Y-35626D02*
X584133D01*
G01X579212D02*
X578621D01*
G01X579589Y-37402D02*
X583126D01*
G01X585525Y-39276D02*
X590938D01*
G01X578602D02*
X576239D01*
G01X577942Y-39449D02*
X590938D01*
G01X583146Y-37706D02*
X583520Y-37640D01*
G01X577521Y-39739D02*
X577396Y-39764D01*
G01X780315Y-7874D02*
X628416D01*
G01Y0D02*
G03Y-7874I0J-3937D01*
G01X597707D02*
G03Y0I0J3937D01*
G01X579963Y-7354D02*
X580016Y-7480D01*
G01X579922Y-7224D02*
X579963Y-7354D01*
G01X579895Y-7124D02*
X579922Y-7224D01*
G01X579885Y-7087D02*
X579895Y-7124D01*
G01X579841Y-6892D02*
X579802Y-6693D01*
G01X579873Y-7035D02*
X579841Y-6892D01*
G01X579885Y-7087D02*
X579873Y-7035D01*
G01X582875Y-6892D02*
X582914Y-6693D01*
G01X582843Y-7034D02*
X582875Y-6892D01*
G01X582830Y-7087D02*
X582843Y-7034D01*
G01X582822Y-7120D02*
X582830Y-7087D01*
G01X582796Y-7214D02*
X582822Y-7120D01*
G01X582755Y-7346D02*
X582796Y-7214D01*
G01X582700Y-7480D02*
X582755Y-7346D01*
G01X580236Y48819D02*
G03I-709J0D01*
G01X587323Y48425D02*
G03I-709J0D01*
G01X588862Y46771D02*
G03I-1969J0D01*
G01X581775D02*
G03I-1969J0D01*
G01X587323Y44094D02*
G03I-709J0D01*
G01X582169Y44055D02*
G03X581184Y45039I-984J0D01*
G01X585515D02*
G03X584531Y44055I0J-984D01*
G01X589255D02*
G03X588271Y45039I-984J0D01*
G01X586893Y41053D02*
G03X585318Y39478I0J-1575D01*
G01X588871Y41033D02*
G03X590446Y42608I0J1575D01*
G01X587323Y34252D02*
G03I-709J0D01*
G01Y38582D02*
G03I-709J0D01*
G01X585358Y36087D02*
G03Y34307I1299J-890D01*
G01X588428D02*
G03Y36087I-1299J890D01*
G01X580236Y43307D02*
G03I-709J0D01*
G01X575082Y44055D02*
G03X574098Y45039I-984J0D01*
G01X578428D02*
G03X577444Y44055I0J-984D01*
G01X581381Y39478D02*
G03X578232I-1575J0D01*
G01X580236Y34645D02*
G03I-709J0D01*
G01Y38976D02*
G03I-709J0D01*
G01X581342Y34307D02*
G03Y36087I-1299J890D01*
G01X578271D02*
G03Y34307I1299J-890D01*
G01X574255D02*
G03Y36087I-1299J890D01*
G01X587323Y29921D02*
G03I-709J0D01*
G01X585358Y29000D02*
G03Y27220I1299J-890D01*
G01X588428D02*
G03Y29000I-1299J890D01*
G01X581342Y27220D02*
G03Y29000I-1299J890D01*
G01X587323Y20078D02*
G03I-709J0D01*
G01Y24409D02*
G03I-709J0D01*
G01X580236Y29134D02*
G03I-709J0D01*
G01X578271Y29000D02*
G03Y27220I1299J-890D01*
G01X574255D02*
G03Y29000I-1299J890D01*
G01X580236Y20472D02*
G03I-709J0D01*
G01Y24803D02*
G03I-709J0D01*
G01X587323Y10236D02*
G03I-709J0D01*
G01X580236Y14960D02*
G03I-709J0D01*
G01X587323Y15748D02*
G03I-709J0D01*
G01Y5905D02*
G03I-709J0D01*
G01X582729Y-7577D02*
G03X582698Y-7482I-157J1D01*
G01X580018D02*
G03X579986Y-7577I125J-95D01*
G01X579427Y-7302D02*
G03X579230Y-7499I0J-197D01*
G01X583525D02*
G03X583328Y-7302I-197J0D01*
G01X583721Y-7499D02*
G03X583328Y-7105I-394J0D01*
G01X579427D02*
G03X579033Y-7499I0J-394D01*
G01X579887Y-7089D02*
G03X579593Y-7577I258J-488D01*
G01X583123D02*
G03X582829Y-7089I-552J0D01*
G01X584115Y-7499D02*
G03X583328Y-6711I-788J0D01*
G01X579427D02*
G03X578639Y-7499I0J-788D01*
G01X579803Y-6696D02*
G03X579199Y-7577I341J-881D01*
G01X583517D02*
G03X582913Y-6696I-945J0D01*
G01X585328Y25730D02*
X583940Y23327D01*
G01X578241Y25730D02*
X576854Y23327D01*
G01X586145Y39921D02*
X585358Y38557D01*
G01X579058Y39921D02*
X578271Y38557D01*
G01X590436Y42608D02*
Y60138D01*
G01X590443Y42608D02*
X590449Y22204D01*
G01X589255D02*
Y44055D01*
G01X588428Y27220D02*
Y22204D01*
G01Y34307D02*
Y29000D01*
G01Y38557D02*
Y36087D01*
G01X585358Y27220D02*
Y22204D01*
G01Y34307D02*
Y29000D01*
G01Y38557D02*
Y36087D01*
G01X585328Y27265D02*
Y25730D01*
G01Y34351D02*
Y28955D01*
G01Y39478D02*
Y36042D01*
G01X584531Y44055D02*
Y22204D01*
G01X583328Y-7284D02*
Y-6693D01*
G01X582169Y44055D02*
Y22204D01*
G01X581371Y36042D02*
Y39478D01*
G01Y28955D02*
Y34351D01*
G01Y25730D02*
Y27265D01*
G01X581342Y27220D02*
Y22204D01*
G01Y34307D02*
Y29000D01*
G01Y38557D02*
Y36087D01*
G01X579427Y-7284D02*
Y-6693D01*
G01X578271Y36087D02*
Y38557D01*
G01Y29000D02*
Y34307D01*
G01Y22204D02*
Y27220D01*
G01X578241Y27265D02*
Y25730D01*
G01Y34351D02*
Y28955D01*
G01Y39478D02*
Y36042D01*
G01X577444Y44055D02*
Y22204D01*
G01X575082Y44055D02*
Y22204D01*
G01X574285Y36042D02*
Y39478D01*
G01Y28955D02*
Y34351D01*
G01Y25730D02*
Y27265D01*
G01X574255Y27220D02*
Y22204D01*
G01Y34307D02*
Y29000D01*
G01Y38557D02*
Y36087D01*
G01X587641Y39921D02*
X588428Y38557D01*
G01X580554Y39921D02*
X581342Y38557D01*
G01X573468Y39921D02*
X574255Y38557D01*
G01X582759Y23327D02*
X581371Y25730D01*
G01X575673Y23327D02*
X574285Y25730D01*
G01X581184Y45039D02*
X578428D01*
G01X588271D02*
X585515D01*
G01X577444Y42516D02*
X582169D01*
G01X589255D02*
X584531D01*
G01X588871Y41043D02*
X586893D01*
G01X580554Y39921D02*
X579058D01*
G01X587641D02*
X586145D01*
G01X581578Y25372D02*
X585121D01*
G01X574491D02*
X578035D01*
G01X576854Y23327D02*
X575673D01*
G01X583940D02*
X582759D01*
G01X588428Y22204D02*
X590449D01*
G01X574255D02*
X578271D01*
G01X585358D02*
X581342D01*
G01X583328Y-6693D02*
X579427D01*
G01X583328Y-7087D02*
X579427D01*
G01Y-7284D02*
X583328D01*
G01X582700Y-7480D02*
X580016D01*
G01X583543Y-7499D02*
X584133D01*
G01X578621D02*
X579212D01*
G01X582732Y-7577D02*
X583520D01*
G01X579983D02*
X579196D01*
G01X578396Y53330D02*
X578271Y53648D01*
G01X578612Y53051D02*
X578396Y53330D01*
G01X585483D02*
X585358Y53648D01*
G01X585699Y53051D02*
X585483Y53330D01*
G01X578414Y53425D02*
X578612Y53051D01*
G01X578287Y53849D02*
X578414Y53425D01*
G01X578241Y54309D02*
X578287Y53849D01*
G01X585500Y53425D02*
X585699Y53051D01*
G01X585374Y53849D02*
X585500Y53425D01*
G01X585328Y54309D02*
X585374Y53849D01*
G01X578249Y53766D02*
X578271Y53643D01*
G01X578241Y53889D02*
X578249Y53766D01*
G01X585336D02*
X585358Y53643D01*
G01X585328Y53889D02*
X585336Y53766D01*
G01X574277Y53767D02*
X574255Y53643D01*
G01X574285Y53889D02*
X574277Y53767D01*
G01X581364D02*
X581342Y53643D01*
G01X581371Y53889D02*
X581364Y53767D01*
G01X588451D02*
X588428Y53643D01*
G01X588458Y53889D02*
X588451Y53767D01*
G01X574128Y53327D02*
X573914Y53051D01*
G01X574255Y53648D02*
X574128Y53327D01*
G01X581215D02*
X581000Y53051D01*
G01X581342Y53648D02*
X581215Y53327D01*
G01X588301D02*
X588087Y53051D01*
G01X588428Y53648D02*
X588301Y53327D01*
G01X574239Y53849D02*
X574285Y54309D01*
G01X574112Y53425D02*
X574239Y53849D01*
G01X573914Y53051D02*
X574112Y53425D01*
G01X581326Y53849D02*
X581371Y54309D01*
G01X581199Y53425D02*
X581326Y53849D01*
G01X581000Y53051D02*
X581199Y53425D01*
G01X588412Y53849D02*
X588458Y54309D01*
G01X588286Y53425D02*
X588412Y53849D01*
G01X588087Y53051D02*
X588286Y53425D01*
G01X602362Y116141D02*
G03I-5906J0D01*
G01X608267D02*
G03I-11811J0D01*
G01X580236Y53149D02*
G03I-709J0D01*
G01X585691Y53045D02*
G03X588095I1202J1018D01*
G01X578605D02*
G03X581008I1201J1018D01*
G01X586539Y61712D02*
X585358Y60531D01*
G01X579452Y61712D02*
X578271Y60531D01*
G01X588458Y60138D02*
Y53889D01*
G01X588428Y60531D02*
Y52657D01*
G01X585358D02*
Y60531D01*
G01X585328Y60138D02*
Y53889D01*
G01X581371Y60138D02*
Y53889D01*
G01X581342Y60531D02*
Y52657D01*
G01X578271D02*
Y60531D01*
G01X578241Y60138D02*
Y53889D01*
G01X574285Y60138D02*
Y53889D01*
G01X574255Y60531D02*
Y52657D01*
G01X587247Y61712D02*
X588428Y60531D01*
G01X580161Y61712D02*
X581342Y60531D01*
G01X580161Y61712D02*
X579452D01*
G01X587247D02*
X586539D01*
G01X581342Y60531D02*
X578271D01*
G01X588428D02*
X585358D01*
G01X578612Y53051D02*
X573914D01*
G01X585699D02*
X581000D01*
G01X590436D02*
X588087D01*
G01X588428Y52657D02*
X590449D01*
G01X581342D02*
X585358D01*
G01X574255D02*
X578271D01*
G01X639763Y206693D02*
Y108267D01*
G01X738189D02*
X639763D01*
G01X669094Y179645D02*
Y135315D01*
G01X708858D02*
X669094D01*
G01X640504Y205978D02*
Y204319D01*
G01D02*
X642164Y205978D01*
G01X738189Y206693D02*
X639763D01*
G01X642164Y205978D02*
X640504D01*
G01X708858Y179645D02*
X669094D01*
G01X735235Y-879845D02*
Y-898782D01*
G01X749279Y-39666D02*
X749345Y-39558D01*
G01X749174Y-39738D02*
X749279Y-39666D01*
G01X749050Y-39764D02*
X749174Y-39738D01*
G01X735105Y-39666D02*
X735172Y-39558D01*
G01X735001Y-39738D02*
X735105Y-39666D01*
G01X734877Y-39764D02*
X735001Y-39738D01*
G01X720932Y-39666D02*
X720999Y-39558D01*
G01X720828Y-39738D02*
X720932Y-39666D01*
G01X720704Y-39764D02*
X720828Y-39738D01*
G01X706759Y-39666D02*
X706826Y-39558D01*
G01X706655Y-39738D02*
X706759Y-39666D01*
G01X706530Y-39764D02*
X706655Y-39738D01*
G01X714264Y-39666D02*
X714196Y-39558D01*
G01X714368Y-39738D02*
X714264Y-39666D01*
G01X714492Y-39764D02*
X714368Y-39738D01*
G01X728437Y-39666D02*
X728370Y-39558D01*
G01X728541Y-39738D02*
X728437Y-39666D01*
G01X728665Y-39764D02*
X728541Y-39738D01*
G01X742610Y-39666D02*
X742543Y-39558D01*
G01X742714Y-39738D02*
X742610Y-39666D01*
G01X742838Y-39764D02*
X742714Y-39738D01*
G01X756783Y-39666D02*
X756716Y-39558D01*
G01X756887Y-39738D02*
X756783Y-39666D01*
G01X757012Y-39764D02*
X756887Y-39738D01*
G01X712290Y-37807D02*
X712294Y-37803D01*
G01X712279Y-37819D02*
X712290Y-37807D01*
G01X712265Y-37837D02*
X712279Y-37819D01*
G01X712253Y-37862D02*
X712265Y-37837D01*
G01X712244Y-37892D02*
X712253Y-37862D01*
G01X712241Y-37927D02*
X712244Y-37892D01*
G01Y-37969D02*
X712241Y-37927D01*
G01X712253Y-38018D02*
X712244Y-37969D01*
G01X712270Y-38072D02*
X712253Y-38018D01*
G01X712292Y-38130D02*
X712270Y-38072D01*
G01X712321Y-38195D02*
X712292Y-38130D01*
G01X712357Y-38265D02*
X712321Y-38195D01*
G01X712398Y-38337D02*
X712357Y-38265D01*
G01X712439Y-38402D02*
X712398Y-38337D01*
G01X712476Y-38458D02*
X712439Y-38402D01*
G01X712510Y-38505D02*
X712476Y-38458D01*
G01X712539Y-38544D02*
X712510Y-38505D01*
G01X712563Y-38574D02*
X712539Y-38544D01*
G01X712580Y-38595D02*
X712563Y-38574D01*
G01X712590Y-38608D02*
X712580Y-38595D01*
G01X712593Y-38611D02*
X712590Y-38608D01*
G01X726463Y-37807D02*
X726467Y-37803D01*
G01X726452Y-37819D02*
X726463Y-37807D01*
G01X726439Y-37837D02*
X726452Y-37819D01*
G01X726426Y-37862D02*
X726439Y-37837D01*
G01X726418Y-37892D02*
X726426Y-37862D01*
G01X726414Y-37927D02*
X726418Y-37892D01*
G01X726417Y-37969D02*
X726414Y-37927D01*
G01X726427Y-38018D02*
X726417Y-37969D01*
G01X726443Y-38072D02*
X726427Y-38018D01*
G01X726465Y-38130D02*
X726443Y-38072D01*
G01X726494Y-38195D02*
X726465Y-38130D01*
G01X726530Y-38265D02*
X726494Y-38195D01*
G01X726571Y-38337D02*
X726530Y-38265D01*
G01X726612Y-38402D02*
X726571Y-38337D01*
G01X726650Y-38458D02*
X726612Y-38402D01*
G01X726683Y-38505D02*
X726650Y-38458D01*
G01X726712Y-38544D02*
X726683Y-38505D01*
G01X726736Y-38574D02*
X726712Y-38544D01*
G01X726753Y-38595D02*
X726736Y-38574D01*
G01X726763Y-38608D02*
X726753Y-38595D01*
G01X726766Y-38611D02*
X726763Y-38608D01*
G01X740636Y-37807D02*
X740641Y-37803D01*
G01X740625Y-37819D02*
X740636Y-37807D01*
G01X740612Y-37837D02*
X740625Y-37819D01*
G01X740599Y-37862D02*
X740612Y-37837D01*
G01X740591Y-37892D02*
X740599Y-37862D01*
G01X740588Y-37927D02*
X740591Y-37892D01*
G01X740590Y-37969D02*
X740588Y-37927D01*
G01X740600Y-38018D02*
X740590Y-37969D01*
G01X740616Y-38072D02*
X740600Y-38018D01*
G01X740638Y-38130D02*
X740616Y-38072D01*
G01X740667Y-38195D02*
X740638Y-38130D01*
G01X740703Y-38265D02*
X740667Y-38195D01*
G01X740744Y-38337D02*
X740703Y-38265D01*
G01X740785Y-38402D02*
X740744Y-38337D01*
G01X740823Y-38458D02*
X740785Y-38402D01*
G01X740857Y-38505D02*
X740823Y-38458D01*
G01X740886Y-38544D02*
X740857Y-38505D01*
G01X740909Y-38574D02*
X740886Y-38544D01*
G01X740926Y-38595D02*
X740909Y-38574D01*
G01X740936Y-38608D02*
X740926Y-38595D01*
G01X740939Y-38611D02*
X740936Y-38608D01*
G01X754809Y-37807D02*
X754814Y-37803D01*
G01X754799Y-37819D02*
X754809Y-37807D01*
G01X754785Y-37837D02*
X754799Y-37819D01*
G01X754773Y-37862D02*
X754785Y-37837D01*
G01X754764Y-37892D02*
X754773Y-37862D01*
G01X754761Y-37927D02*
X754764Y-37892D01*
G01Y-37969D02*
X754761Y-37927D01*
G01X754773Y-38018D02*
X754764Y-37969D01*
G01X754789Y-38072D02*
X754773Y-38018D01*
G01X754812Y-38130D02*
X754789Y-38072D01*
G01X754840Y-38195D02*
X754812Y-38130D01*
G01X754876Y-38265D02*
X754840Y-38195D01*
G01X754918Y-38337D02*
X754876Y-38265D01*
G01X754958Y-38402D02*
X754918Y-38337D01*
G01X754996Y-38458D02*
X754958Y-38402D01*
G01X755030Y-38505D02*
X754996Y-38458D01*
G01X755059Y-38544D02*
X755030Y-38505D01*
G01X755083Y-38574D02*
X755059Y-38544D01*
G01X755100Y-38595D02*
X755083Y-38574D01*
G01X755110Y-38608D02*
X755100Y-38595D01*
G01X755113Y-38611D02*
X755110Y-38608D01*
G01X714398Y-39750D02*
X714492Y-39764D01*
G01X714312Y-39707D02*
X714398Y-39750D01*
G01X714243Y-39641D02*
X714312Y-39707D01*
G01X714196Y-39558D02*
X714243Y-39641D01*
G01X728571Y-39750D02*
X728665Y-39764D01*
G01X728485Y-39707D02*
X728571Y-39750D01*
G01X728416Y-39641D02*
X728485Y-39707D01*
G01X728370Y-39558D02*
X728416Y-39641D01*
G01X742744Y-39750D02*
X742838Y-39764D01*
G01X742658Y-39707D02*
X742744Y-39750D01*
G01X742589Y-39641D02*
X742658Y-39707D01*
G01X742543Y-39558D02*
X742589Y-39641D01*
G01X756917Y-39750D02*
X757012Y-39764D01*
G01X756831Y-39707D02*
X756917Y-39750D01*
G01X756762Y-39641D02*
X756831Y-39707D01*
G01X756716Y-39558D02*
X756762Y-39641D01*
G01X706650Y-39736D02*
X706526Y-39764D01*
G01X706748Y-39659D02*
X706650Y-39736D01*
G01X706808Y-39553D02*
X706748Y-39659D01*
G01X720823Y-39736D02*
X720699Y-39764D01*
G01X720922Y-39659D02*
X720823Y-39736D01*
G01X720981Y-39553D02*
X720922Y-39659D01*
G01X708000Y-39374D02*
X707816Y-39494D01*
G01X708124Y-39250D02*
X708000Y-39374D01*
G01X708202Y-39119D02*
X708124Y-39250D01*
G01X706954Y-39706D02*
X706486Y-39764D01*
G01X707363Y-39559D02*
X706954Y-39706D01*
G01X707736Y-39339D02*
X707363Y-39559D01*
G01X721127Y-39706D02*
X720660Y-39764D01*
G01X721537Y-39559D02*
X721127Y-39706D01*
G01X721909Y-39339D02*
X721537Y-39559D01*
G01X707763Y-39519D02*
X707736Y-39531D01*
G01X707790Y-39507D02*
X707763Y-39519D01*
G01X707816Y-39494D02*
X707790Y-39507D01*
G01X721936Y-39519D02*
X721909Y-39531D01*
G01X721963Y-39507D02*
X721936Y-39519D01*
G01X721989Y-39494D02*
X721963Y-39507D01*
G01X736110Y-39519D02*
X736082Y-39531D01*
G01X736136Y-39507D02*
X736110Y-39519D01*
G01X736162Y-39494D02*
X736136Y-39507D01*
G01X721151Y-39491D02*
X721249Y-39449D01*
G01X721070Y-39526D02*
X721151Y-39491D01*
G01X721017Y-39549D02*
X721070Y-39526D01*
G01X720999Y-39558D02*
X721017Y-39549D01*
G01X735324Y-39491D02*
X735422Y-39449D01*
G01X735243Y-39526D02*
X735324Y-39491D01*
G01X735191Y-39549D02*
X735243Y-39526D01*
G01X735172Y-39558D02*
X735191Y-39549D01*
G01X749497Y-39491D02*
X749596Y-39449D01*
G01X749416Y-39526D02*
X749497Y-39491D01*
G01X749364Y-39549D02*
X749416Y-39526D01*
G01X749345Y-39558D02*
X749364Y-39549D01*
G01X706844D02*
X706826Y-39558D01*
G01X706897Y-39526D02*
X706844Y-39549D01*
G01X706978Y-39491D02*
X706897Y-39526D01*
G01X707076Y-39449D02*
X706978Y-39491D01*
G01X734996Y-39736D02*
X734872Y-39764D01*
G01X735095Y-39659D02*
X734996Y-39736D01*
G01X735154Y-39553D02*
X735095Y-39659D01*
G01X749170Y-39736D02*
X749046Y-39764D01*
G01X749268Y-39659D02*
X749170Y-39736D01*
G01X749328Y-39553D02*
X749268Y-39659D01*
G01X722173Y-39374D02*
X721989Y-39494D01*
G01X722297Y-39250D02*
X722173Y-39374D01*
G01X722375Y-39119D02*
X722297Y-39250D01*
G01X736347Y-39374D02*
X736162Y-39494D01*
G01X736470Y-39250D02*
X736347Y-39374D01*
G01X736548Y-39119D02*
X736470Y-39250D01*
G01X750520Y-39374D02*
X750335Y-39494D01*
G01X750643Y-39250D02*
X750520Y-39374D01*
G01X750721Y-39119D02*
X750643Y-39250D01*
G01X708694Y-37803D02*
X708690Y-37799D01*
G01X708705Y-37815D02*
X708694Y-37803D01*
G01X708719Y-37833D02*
X708705Y-37815D01*
G01X708732Y-37858D02*
X708719Y-37833D01*
G01X708741Y-37888D02*
X708732Y-37858D01*
G01X708744Y-37923D02*
X708741Y-37888D01*
G01X708742Y-37965D02*
X708744Y-37923D01*
G01X708732Y-38015D02*
X708742Y-37965D01*
G01X708716Y-38069D02*
X708732Y-38015D01*
G01X708694Y-38128D02*
X708716Y-38069D01*
G01X708664Y-38193D02*
X708694Y-38128D01*
G01X708628Y-38264D02*
X708664Y-38193D01*
G01X708586Y-38337D02*
X708628Y-38264D01*
G01X708545Y-38403D02*
X708586Y-38337D01*
G01X708507Y-38459D02*
X708545Y-38403D01*
G01X708472Y-38507D02*
X708507Y-38459D01*
G01X708443Y-38547D02*
X708472Y-38507D01*
G01X708419Y-38577D02*
X708443Y-38547D01*
G01X708401Y-38599D02*
X708419Y-38577D01*
G01X708391Y-38611D02*
X708401Y-38599D01*
G01X708388Y-38615D02*
X708391Y-38611D01*
G01X722868Y-37803D02*
X722863Y-37799D01*
G01X722879Y-37815D02*
X722868Y-37803D01*
G01X722892Y-37833D02*
X722879Y-37815D01*
G01X722905Y-37858D02*
X722892Y-37833D01*
G01X722914Y-37888D02*
X722905Y-37858D01*
G01X722918Y-37923D02*
X722914Y-37888D01*
G01X722915Y-37965D02*
X722918Y-37923D01*
G01X722905Y-38015D02*
X722915Y-37965D01*
G01X722889Y-38069D02*
X722905Y-38015D01*
G01X722867Y-38128D02*
X722889Y-38069D01*
G01X722838Y-38193D02*
X722867Y-38128D01*
G01X722801Y-38264D02*
X722838Y-38193D01*
G01X722760Y-38337D02*
X722801Y-38264D01*
G01X722718Y-38403D02*
X722760Y-38337D01*
G01X722680Y-38459D02*
X722718Y-38403D01*
G01X722646Y-38507D02*
X722680Y-38459D01*
G01X722616Y-38547D02*
X722646Y-38507D01*
G01X722592Y-38577D02*
X722616Y-38547D01*
G01X722575Y-38599D02*
X722592Y-38577D01*
G01X722565Y-38611D02*
X722575Y-38599D01*
G01X722561Y-38615D02*
X722565Y-38611D01*
G01X737041Y-37803D02*
X737036Y-37799D01*
G01X737052Y-37815D02*
X737041Y-37803D01*
G01X737066Y-37833D02*
X737052Y-37815D01*
G01X737079Y-37858D02*
X737066Y-37833D01*
G01X737087Y-37888D02*
X737079Y-37858D01*
G01X737091Y-37923D02*
X737087Y-37888D01*
G01X737088Y-37965D02*
X737091Y-37923D01*
G01X737079Y-38015D02*
X737088Y-37965D01*
G01X737063Y-38069D02*
X737079Y-38015D01*
G01X737040Y-38128D02*
X737063Y-38069D01*
G01X737011Y-38193D02*
X737040Y-38128D01*
G01X736975Y-38264D02*
X737011Y-38193D01*
G01X736933Y-38337D02*
X736975Y-38264D01*
G01X736891Y-38403D02*
X736933Y-38337D01*
G01X736853Y-38459D02*
X736891Y-38403D01*
G01X736819Y-38507D02*
X736853Y-38459D01*
G01X736789Y-38547D02*
X736819Y-38507D01*
G01X736765Y-38577D02*
X736789Y-38547D01*
G01X736748Y-38599D02*
X736765Y-38577D01*
G01X736738Y-38611D02*
X736748Y-38599D01*
G01X736735Y-38615D02*
X736738Y-38611D01*
G01X751214Y-37803D02*
X751209Y-37799D01*
G01X751225Y-37815D02*
X751214Y-37803D01*
G01X751239Y-37833D02*
X751225Y-37815D01*
G01X751252Y-37858D02*
X751239Y-37833D01*
G01X751261Y-37888D02*
X751252Y-37858D01*
G01X751264Y-37923D02*
X751261Y-37888D01*
G01X751262Y-37965D02*
X751264Y-37923D01*
G01X751252Y-38015D02*
X751262Y-37965D01*
G01X751236Y-38069D02*
X751252Y-38015D01*
G01X751213Y-38128D02*
X751236Y-38069D01*
G01X751184Y-38193D02*
X751213Y-38128D01*
G01X751148Y-38264D02*
X751184Y-38193D01*
G01X751106Y-38337D02*
X751148Y-38264D01*
G01X751065Y-38403D02*
X751106Y-38337D01*
G01X751026Y-38459D02*
X751065Y-38403D01*
G01X750992Y-38507D02*
X751026Y-38459D01*
G01X750963Y-38547D02*
X750992Y-38507D01*
G01X750939Y-38577D02*
X750963Y-38547D01*
G01X750921Y-38599D02*
X750939Y-38577D01*
G01X750911Y-38611D02*
X750921Y-38599D01*
G01X750908Y-38615D02*
X750911Y-38611D01*
G01X735300Y-39706D02*
X734833Y-39764D01*
G01X735710Y-39559D02*
X735300Y-39706D01*
G01X736082Y-39339D02*
X735710Y-39559D01*
G01X749474Y-39706D02*
X749006Y-39764D01*
G01X749883Y-39559D02*
X749474Y-39706D01*
G01X750255Y-39339D02*
X749883Y-39559D01*
G01X750283Y-39519D02*
X750255Y-39531D01*
G01X750309Y-39507D02*
X750283Y-39519D01*
G01X750335Y-39494D02*
X750309Y-39507D01*
G01X755787Y-35626D02*
G03X755884Y-36172I1575J-2D01*
G01X750177D02*
G03X750275Y-35626I-1477J547D01*
G01X755393D02*
G03X755515Y-36308I1969J0D01*
G01X750547D02*
G03X750669Y-35626I-1847J682D01*
G01X755196D02*
G03X755330Y-36377I2166J-1D01*
G01X750731D02*
G03X750865Y-35626I-2031J750D01*
G01X750253Y-39325D02*
G03X750908Y-38615I-1372J1923D01*
G01X751209Y-37799D02*
G03X751243Y-37402I-2328J399D01*
G01X754780D02*
G03X754814Y-37803I2362J-2D01*
G01X755113Y-38611D02*
G03X757142Y-39764I2029J1209D01*
G01X756716Y-39558D02*
G03X757012Y-39764I296J110D01*
G01X749050D02*
G03X749345Y-39558I0J314D01*
G01X741613Y-35626D02*
G03X741711Y-36172I1575J1D01*
G01X736004D02*
G03X736102Y-35626I-1477J547D01*
G01X741220D02*
G03X741342Y-36308I1967J0D01*
G01X736373D02*
G03X736495Y-35626I-1845J682D01*
G01X741023D02*
G03X741157Y-36377I2165J-1D01*
G01X736558D02*
G03X736692Y-35626I-2031J750D01*
G01X740606Y-37402D02*
G03X740641Y-37803I2363J4D01*
G01X740940Y-38611D02*
G03X742969Y-39764I2029J1209D01*
G01X736079Y-39325D02*
G03X736735Y-38615I-1370J1924D01*
G01X737036Y-37799D02*
G03X737070Y-37402I-2328J399D01*
G01X742543Y-39558D02*
G03X742838Y-39764I295J108D01*
G01X734877D02*
G03X735172Y-39558I0J314D01*
G01X727440Y-35626D02*
G03X727538Y-36172I1575J1D01*
G01X721831D02*
G03X721928Y-35626I-1477J544D01*
G01X727047D02*
G03X727169Y-36308I1967J0D01*
G01X722200D02*
G03X722322Y-35626I-1845J682D01*
G01X726850D02*
G03X726984Y-36377I2165J-1D01*
G01X722385D02*
G03X722519Y-35626I-2031J750D01*
G01X726433Y-37402D02*
G03X726467Y-37803I2362J-2D01*
G01X726766Y-38611D02*
G03X728795Y-39764I2029J1209D01*
G01X721906Y-39325D02*
G03X722561Y-38615I-1372J1923D01*
G01X722863Y-37799D02*
G03X722897Y-37402I-2329J399D01*
G01X728370Y-39558D02*
G03X728665Y-39764I295J108D01*
G01X720704D02*
G03X720999Y-39558I0J314D01*
G01X713267Y-35626D02*
G03X713365Y-36172I1575J1D01*
G01X707658D02*
G03X707755Y-35626I-1478J544D01*
G01X712873D02*
G03X712995Y-36308I1969J0D01*
G01X708027D02*
G03X708149Y-35626I-1847J682D01*
G01X708212Y-36377D02*
G03X708346Y-35626I-2032J750D01*
G01X712676D02*
G03X712811Y-36377I2166J2D01*
G01X707733Y-39325D02*
G03X708388Y-38615I-1372J1923D01*
G01X708690Y-37799D02*
G03X708723Y-37402I-2329J393D01*
G01X712260D02*
G03X712294Y-37803I2362J-2D01*
G01X712593Y-38611D02*
G03X714622Y-39764I2029J1209D01*
G01X714196Y-39558D02*
G03X714492Y-39764I296J110D01*
G01X706530D02*
G03X706826Y-39558I0J316D01*
G01X751243Y-37708D02*
X750721Y-39119D01*
G01X750849Y-37637D02*
X750255Y-39245D01*
G01X750731Y-36377D02*
X749596Y-39449D01*
G01X750547Y-36308D02*
X749345Y-39558D01*
G01X748966Y-39449D02*
X750177Y-36172D01*
G01X756716Y-39558D02*
X757096Y-39449D01*
G01X755330Y-36377D02*
X755884Y-36172D01*
G01X741157Y-36377D02*
X741711Y-36172D01*
G01X726984Y-36377D02*
X727538Y-36172D01*
G01X736548Y-39119D02*
X737070Y-37708D01*
G01X736676Y-37637D02*
X736082Y-39245D01*
G01X736558Y-36377D02*
X735422Y-39449D01*
G01X736373Y-36308D02*
X735172Y-39558D01*
G01X734793Y-39449D02*
X736004Y-36172D01*
G01X722375Y-39119D02*
X722897Y-37708D01*
G01X722503Y-37637D02*
X721909Y-39245D01*
G01X722385Y-36377D02*
X721249Y-39449D01*
G01X722200Y-36308D02*
X720999Y-39558D01*
G01X720620Y-39449D02*
X721831Y-36172D01*
G01X742543Y-39558D02*
X742922Y-39449D01*
G01X728370Y-39558D02*
X728749Y-39449D01*
G01X714196Y-39558D02*
X714576Y-39449D01*
G01X712811Y-36377D02*
X713365Y-36172D01*
G01X708723Y-37708D02*
X708202Y-39119D01*
G01X708330Y-37637D02*
X707736Y-39245D01*
G01X708211Y-36377D02*
X707076Y-39449D01*
G01X708027Y-36308D02*
X706826Y-39558D01*
G01X706446Y-39449D02*
X707658Y-36172D01*
G01X757178Y-31890D02*
Y-39764D01*
G01X757096Y-39449D02*
Y-39764D01*
G01X756466Y-39449D02*
Y-39764D01*
G01X755787Y-35626D02*
Y-7499D01*
G01X755393D02*
Y-35626D01*
G01X755196Y-7499D02*
Y-35626D01*
G01X755173Y-7577D02*
Y-37640D01*
G01X754780Y-7577D02*
Y-37402D01*
G01X754386Y-7577D02*
Y-39764D01*
G01X751637Y-7577D02*
Y-39764D01*
G01X751243Y-7577D02*
Y-37708D01*
G01X750865Y-35626D02*
Y-7499D01*
G01X750849Y-37637D02*
Y-7577D01*
G01X750669Y-7499D02*
Y-35626D01*
G01X750275Y-7499D02*
Y-35626D01*
G01X750255Y-31890D02*
Y-39531D01*
G01X749596Y-39449D02*
Y-39764D01*
G01X748966Y-39449D02*
Y-39764D01*
G01X747893Y-31890D02*
Y-39764D01*
G01X747533Y-31890D02*
Y-39764D01*
G01X743005Y-31890D02*
Y-39764D01*
G01X742922Y-39449D02*
Y-39764D01*
G01X742293Y-39449D02*
Y-39764D01*
G01X741613Y-35626D02*
Y-7499D01*
G01X741220D02*
Y-35626D01*
G01X741023Y-7499D02*
Y-35626D01*
G01X741000Y-7577D02*
Y-37640D01*
G01X740606Y-7577D02*
Y-37402D01*
G01X740213Y-39764D02*
Y-7577D01*
G01X737463D02*
Y-39764D01*
G01X737070Y-37708D02*
Y-7577D01*
G01X736692Y-35626D02*
Y-7499D01*
G01X736676Y-37637D02*
Y-7577D01*
G01X736495Y-7499D02*
Y-35626D01*
G01X736102Y-7499D02*
Y-35626D01*
G01X736082Y-39531D02*
Y-31890D01*
G01X735422Y-39449D02*
Y-39764D01*
G01X734793Y-39449D02*
Y-39764D01*
G01X733720Y-31890D02*
Y-39764D01*
G01X733360Y-31890D02*
Y-39764D01*
G01X728832Y-31890D02*
Y-39764D01*
G01X728749Y-39449D02*
Y-39764D01*
G01X728119Y-39449D02*
Y-39764D01*
G01X727440Y-35626D02*
Y-7499D01*
G01X727047D02*
Y-35626D01*
G01X726850Y-7499D02*
Y-35626D01*
G01X726827Y-7577D02*
Y-37640D01*
G01X726433Y-7577D02*
Y-37402D01*
G01X726039Y-39764D02*
Y-7577D01*
G01X723290D02*
Y-39764D01*
G01X722897Y-37708D02*
Y-7577D01*
G01X722519Y-35626D02*
Y-7499D01*
G01X722503Y-37637D02*
Y-7577D01*
G01X722322Y-7499D02*
Y-35626D01*
G01X721928Y-7499D02*
Y-35626D01*
G01X721909Y-39531D02*
Y-31890D01*
G01X721249Y-39449D02*
Y-39764D01*
G01X720620Y-39449D02*
Y-39764D01*
G01X719547Y-31890D02*
Y-39764D01*
G01X719186Y-31890D02*
Y-39764D01*
G01X714659Y-31890D02*
Y-39764D01*
G01X714576D02*
Y-39449D01*
G01X713946D02*
Y-39764D01*
G01X713267Y-35626D02*
Y-7499D01*
G01X712873Y-35626D02*
Y-7499D01*
G01X712676D02*
Y-35626D01*
G01X712654Y-7577D02*
Y-37640D01*
G01X712260Y-7577D02*
Y-37402D01*
G01X711866Y-7577D02*
Y-39764D01*
G01X709117Y-7577D02*
Y-39764D01*
G01X708723Y-7577D02*
Y-37708D01*
G01X708346Y-35626D02*
Y-7499D01*
G01X708330Y-37637D02*
Y-7577D01*
G01X708149Y-7499D02*
Y-35626D01*
G01X707755Y-7499D02*
Y-35626D01*
G01X707736Y-39531D02*
Y-31890D01*
G01X707076Y-39449D02*
Y-39764D01*
G01X706446Y-39449D02*
Y-39764D01*
G01X706293Y-1181D02*
Y-39764D01*
G01X705965Y62697D02*
Y-12828D01*
G01X755884Y-36172D02*
X757096Y-39449D01*
G01X756716Y-39558D02*
X755515Y-36308D01*
G01X756466Y-39449D02*
X755330Y-36377D01*
G01X755805Y-39350D02*
X755173Y-37640D01*
G01X754814Y-37803D02*
X755113Y-38611D01*
G01X741711Y-36172D02*
X742922Y-39449D01*
G01X742543Y-39558D02*
X741342Y-36308D01*
G01X742293Y-39449D02*
X741157Y-36377D01*
G01X741632Y-39350D02*
X741000Y-37640D01*
G01X740641Y-37803D02*
X740939Y-38611D01*
G01X727538Y-36172D02*
X728749Y-39449D01*
G01X728370Y-39558D02*
X727169Y-36308D01*
G01X728119Y-39449D02*
X726984Y-36377D01*
G01X727459Y-39350D02*
X726827Y-37640D01*
G01X726467Y-37803D02*
X726766Y-38611D01*
G01X713365Y-36172D02*
X714576Y-39449D01*
G01X712995Y-36308D02*
X714196Y-39558D01*
G01X713946Y-39449D02*
X712811Y-36377D01*
G01X713286Y-39350D02*
X712654Y-37640D01*
G01X712294Y-37803D02*
X712593Y-38611D01*
G01X756466Y-39449D02*
X756716Y-39558D01*
G01X742293Y-39449D02*
X742543Y-39558D01*
G01X728119Y-39449D02*
X728370Y-39558D01*
G01X713946Y-39449D02*
X714196Y-39558D01*
G01X750177Y-36172D02*
X750731Y-36377D01*
G01X736004Y-36172D02*
X736558Y-36377D01*
G01X721831Y-36172D02*
X722385Y-36377D01*
G01X707658Y-36172D02*
X708211Y-36377D01*
G01X748966Y-39449D02*
X749345Y-39558D01*
G01X734793Y-39449D02*
X735172Y-39558D01*
G01X750255Y-39471D02*
X750335Y-39494D01*
G01X736082Y-39471D02*
X736162Y-39494D01*
G01X720620Y-39449D02*
X720999Y-39558D01*
G01X706446Y-39449D02*
X706826Y-39558D01*
G01X721909Y-39471D02*
X721989Y-39494D01*
G01X707736Y-39471D02*
X707816Y-39494D01*
G01X751243Y-37708D02*
X750849Y-37637D01*
G01X737070Y-37708D02*
X736676Y-37637D01*
G01X722897Y-37708D02*
X722503Y-37637D01*
G01X708723Y-37708D02*
X708330Y-37637D01*
G01X706293Y-12828D02*
X705965D01*
G01X747893Y-31890D02*
X750255D01*
G01X733720D02*
X736082D01*
G01X719547D02*
X721909D01*
G01X707736D02*
X706293D01*
G01X719186D02*
X714659D01*
G01X733360D02*
X728832D01*
G01X747533D02*
X743005D01*
G01X762592D02*
X757178D01*
G01X755196Y-35626D02*
X755787D01*
G01X741023D02*
X741613D01*
G01X726850D02*
X727440D01*
G01X712676D02*
X713267D01*
G01X707755D02*
X708346D01*
G01X722519D02*
X721928D01*
G01X736692D02*
X736102D01*
G01X750865D02*
X750275D01*
G01X751243Y-37402D02*
X754780D01*
G01X737070D02*
X740606D01*
G01X722897D02*
X726433D01*
G01X708723D02*
X712260D01*
G01X757178Y-39276D02*
X762592D01*
G01X743005D02*
X747533D01*
G01X728832D02*
X733360D01*
G01X714659D02*
X719186D01*
G01X707736D02*
X706293D01*
G01X721909D02*
X719547D01*
G01X736082D02*
X733720D01*
G01X750255D02*
X747893D01*
G01X749596Y-39449D02*
X762592D01*
G01X735422D02*
X748966D01*
G01X721249D02*
X734793D01*
G01X707076D02*
X720620D01*
G01X706293D02*
X706446D01*
G01X749049Y-39764D02*
X749596D01*
G01X734876D02*
X735422D01*
G01X706293D02*
X762592D01*
G01X728119D02*
X728666D01*
G01X742293D02*
X742839D01*
G01X756466D02*
X757012D01*
G01X712654Y-37640D02*
X712280Y-37706D01*
G01X726453D02*
X726827Y-37640D01*
G01X740626Y-37706D02*
X741000Y-37640D01*
G01X754799Y-37706D02*
X755173Y-37640D01*
G01X709097Y-7354D02*
X709149Y-7480D01*
G01X709055Y-7223D02*
X709097Y-7354D01*
G01X709028Y-7123D02*
X709055Y-7223D01*
G01X709019Y-7087D02*
X709028Y-7123D01*
G01X723270Y-7354D02*
X723323Y-7480D01*
G01X723229Y-7223D02*
X723270Y-7354D01*
G01X723202Y-7123D02*
X723229Y-7223D01*
G01X723192Y-7087D02*
X723202Y-7123D01*
G01X723138Y-6846D02*
X723109Y-6693D01*
G01X723166Y-6973D02*
X723138Y-6846D01*
G01X723185Y-7057D02*
X723166Y-6973D01*
G01X723192Y-7087D02*
X723185Y-7057D01*
G01X709012D02*
X709019Y-7087D01*
G01X708992Y-6972D02*
X709012Y-7057D01*
G01X708965Y-6844D02*
X708992Y-6972D01*
G01X708935Y-6693D02*
X708965Y-6844D01*
G01X737443Y-7354D02*
X737496Y-7480D01*
G01X737402Y-7223D02*
X737443Y-7354D01*
G01X737375Y-7123D02*
X737402Y-7223D01*
G01X737366Y-7087D02*
X737375Y-7123D01*
G01X751617Y-7354D02*
X751669Y-7480D01*
G01X751575Y-7223D02*
X751617Y-7354D01*
G01X751548Y-7123D02*
X751575Y-7223D01*
G01X751539Y-7087D02*
X751548Y-7123D01*
G01X737312Y-6846D02*
X737282Y-6693D01*
G01X737339Y-6973D02*
X737312Y-6846D01*
G01X737358Y-7057D02*
X737339Y-6973D01*
G01X737366Y-7087D02*
X737358Y-7057D01*
G01X751485Y-6846D02*
X751455Y-6693D01*
G01X751512Y-6973D02*
X751485Y-6846D01*
G01X751532Y-7057D02*
X751512Y-6973D01*
G01X751539Y-7087D02*
X751532Y-7057D01*
G01X711971D02*
X711964Y-7087D01*
G01X711991Y-6972D02*
X711971Y-7057D01*
G01X712018Y-6844D02*
X711991Y-6972D01*
G01X712048Y-6693D02*
X712018Y-6844D01*
G01X726191Y-6846D02*
X726221Y-6693D01*
G01X726164Y-6973D02*
X726191Y-6846D01*
G01X726145Y-7057D02*
X726164Y-6973D01*
G01X726137Y-7087D02*
X726145Y-7057D01*
G01X740364Y-6846D02*
X740394Y-6693D01*
G01X740337Y-6973D02*
X740364Y-6846D01*
G01X740318Y-7057D02*
X740337Y-6973D01*
G01X740311Y-7087D02*
X740318Y-7057D01*
G01X726069Y-7327D02*
X726007Y-7480D01*
G01X726108Y-7199D02*
X726069Y-7327D01*
G01X726130Y-7115D02*
X726108Y-7199D01*
G01X726137Y-7087D02*
X726130Y-7115D01*
G01X740242Y-7327D02*
X740180Y-7480D01*
G01X740281Y-7199D02*
X740242Y-7327D01*
G01X740303Y-7115D02*
X740281Y-7199D01*
G01X740311Y-7087D02*
X740303Y-7115D01*
G01X711956Y-7120D02*
X711964Y-7087D01*
G01X711930Y-7214D02*
X711956Y-7120D01*
G01X711889Y-7346D02*
X711930Y-7214D01*
G01X711834Y-7480D02*
X711889Y-7346D01*
G01X754538Y-6846D02*
X754568Y-6693D01*
G01X754510Y-6973D02*
X754538Y-6846D01*
G01X754491Y-7057D02*
X754510Y-6973D01*
G01X754484Y-7087D02*
X754491Y-7057D01*
G01X754415Y-7327D02*
X754354Y-7480D01*
G01X754454Y-7199D02*
X754415Y-7327D01*
G01X754477Y-7115D02*
X754454Y-7199D01*
G01X754484Y-7087D02*
X754477Y-7115D01*
G01X751889Y48819D02*
G03I-708J0D01*
G01X758976Y48425D02*
G03I-709J0D01*
G01X760515Y46771D02*
G03I-1968J0D01*
G01X753428D02*
G03I-1968J0D01*
G01X758976Y44094D02*
G03I-709J0D01*
G01X757169Y45039D02*
G03X756184Y44055I0J-985D01*
G01X758547Y41053D02*
G03X756972Y39478I0J-1575D01*
G01X758976Y38582D02*
G03I-709J0D01*
G01Y34252D02*
G03I-709J0D01*
G01X757011Y36087D02*
G03Y34307I1299J-890D01*
G01X751889Y43307D02*
G03I-708J0D01*
G01X750082Y45039D02*
G03X749098Y44055I0J-984D01*
G01X753822D02*
G03X752838Y45039I-984J0D01*
G01X753035Y39478D02*
G03X749885I-1575J0D01*
G01X751889Y38976D02*
G03I-708J0D01*
G01Y34645D02*
G03I-708J0D01*
G01X752995Y34307D02*
G03Y36087I-1299J890D01*
G01X749924D02*
G03Y34307I1300J-890D01*
G01X744803Y48425D02*
G03I-709J0D01*
G01X737716Y48819D02*
G03I-708J0D01*
G01X746342Y46771D02*
G03I-1969J0D01*
G01X739255D02*
G03I-1968J0D01*
G01X744803Y44094D02*
G03I-709J0D01*
G01X742995Y45039D02*
G03X742011Y44055I0J-984D01*
G01X746736D02*
G03X745751Y45039I-984J0D01*
G01X745948Y39478D02*
G03X742799I-1574J0D01*
G01X744803Y38582D02*
G03I-709J0D01*
G01Y34252D02*
G03I-709J0D01*
G01X745909Y34307D02*
G03Y36087I-1299J890D01*
G01X742838D02*
G03Y34307I1299J-890D01*
G01X737716Y43307D02*
G03I-708J0D01*
G01X735909Y45039D02*
G03X734925Y44055I0J-984D01*
G01X739649D02*
G03X738665Y45039I-984J0D01*
G01X738862Y39478D02*
G03X735712I-1575J0D01*
G01X737716Y38976D02*
G03I-708J0D01*
G01Y34645D02*
G03I-708J0D01*
G01X738822Y34307D02*
G03Y36087I-1299J890D01*
G01X735751D02*
G03Y34307I1300J-890D01*
G01X758976Y29921D02*
G03I-709J0D01*
G01X757011Y29000D02*
G03Y27220I1299J-890D01*
G01X758976Y24409D02*
G03I-709J0D01*
G01Y20078D02*
G03I-709J0D01*
G01X751889Y29134D02*
G03I-708J0D01*
G01X752995Y27220D02*
G03Y29000I-1299J890D01*
G01X749924D02*
G03Y27220I1300J-890D01*
G01X751889Y24803D02*
G03I-708J0D01*
G01Y20472D02*
G03I-708J0D01*
G01Y14960D02*
G03I-708J0D01*
G01X758976Y15748D02*
G03I-709J0D01*
G01Y10236D02*
G03I-709J0D01*
G01X744803Y29921D02*
G03I-709J0D01*
G01X745909Y27220D02*
G03Y29000I-1299J890D01*
G01X742838D02*
G03Y27220I1299J-890D01*
G01X744803Y24409D02*
G03I-709J0D01*
G01Y20078D02*
G03I-709J0D01*
G01X737716Y29134D02*
G03I-708J0D01*
G01X738822Y27220D02*
G03Y29000I-1299J890D01*
G01X735751D02*
G03Y27220I1300J-890D01*
G01X737716Y24803D02*
G03I-708J0D01*
G01Y20472D02*
G03I-708J0D01*
G01Y14960D02*
G03I-708J0D01*
G01X744803Y15748D02*
G03I-709J0D01*
G01Y10236D02*
G03I-709J0D01*
G01X730630Y48425D02*
G03I-709J0D01*
G01X723543Y48819D02*
G03I-709J0D01*
G01X732169Y46771D02*
G03I-1969J0D01*
G01X725082D02*
G03I-1969J0D01*
G01X730630Y44094D02*
G03I-709J0D01*
G01X728822Y45039D02*
G03X727838Y44055I0J-984D01*
G01X732562D02*
G03X731578Y45039I-984J0D01*
G01X731775Y39478D02*
G03X728625I-1575J0D01*
G01X730630Y38582D02*
G03I-709J0D01*
G01Y34252D02*
G03I-709J0D01*
G01X731736Y34307D02*
G03Y36087I-1300J890D01*
G01X728665D02*
G03Y34307I1299J-890D01*
G01X723543Y43307D02*
G03I-709J0D01*
G01X721736Y45039D02*
G03X720751Y44055I0J-985D01*
G01X725476D02*
G03X724491Y45039I-984J0D01*
G01X724688Y39478D02*
G03X721539I-1574J0D01*
G01X723543Y38976D02*
G03I-709J0D01*
G01Y34645D02*
G03I-709J0D01*
G01X724649Y34307D02*
G03Y36087I-1299J890D01*
G01X721578D02*
G03Y34307I1299J-890D01*
G01X716456Y48425D02*
G03I-708J0D01*
G01X709370Y48819D02*
G03I-709J0D01*
G01X717995Y46771D02*
G03I-1968J0D01*
G01X710909D02*
G03I-1969J0D01*
G01X716456Y44094D02*
G03I-708J0D01*
G01X714649Y45039D02*
G03X713665Y44055I0J-984D01*
G01X718389D02*
G03X717405Y45039I-984J0D01*
G01X717602Y39478D02*
G03X714452I-1575J0D01*
G01X716456Y38582D02*
G03I-708J0D01*
G01Y34252D02*
G03I-708J0D01*
G01X714491Y36087D02*
G03Y34307I1300J-890D01*
G01X717562D02*
G03Y36087I-1299J890D01*
G01X709370Y43307D02*
G03I-709J0D01*
G01X707562Y45039D02*
G03X706578Y44055I0J-984D01*
G01X711302D02*
G03X710318Y45039I-984J0D01*
G01X705938Y42608D02*
G03X707513Y41033I1575J0D01*
G01X710515Y39478D02*
G03X708940Y41053I-1575J0D01*
G01X709370Y38976D02*
G03I-709J0D01*
G01Y34645D02*
G03I-709J0D01*
G01X707405Y36087D02*
G03Y34307I1299J-890D01*
G01X710476D02*
G03Y36087I-1300J890D01*
G01X730630Y29921D02*
G03I-709J0D01*
G01X731736Y27220D02*
G03Y29000I-1300J890D01*
G01X728665D02*
G03Y27220I1299J-890D01*
G01X730630Y24409D02*
G03I-709J0D01*
G01Y20078D02*
G03I-709J0D01*
G01X723543Y29134D02*
G03I-709J0D01*
G01X724649Y27220D02*
G03Y29000I-1299J890D01*
G01X721578D02*
G03Y27220I1299J-890D01*
G01X723543Y24803D02*
G03I-709J0D01*
G01Y20472D02*
G03I-709J0D01*
G01Y14960D02*
G03I-709J0D01*
G01X730630Y15748D02*
G03I-709J0D01*
G01Y10236D02*
G03I-709J0D01*
G01X716456Y29921D02*
G03I-708J0D01*
G01X714491Y29000D02*
G03Y27220I1300J-890D01*
G01X717562D02*
G03Y29000I-1299J890D01*
G01X716456Y24409D02*
G03I-708J0D01*
G01Y20078D02*
G03I-708J0D01*
G01X709370Y29134D02*
G03I-709J0D01*
G01X707405Y29000D02*
G03Y27220I1299J-890D01*
G01X710476D02*
G03Y29000I-1300J890D01*
G01X709370Y24803D02*
G03I-709J0D01*
G01Y20472D02*
G03I-709J0D01*
G01X716456Y15748D02*
G03I-708J0D01*
G01Y10236D02*
G03I-708J0D01*
G01X709370Y14960D02*
G03I-709J0D01*
G01X710630D02*
G03I-1969J0D01*
G01X758976Y5905D02*
G03I-709J0D01*
G01X754383Y-7577D02*
G03X754351Y-7482I-157J0D01*
G01X751672D02*
G03X751640Y-7577I125J-95D01*
G01X751080Y-7302D02*
G03X750884Y-7499I0J-196D01*
G01X755178D02*
G03X754981Y-7302I-197J0D01*
G01X751080Y-7105D02*
G03X750687Y-7499I0J-393D01*
G01X755375D02*
G03X754981Y-7105I-394J0D01*
G01X751540Y-7089D02*
G03X751246Y-7577I258J-488D01*
G01X754776D02*
G03X754482Y-7089I-552J0D01*
G01X755769Y-7499D02*
G03X754981Y-6711I-788J0D01*
G01X751080D02*
G03X750293Y-7499I0J-787D01*
G01X751456Y-6696D02*
G03X750852Y-7577I341J-881D01*
G01X755170D02*
G03X754566Y-6696I-945J0D01*
G01X744803Y5905D02*
G03I-709J0D01*
G01X740210Y-7577D02*
G03X740178Y-7482I-157J0D01*
G01X737498D02*
G03X737467Y-7577I126J-94D01*
G01X736907Y-7302D02*
G03X736710Y-7499I0J-197D01*
G01X741005D02*
G03X740808Y-7302I-197J0D01*
G01X741202Y-7499D02*
G03X740808Y-7105I-394J0D01*
G01X736907D02*
G03X736513Y-7499I0J-394D01*
G01X737367Y-7089D02*
G03X737073Y-7577I258J-488D01*
G01X740603D02*
G03X740309Y-7089I-552J0D01*
G01X741595Y-7499D02*
G03X740808Y-6711I-788J0D01*
G01X736907D02*
G03X736120Y-7499I0J-787D01*
G01X737283Y-6696D02*
G03X736679Y-7577I341J-881D01*
G01X740997D02*
G03X740393Y-6696I-945J0D01*
G01X730630Y5905D02*
G03I-709J0D01*
G01X726036Y-7577D02*
G03X726005Y-7482I-157J1D01*
G01X723325D02*
G03X723293Y-7577I125J-95D01*
G01X722734Y-7302D02*
G03X722537Y-7499I0J-197D01*
G01X726832D02*
G03X726635Y-7302I-197J0D01*
G01X727028Y-7499D02*
G03X726635Y-7105I-394J0D01*
G01X722734D02*
G03X722340Y-7499I0J-394D01*
G01X723194Y-7089D02*
G03X722900Y-7577I258J-488D01*
G01X726430D02*
G03X726136Y-7089I-552J0D01*
G01X727422Y-7499D02*
G03X726635Y-6711I-788J0D01*
G01X722734D02*
G03X721947Y-7499I0J-787D01*
G01X723110Y-6696D02*
G03X722506Y-7577I341J-881D01*
G01X726824D02*
G03X726220Y-6696I-945J0D01*
G01X716456Y5905D02*
G03I-708J0D01*
G01X711863Y-7577D02*
G03X711831Y-7482I-157J0D01*
G01X709152D02*
G03X709120Y-7577I125J-95D01*
G01X708561Y-7302D02*
G03X708364Y-7499I0J-197D01*
G01X712658D02*
G03X712462Y-7302I-197J0D01*
G01X712855Y-7499D02*
G03X712462Y-7105I-394J0D01*
G01X708561D02*
G03X708167Y-7499I0J-394D01*
G01X709021Y-7089D02*
G03X708726Y-7577I256J-488D01*
G01X712257D02*
G03X711963Y-7089I-552J0D01*
G01X713249Y-7499D02*
G03X712462Y-6711I-788J0D01*
G01X708561D02*
G03X707773Y-7499I0J-788D01*
G01X708937Y-6696D02*
G03X708333Y-7577I341J-881D01*
G01X712650D02*
G03X712047Y-6696I-945J0D01*
G01X706693Y11750D02*
X706752Y11810D01*
G01X712037Y12081D02*
X711860Y11870D01*
G01Y12111D02*
X712037Y12323D01*
G01X706929Y11780D02*
X706840Y11659D01*
G01X756982Y25730D02*
X755594Y23327D01*
G01X749895Y25730D02*
X748507Y23327D01*
G01X757799Y39921D02*
X757011Y38557D01*
G01X742808Y25730D02*
X741421Y23327D01*
G01X750712Y39921D02*
X749925Y38557D01*
G01X735722Y25730D02*
X734334Y23327D01*
G01X743625Y39921D02*
X742838Y38557D01*
G01X728635Y25730D02*
X727247Y23327D01*
G01X736539Y39921D02*
X735751Y38557D01*
G01X721549Y25730D02*
X720161Y23327D01*
G01X729452Y39921D02*
X728665Y38557D01*
G01X706840Y11659D02*
X706722Y11569D01*
G01X714462Y25730D02*
X713074Y23327D01*
G01X722365Y39921D02*
X721578Y38557D01*
G01X715279Y39921D02*
X714491Y38557D01*
G01X708192Y39921D02*
X707405Y38557D01*
G01X710443Y10905D02*
X710915Y12323D01*
G01X710738Y11267D02*
X710620Y10905D01*
G01X710767Y11388D02*
X711033Y12202D01*
G01X706958Y11870D02*
X706929Y11780D01*
G01X706752Y11810D02*
X706781Y11900D01*
G01X706604Y11719D02*
X706693Y11750D01*
G01X757011Y27220D02*
Y22204D01*
G01Y34307D02*
Y29000D01*
G01Y38557D02*
Y36087D01*
G01X756982Y27265D02*
Y25730D01*
G01Y34351D02*
Y28955D01*
G01Y39478D02*
Y36042D01*
G01X756184Y44055D02*
Y22204D01*
G01X754981Y-7284D02*
Y-6693D01*
G01X753822Y44055D02*
Y22204D01*
G01X753025Y36042D02*
Y39478D01*
G01Y28955D02*
Y34351D01*
G01Y25730D02*
Y27265D01*
G01X752995Y27220D02*
Y22204D01*
G01Y34307D02*
Y29000D01*
G01Y38557D02*
Y36087D01*
G01X751080Y-7284D02*
Y-6693D01*
G01X749925Y36087D02*
Y38557D01*
G01Y29000D02*
Y34307D01*
G01Y22204D02*
Y27220D01*
G01X749895Y27265D02*
Y25730D01*
G01Y34351D02*
Y28955D01*
G01Y39478D02*
Y36042D01*
G01X749098Y44055D02*
Y22204D01*
G01X746736Y44055D02*
Y22204D01*
G01X745938Y36042D02*
Y39478D01*
G01Y28955D02*
Y34351D01*
G01Y25730D02*
Y27265D01*
G01X745909Y27220D02*
Y22204D01*
G01Y34307D02*
Y29000D01*
G01Y38557D02*
Y36087D01*
G01X742838D02*
Y38557D01*
G01Y29000D02*
Y34307D01*
G01Y22204D02*
Y27220D01*
G01X742808Y27265D02*
Y25730D01*
G01Y34351D02*
Y28955D01*
G01Y39478D02*
Y36042D01*
G01X742011Y44055D02*
Y22204D01*
G01X740808Y-7284D02*
Y-6693D01*
G01X739649Y44055D02*
Y22204D01*
G01X738852Y36042D02*
Y39478D01*
G01Y28955D02*
Y34351D01*
G01Y25730D02*
Y27265D01*
G01X738822Y27220D02*
Y22204D01*
G01Y34307D02*
Y29000D01*
G01Y38557D02*
Y36087D01*
G01X736907Y-7284D02*
Y-6693D01*
G01X735751Y36087D02*
Y38557D01*
G01Y29000D02*
Y34307D01*
G01Y22204D02*
Y27220D01*
G01X735722Y27265D02*
Y25730D01*
G01Y34351D02*
Y28955D01*
G01Y39478D02*
Y36042D01*
G01X734925Y44055D02*
Y22204D01*
G01X732562Y44055D02*
Y22204D01*
G01X731765Y36042D02*
Y39478D01*
G01Y28955D02*
Y34351D01*
G01Y25730D02*
Y27265D01*
G01X731736Y27220D02*
Y22204D01*
G01Y34307D02*
Y29000D01*
G01Y38557D02*
Y36087D01*
G01X728665D02*
Y38557D01*
G01Y29000D02*
Y34307D01*
G01Y22204D02*
Y27220D01*
G01X728635Y27265D02*
Y25730D01*
G01Y34351D02*
Y28955D01*
G01Y39478D02*
Y36042D01*
G01X727838Y44055D02*
Y22204D01*
G01X726635Y-7284D02*
Y-6693D01*
G01X725476Y44055D02*
Y22204D01*
G01X724678Y36042D02*
Y39478D01*
G01Y28955D02*
Y34351D01*
G01Y25730D02*
Y27265D01*
G01X724649Y27220D02*
Y22204D01*
G01Y34307D02*
Y29000D01*
G01Y38557D02*
Y36087D01*
G01X722734Y-7284D02*
Y-6693D01*
G01X721578Y36087D02*
Y38557D01*
G01Y29000D02*
Y34307D01*
G01Y22204D02*
Y27220D01*
G01X721549Y27265D02*
Y25730D01*
G01Y34351D02*
Y28955D01*
G01Y39478D02*
Y36042D01*
G01X720751Y44055D02*
Y22204D01*
G01X718389D02*
Y44055D01*
G01X717592Y36042D02*
Y39478D01*
G01Y28955D02*
Y34351D01*
G01Y25730D02*
Y27265D01*
G01X717562Y27220D02*
Y22204D01*
G01Y34307D02*
Y29000D01*
G01Y38557D02*
Y36087D01*
G01X714491D02*
Y38557D01*
G01Y29000D02*
Y34307D01*
G01Y22204D02*
Y27220D01*
G01X714462Y27265D02*
Y25730D01*
G01Y34351D02*
Y28955D01*
G01Y39478D02*
Y36042D01*
G01X713665Y44055D02*
Y22204D01*
G01X712462Y-7284D02*
Y-6693D01*
G01X712214Y12323D02*
Y10905D01*
G01X712037D02*
Y12081D01*
G01X711860Y11870D02*
Y12111D01*
G01X711302Y22204D02*
Y44055D01*
G01X710505Y36042D02*
Y39478D01*
G01Y28955D02*
Y34351D01*
G01Y25730D02*
Y27265D01*
G01X710476Y27220D02*
Y22204D01*
G01Y34307D02*
Y29000D01*
G01Y38557D02*
Y36087D01*
G01X708789Y12323D02*
Y10905D01*
G01X708612Y11116D02*
Y12323D01*
G01X708561Y-7284D02*
Y-6693D01*
G01X707785Y12142D02*
Y10905D01*
G01X707608D02*
Y12323D01*
G01X707405Y36087D02*
Y38557D01*
G01Y29000D02*
Y34307D01*
G01Y22204D02*
Y27220D01*
G01X707372Y12323D02*
Y10905D01*
G01X707195D02*
Y12323D01*
G01X706958Y11991D02*
Y11870D01*
G01X706781Y11900D02*
Y11991D01*
G01X706578Y44055D02*
Y22204D01*
G01X706043Y12172D02*
Y11719D01*
G01Y11539D02*
Y10905D01*
G01X705948Y42608D02*
Y60138D01*
G01X705866Y10905D02*
Y12323D01*
G01X711033Y12202D02*
X711299Y11388D01*
G01X711447Y10905D02*
X711328Y11267D01*
G01X706929Y12081D02*
X706958Y11991D01*
G01X706781D02*
X706752Y12081D01*
G01X711151Y12323D02*
X711624Y10905D01*
G01X759295Y39921D02*
X760082Y38557D01*
G01X752208Y39921D02*
X752995Y38557D01*
G01X745121Y39921D02*
X745909Y38557D01*
G01X754413Y23327D02*
X753025Y25730D01*
G01X738035Y39921D02*
X738822Y38557D01*
G01X747326Y23327D02*
X745938Y25730D01*
G01X730948Y39921D02*
X731736Y38557D01*
G01X740239Y23327D02*
X738852Y25730D01*
G01X723862Y39921D02*
X724649Y38557D01*
G01X733153Y23327D02*
X731765Y25730D01*
G01X716775Y39921D02*
X717562Y38557D01*
G01X726066Y23327D02*
X724678Y25730D01*
G01X709688Y39921D02*
X710476Y38557D01*
G01X718980Y23327D02*
X717592Y25730D01*
G01X711893Y23327D02*
X710505Y25730D01*
G01X708523Y10905D02*
X707785Y12142D01*
G01X707874Y12323D02*
X708612Y11116D01*
G01X706840Y12202D02*
X706929Y12081D01*
G01X706752D02*
X706693Y12142D01*
G01X706722Y12292D02*
X706840Y12202D01*
G01X706693Y12142D02*
X706604Y12172D01*
G01X706575Y12323D02*
X706722Y12292D01*
G01X710318Y45039D02*
X707562D01*
G01X717405D02*
X714649D01*
G01X724491D02*
X721736D01*
G01X731578D02*
X728822D01*
G01X738665D02*
X735909D01*
G01X745751D02*
X742995D01*
G01X752838D02*
X750082D01*
G01X759925D02*
X757169D01*
G01X749098Y42516D02*
X753822D01*
G01X742011D02*
X746736D01*
G01X734925D02*
X739649D01*
G01X727838D02*
X732562D01*
G01X720751D02*
X725476D01*
G01X711302D02*
X706578D01*
G01X718389D02*
X713665D01*
G01X760909D02*
X756184D01*
G01X708940Y41043D02*
X707513D01*
G01X759974D02*
X758547D01*
G01X715279Y39921D02*
X716775D01*
G01X708192D02*
X709688D01*
G01X723862D02*
X722365D01*
G01X730948D02*
X729452D01*
G01X738035D02*
X736539D01*
G01X745121D02*
X743625D01*
G01X752208D02*
X750712D01*
G01X759295D02*
X757799D01*
G01X753232Y25372D02*
X756775D01*
G01X746145D02*
X749688D01*
G01X739058D02*
X742602D01*
G01X731972D02*
X735515D01*
G01X724885D02*
X728428D01*
G01X717799D02*
X721342D01*
G01X710712D02*
X714255D01*
G01X713074Y23327D02*
X711893D01*
G01X720161D02*
X718980D01*
G01X727247D02*
X726066D01*
G01X734334D02*
X733153D01*
G01X741421D02*
X740239D01*
G01X748507D02*
X747326D01*
G01X755594D02*
X754413D01*
G01X745909Y22204D02*
X749925D01*
G01X738822D02*
X742838D01*
G01X731736D02*
X735751D01*
G01X724649D02*
X728665D01*
G01X717562D02*
X721578D01*
G01X710476D02*
X714491D01*
G01X705965D02*
X707405D01*
G01X757011D02*
X752995D01*
G01X712037Y12323D02*
X712214D01*
G01X710915D02*
X711151D01*
G01X707608D02*
X707874D01*
G01X708612D02*
X708789D01*
G01X707195D02*
X707372D01*
G01X705866D02*
X706575D01*
G01X706604Y12172D02*
X706043D01*
G01Y11719D02*
X706604D01*
G01X706575Y11539D02*
X706043D01*
G01X711299Y11388D02*
X710767D01*
G01X711328Y11267D02*
X710738D01*
G01X707785Y10905D02*
X707608D01*
G01X708789D02*
X708523D01*
G01X707372D02*
X707195D01*
G01X706043D02*
X705866D01*
G01X712214D02*
X712037D01*
G01X711624D02*
X711447D01*
G01X710620D02*
X710443D01*
G01X762592Y-1181D02*
X705965D01*
G01X762592Y-1772D02*
X706293D01*
G01X762592Y-4394D02*
X706293D01*
G01X762592Y-4591D02*
X706293D01*
G01X712462Y-6693D02*
X708561D01*
G01X726635D02*
X722734D01*
G01X740808D02*
X736907D01*
G01X754981D02*
X751080D01*
G01X712462Y-7087D02*
X708561D01*
G01X726635D02*
X722734D01*
G01X740808D02*
X736907D01*
G01X754981D02*
X751080D01*
G01Y-7284D02*
X754981D01*
G01X736907D02*
X740808D01*
G01X722734D02*
X726635D01*
G01X708561D02*
X712462D01*
G01X711834Y-7480D02*
X709149D01*
G01X726007D02*
X723323D01*
G01X740180D02*
X737496D01*
G01X754354D02*
X751669D01*
G01X755196Y-7499D02*
X755787D01*
G01X750275D02*
X750865D01*
G01X741023D02*
X741613D01*
G01X736102D02*
X736692D01*
G01X726850D02*
X727440D01*
G01X721928D02*
X722519D01*
G01X712676D02*
X713267D01*
G01X708346D02*
X707755D01*
G01X754386Y-7577D02*
X755173D01*
G01X740213D02*
X741000D01*
G01X726039D02*
X726827D01*
G01X711866D02*
X712654D01*
G01X708330D02*
X709117D01*
G01X723290D02*
X722503D01*
G01X737463D02*
X736676D01*
G01X751637D02*
X750849D01*
G01X706722Y11569D02*
X706575Y11539D01*
G01X707478Y53433D02*
X707405Y53648D01*
G01X707593Y53231D02*
X707478Y53433D01*
G01X707746Y53051D02*
X707593Y53231D01*
G01X714565Y53433D02*
X714491Y53648D01*
G01X714680Y53231D02*
X714565Y53433D01*
G01X714833Y53051D02*
X714680Y53231D01*
G01X721651Y53433D02*
X721578Y53648D01*
G01X721766Y53231D02*
X721651Y53433D01*
G01X721919Y53051D02*
X721766Y53231D01*
G01X728738Y53433D02*
X728665Y53648D01*
G01X728853Y53231D02*
X728738Y53433D01*
G01X729006Y53051D02*
X728853Y53231D01*
G01X735824Y53433D02*
X735751Y53648D01*
G01X735939Y53231D02*
X735824Y53433D01*
G01X736093Y53051D02*
X735939Y53231D01*
G01X742911Y53433D02*
X742838Y53648D01*
G01X743026Y53231D02*
X742911Y53433D01*
G01X743179Y53051D02*
X743026Y53231D01*
G01X749998Y53433D02*
X749925Y53648D01*
G01X750113Y53231D02*
X749998Y53433D01*
G01X750266Y53051D02*
X750113Y53231D01*
G01X757084Y53433D02*
X757011Y53648D01*
G01X757199Y53231D02*
X757084Y53433D01*
G01X757353Y53051D02*
X757199Y53231D01*
G01X707549Y53421D02*
X707746Y53051D01*
G01X707420Y53852D02*
X707549Y53421D01*
G01X707375Y54309D02*
X707420Y53852D01*
G01X714636Y53421D02*
X714833Y53051D01*
G01X714507Y53852D02*
X714636Y53421D01*
G01X714462Y54309D02*
X714507Y53852D01*
G01X721722Y53421D02*
X721919Y53051D01*
G01X721594Y53852D02*
X721722Y53421D01*
G01X721549Y54309D02*
X721594Y53852D01*
G01X728809Y53421D02*
X729006Y53051D01*
G01X728680Y53852D02*
X728809Y53421D01*
G01X728635Y54309D02*
X728680Y53852D01*
G01X735896Y53421D02*
X736093Y53051D01*
G01X735767Y53852D02*
X735896Y53421D01*
G01X735722Y54309D02*
X735767Y53852D01*
G01X742982Y53421D02*
X743179Y53051D01*
G01X742853Y53852D02*
X742982Y53421D01*
G01X742808Y54309D02*
X742853Y53852D01*
G01X707383Y53766D02*
X707405Y53643D01*
G01X707375Y53889D02*
X707383Y53766D01*
G01X714469D02*
X714491Y53643D01*
G01X714462Y53889D02*
X714469Y53766D01*
G01X721556D02*
X721578Y53643D01*
G01X721549Y53889D02*
X721556Y53766D01*
G01X728643D02*
X728665Y53643D01*
G01X728635Y53889D02*
X728643Y53766D01*
G01X735729D02*
X735751Y53643D01*
G01X735722Y53889D02*
X735729Y53766D01*
G01X710498Y53767D02*
X710476Y53643D01*
G01X710505Y53889D02*
X710498Y53767D01*
G01X750069Y53421D02*
X750266Y53051D01*
G01X749940Y53852D02*
X750069Y53421D01*
G01X749895Y54309D02*
X749940Y53852D01*
G01X757155Y53421D02*
X757353Y53051D01*
G01X757027Y53852D02*
X757155Y53421D01*
G01X756982Y54309D02*
X757027Y53852D01*
G01X742816Y53766D02*
X742838Y53643D01*
G01X742808Y53889D02*
X742816Y53766D01*
G01X749902D02*
X749925Y53643D01*
G01X749895Y53889D02*
X749902Y53766D01*
G01X756989D02*
X757011Y53643D01*
G01X756982Y53889D02*
X756989Y53766D01*
G01X717584Y53767D02*
X717562Y53643D01*
G01X717592Y53889D02*
X717584Y53767D01*
G01X724671D02*
X724649Y53643D01*
G01X724678Y53889D02*
X724671Y53767D01*
G01X731758D02*
X731736Y53643D01*
G01X731765Y53889D02*
X731758Y53767D01*
G01X738844D02*
X738822Y53643D01*
G01X738852Y53889D02*
X738844Y53767D01*
G01X745931D02*
X745909Y53643D01*
G01X745938Y53889D02*
X745931Y53767D01*
G01X710287Y53231D02*
X710134Y53051D01*
G01X710403Y53433D02*
X710287Y53231D01*
G01X710476Y53648D02*
X710403Y53433D01*
G01X753018Y53767D02*
X752995Y53643D01*
G01X753025Y53889D02*
X753018Y53767D01*
G01X717374Y53231D02*
X717221Y53051D01*
G01X717490Y53433D02*
X717374Y53231D01*
G01X717562Y53648D02*
X717490Y53433D01*
G01X724460Y53231D02*
X724308Y53051D01*
G01X724576Y53433D02*
X724460Y53231D01*
G01X724649Y53648D02*
X724576Y53433D01*
G01X731547Y53231D02*
X731394Y53051D01*
G01X731663Y53433D02*
X731547Y53231D01*
G01X731736Y53648D02*
X731663Y53433D01*
G01X738634Y53231D02*
X738481Y53051D01*
G01X738749Y53433D02*
X738634Y53231D01*
G01X738822Y53648D02*
X738749Y53433D01*
G01X745720Y53231D02*
X745567Y53051D01*
G01X745836Y53433D02*
X745720Y53231D01*
G01X745909Y53648D02*
X745836Y53433D01*
G01X710460Y53853D02*
X710505Y54309D01*
G01X710332Y53422D02*
X710460Y53853D01*
G01X710134Y53051D02*
X710332Y53422D01*
G01X717547Y53853D02*
X717592Y54309D01*
G01X717418Y53422D02*
X717547Y53853D01*
G01X717221Y53051D02*
X717418Y53422D01*
G01X724634Y53853D02*
X724678Y54309D01*
G01X724505Y53422D02*
X724634Y53853D01*
G01X724308Y53051D02*
X724505Y53422D01*
G01X731720Y53853D02*
X731765Y54309D01*
G01X731591Y53422D02*
X731720Y53853D01*
G01X731394Y53051D02*
X731591Y53422D01*
G01X752807Y53231D02*
X752654Y53051D01*
G01X752923Y53433D02*
X752807Y53231D01*
G01X752995Y53648D02*
X752923Y53433D01*
G01X738807Y53853D02*
X738852Y54309D01*
G01X738678Y53422D02*
X738807Y53853D01*
G01X738481Y53051D02*
X738678Y53422D01*
G01X745893Y53853D02*
X745938Y54309D01*
G01X745765Y53422D02*
X745893Y53853D01*
G01X745567Y53051D02*
X745765Y53422D01*
G01X752980Y53853D02*
X753025Y54309D01*
G01X752851Y53422D02*
X752980Y53853D01*
G01X752654Y53051D02*
X752851Y53422D01*
G01X751889Y53149D02*
G03I-708J0D01*
G01X757345Y53045D02*
G03X759748I1201J1018D01*
G01X750258D02*
G03X752662I1202J1018D01*
G01X737716Y53149D02*
G03I-708J0D01*
G01X743172Y53045D02*
G03X745575I1201J1018D01*
G01X736085D02*
G03X738488I1201J1018D01*
G01X723543Y53149D02*
G03I-709J0D01*
G01X728999Y53045D02*
G03X731402I1202J1018D01*
G01X721912D02*
G03X724315I1201J1018D01*
G01X709370Y53149D02*
G03I-709J0D01*
G01X714825Y53045D02*
G03X717228I1202J1018D01*
G01X707739D02*
G03X710142I1201J1018D01*
G01X758192Y61712D02*
X757011Y60531D01*
G01X751106Y61712D02*
X749925Y60531D01*
G01X744019Y61712D02*
X742838Y60531D01*
G01X736932Y61712D02*
X735751Y60531D01*
G01X729846Y61712D02*
X728665Y60531D01*
G01X722759Y61712D02*
X721578Y60531D01*
G01X715673Y61712D02*
X714491Y60531D01*
G01X708586Y61712D02*
X707405Y60531D01*
G01X757011Y52657D02*
Y60531D01*
G01X756982Y60138D02*
Y53889D01*
G01X753025Y60138D02*
Y53889D01*
G01X752995Y60531D02*
Y52657D01*
G01X749925D02*
Y60531D01*
G01X749895Y60138D02*
Y53889D01*
G01X745938Y60138D02*
Y53889D01*
G01X745909Y60531D02*
Y52657D01*
G01X742838D02*
Y60531D01*
G01X742808Y60138D02*
Y53889D01*
G01X738852Y60138D02*
Y53889D01*
G01X738822Y60531D02*
Y52657D01*
G01X738189Y206693D02*
Y108267D01*
G01X735751Y52657D02*
Y60531D01*
G01X735722Y60138D02*
Y53889D01*
G01X731765Y60138D02*
Y53889D01*
G01X731736Y60531D02*
Y52657D01*
G01X728665D02*
Y60531D01*
G01X728635Y60138D02*
Y53889D01*
G01X724678Y60138D02*
Y53889D01*
G01X724649Y60531D02*
Y52657D01*
G01X721578D02*
Y60531D01*
G01X721549Y60138D02*
Y53889D01*
G01X717592Y60138D02*
Y53889D01*
G01X717562Y60531D02*
Y52657D01*
G01X714491D02*
Y60531D01*
G01X714462Y60138D02*
Y53889D01*
G01X710505Y60138D02*
Y53889D01*
G01X710476Y60531D02*
Y52657D01*
G01X707405D02*
Y60531D01*
G01X707375Y60138D02*
Y53889D01*
G01X758901Y61712D02*
X760082Y60531D01*
G01X751814Y61712D02*
X752995Y60531D01*
G01X744728Y61712D02*
X745909Y60531D01*
G01X737641Y61712D02*
X738822Y60531D01*
G01X730554Y61712D02*
X731736Y60531D01*
G01X723468Y61712D02*
X724649Y60531D01*
G01X716381Y61712D02*
X717562Y60531D01*
G01X709295Y61712D02*
X710476Y60531D01*
G01X705965Y62697D02*
X762103D01*
G01X709295Y61712D02*
X708586D01*
G01X716381D02*
X715673D01*
G01X723468D02*
X722759D01*
G01X730554D02*
X729846D01*
G01X737641D02*
X736932D01*
G01X744728D02*
X744019D01*
G01X751814D02*
X751106D01*
G01X758901D02*
X758192D01*
G01X710476Y60531D02*
X707405D01*
G01X717562D02*
X714491D01*
G01X724649D02*
X721578D01*
G01X731736D02*
X728665D01*
G01X738822D02*
X735751D01*
G01X745909D02*
X742838D01*
G01X752995D02*
X749925D01*
G01X760082D02*
X757011D01*
G01X761539Y60138D02*
X705948D01*
G01X705965Y58956D02*
X762103D01*
G01X705948Y57775D02*
X762103D01*
G01X707746Y53051D02*
X705948D01*
G01X714833D02*
X710134D01*
G01X721919D02*
X717221D01*
G01X729006D02*
X724308D01*
G01X736093D02*
X731394D01*
G01X743179D02*
X738481D01*
G01X750266D02*
X745567D01*
G01X757353D02*
X752654D01*
G01X752995Y52657D02*
X757011D01*
G01X745909D02*
X749925D01*
G01X738822D02*
X742838D01*
G01X731736D02*
X735751D01*
G01X724649D02*
X728665D01*
G01X717562D02*
X721578D01*
G01X710476D02*
X714491D01*
G01X705965D02*
X707405D01*
G01X708858Y179645D02*
Y135315D01*
G01X807086Y548127D02*
G03Y486755I-17716J-30686D01*
G01X735235Y1297911D02*
Y1278974D01*
G01X817003Y-86834D02*
G03I-4292J0D01*
G01X811771Y-102362D02*
G03X826771Y-87362I0J15000D01*
G01X762592Y-39764D02*
Y-1181D01*
G01X762103Y-12828D02*
Y62697D01*
G01X762592Y-12828D02*
X762103D01*
G01X811023Y0D02*
G03Y-7874I0J-3937D01*
G01X780315D02*
G03Y0I0J3937D01*
G01X822834Y-7874D02*
X811023D01*
G01X818897Y0D02*
G03X826771Y7874I0J7874D01*
G01X760909Y44055D02*
G03X759925Y45039I-984J0D01*
G01X759974Y41033D02*
G03X761549Y42608I0J1575D01*
G01X760082Y34307D02*
G03Y36087I-1299J890D01*
G01Y27220D02*
G03Y29000I-1299J890D01*
G01X761539Y60138D02*
Y42608D01*
G01X760909Y22204D02*
Y44055D01*
G01X760082Y27220D02*
Y22204D01*
G01Y34307D02*
Y29000D01*
G01Y38557D02*
Y36087D01*
G01Y22204D02*
X762103D01*
G01X818897Y0D02*
X807086D01*
G01X760104Y53767D02*
X760082Y53643D01*
G01X760112Y53889D02*
X760104Y53767D01*
G01X759893Y53231D02*
X759741Y53051D01*
G01X760009Y53433D02*
X759893Y53231D01*
G01X760082Y53648D02*
X760009Y53433D01*
G01X760067Y53853D02*
X760112Y54309D01*
G01X759938Y53422D02*
X760067Y53853D01*
G01X759741Y53051D02*
X759938Y53422D01*
G01X760112Y60138D02*
Y53889D01*
G01X760082Y60531D02*
Y52657D01*
G01X761539Y53051D02*
X759741D01*
G01X760082Y52657D02*
X762103D01*
G01X787401Y198819D02*
G03I-5905J0D01*
G01X793307D02*
G03I-11811J0D01*
G01X792421Y499724D02*
G03I-3051J0D01*
G01X807086Y548127D02*
Y486755D01*
G01X793504Y535157D02*
G03I-4134J0D01*
G01X796653Y517441D02*
G03I-7283J0D01*
G01X826771Y562992D02*
G03X818897Y570866I-7874J0D01*
G01X826771Y-11811D02*
Y-87362D01*
G01Y-11811D02*
G03X822834Y-7874I-3937J0D01*
G01X826771Y562992D02*
Y7874D01*
G01Y566929D02*
Y617965D01*
G01X954904Y-879845D02*
Y-898782D01*
G01Y1297911D02*
Y1278974D01*
G01X1174573Y-879845D02*
Y-898782D01*
G01X1317830Y-482443D02*
X1173525D01*
G01X1209641Y-497010D02*
X1173525D01*
G01X1317830Y-457955D02*
X1167077D01*
G01X1219815Y416352D02*
X1185267D01*
G01X1249343Y916076D02*
X1185267D01*
G01X1249343Y933793D02*
X1186576D01*
G01X1249343Y951509D02*
X1185267D01*
G01X1213071Y985881D02*
X1171535Y1026868D01*
G01D02*
X1159724D01*
G01X1219815Y987218D02*
X1185267D01*
G01X1460323Y1135090D02*
X1174208D01*
G01X1174573Y1297911D02*
Y1278974D01*
G01X1205704Y-493073D02*
Y-564169D01*
G01Y-489136D02*
Y65982D01*
G01Y-489136D02*
Y65982D01*
G01X1225389Y73856D02*
Y-497010D01*
G01X2024601D02*
X1213578D01*
G01X1225389D02*
X1213578D01*
G01X1205704Y-489136D02*
G03X1213578Y-497010I7874J0D01*
G01X1205704Y-489136D02*
G03X1213578Y-497010I7874J0D01*
G01X1210192Y-289215D02*
Y-287985D01*
G01Y-285278D02*
Y-284048D01*
G01Y-281341D02*
Y-280111D01*
G01Y-278142D02*
Y-276912D01*
G01Y-274205D02*
Y-272975D01*
G01X1217229Y-287000D02*
Y-286262D01*
G01Y-283063D02*
Y-282571D01*
G01Y-275928D02*
Y-275189D01*
G01Y-271991D02*
Y-271498D01*
G01X1218234D02*
Y-272483D01*
G01Y-275435D02*
Y-276420D01*
G01Y-280111D02*
Y-281341D01*
G01Y-282571D02*
Y-283556D01*
G01Y-286508D02*
Y-287493D01*
G01X1217982Y-285770D02*
X1218234Y-286508D01*
G01X1217229Y-282571D02*
X1216977Y-281833D01*
G01X1217982D02*
X1218234Y-282571D01*
G01X1217982Y-274697D02*
X1218234Y-275435D01*
G01X1217229Y-271498D02*
X1216977Y-270760D01*
G01X1217982D02*
X1218234Y-271498D01*
G01X1217229Y-286262D02*
X1216977Y-285770D01*
G01X1217229Y-275189D02*
X1216977Y-274697D01*
G01X1218234Y-272483D02*
X1217982Y-273221D01*
G01X1218234Y-276420D02*
X1217982Y-277158D01*
G01X1218234Y-283556D02*
X1217982Y-284294D01*
G01X1218234Y-287493D02*
X1217982Y-288231D01*
G01X1216977Y-272483D02*
X1217229Y-271991D01*
G01X1216977Y-285770D02*
X1216726Y-285524D01*
G01X1217229Y-285032D02*
X1217982Y-285770D01*
G01X1216977Y-281833D02*
X1216475Y-281341D01*
G01X1217480D02*
X1217982Y-281833D01*
G01X1216977Y-276420D02*
X1217229Y-275928D01*
G01X1216977Y-283556D02*
X1217229Y-283063D01*
G01X1216977Y-287493D02*
X1217229Y-287000D01*
G01X1216977Y-274697D02*
X1216726Y-274451D01*
G01X1217229Y-273959D02*
X1217982Y-274697D01*
G01X1216977Y-270760D02*
X1216475Y-270268D01*
G01X1217480D02*
X1217982Y-270760D01*
G01X1216726Y-272729D02*
X1216977Y-272483D01*
G01X1217982Y-273221D02*
X1217229Y-273959D01*
G01X1216726Y-276666D02*
X1216977Y-276420D01*
G01X1217982Y-277158D02*
X1217480Y-277650D01*
G01X1216726Y-285524D02*
X1216223Y-285278D01*
G01X1216726Y-274451D02*
X1216223Y-274205D01*
G01X1216726Y-283802D02*
X1216977Y-283556D01*
G01X1217982Y-284294D02*
X1217229Y-285032D01*
G01X1216726Y-287739D02*
X1216977Y-287493D01*
G01X1217982Y-288231D02*
X1217480Y-288723D01*
G01X1216223Y-272975D02*
X1216726Y-272729D01*
G01X1216223Y-276912D02*
X1216726Y-276666D01*
G01X1216223Y-284048D02*
X1216726Y-283802D01*
G01X1216223Y-287985D02*
X1216726Y-287739D01*
G01X1217480Y-277650D02*
X1216223Y-278142D01*
G01X1217480Y-288723D02*
X1216223Y-289215D01*
G01D02*
X1210192D01*
G01Y-287985D02*
X1216223D01*
G01Y-285278D02*
X1210192D01*
G01Y-284048D02*
X1216223D01*
G01X1218234Y-281341D02*
X1217480D01*
G01X1216475D02*
X1210192D01*
G01Y-280111D02*
X1218234D01*
G01X1216223Y-278142D02*
X1210192D01*
G01Y-276912D02*
X1216223D01*
G01Y-274205D02*
X1210192D01*
G01Y-272975D02*
X1216223D01*
G01X1210192Y-270268D02*
Y-269038D01*
G01Y-267069D02*
Y-258211D01*
G01X1211449Y-260180D02*
Y-267069D01*
G01X1218234Y-269038D02*
Y-270268D01*
G01X1219239Y-259687D02*
Y-258457D01*
G01X1220747Y-263132D02*
Y-262148D01*
G01D02*
X1220495Y-260918D01*
G01X1221752Y-260672D02*
X1222003Y-262394D01*
G01D02*
Y-263378D01*
G01D02*
X1221752Y-264855D01*
G01X1220495Y-264363D02*
X1220747Y-263132D01*
G01X1221249Y-259687D02*
X1221752Y-260672D01*
G01X1211449Y-258211D02*
X1217731Y-265101D01*
G01X1216977Y-266331D02*
X1211449Y-260180D01*
G01X1220495Y-260918D02*
X1219993Y-260180D01*
G01X1221752Y-264855D02*
X1221249Y-265839D01*
G01X1219993Y-265101D02*
X1220495Y-264363D01*
G01X1220244Y-258703D02*
X1221249Y-259687D01*
G01X1217731Y-266823D02*
X1216977Y-266331D01*
G01X1221249Y-265839D02*
X1220244Y-266823D01*
G01X1219993Y-260180D02*
X1219239Y-259687D01*
G01X1217731Y-265101D02*
X1218736Y-265593D01*
G01X1219239D02*
X1219993Y-265101D01*
G01X1218736Y-267069D02*
X1217731Y-266823D01*
G01X1218234Y-270268D02*
X1217480D01*
G01X1216475D02*
X1210192D01*
G01Y-269038D02*
X1218234D01*
G01X1219239Y-267069D02*
X1218736D01*
G01X1211449D02*
X1210192D01*
G01X1218736Y-265593D02*
X1219239D01*
G01X1220244Y-266823D02*
X1219239Y-267069D01*
G01X1210192Y-256243D02*
Y-255012D01*
G01X1211449D02*
Y-256243D01*
G01Y-248615D02*
X1211700Y-249845D01*
G01X1220747Y-248615D02*
X1220495Y-247384D01*
G01X1210192Y-248615D02*
X1210443Y-250091D01*
G01X1222003Y-248615D02*
X1221752Y-247138D01*
G01X1210443D02*
X1210192Y-248615D01*
G01X1221752Y-250091D02*
X1222003Y-248615D01*
G01X1211700Y-247384D02*
X1211449Y-248615D01*
G01X1220495Y-249845D02*
X1220747Y-248615D01*
G01X1210443Y-250091D02*
X1211197Y-251321D01*
G01X1216223Y-237050D02*
X1218736Y-241725D01*
G01X1217982Y-242217D02*
X1216223Y-238772D01*
G01D02*
X1214464Y-242217D01*
G01X1213710Y-241725D02*
X1216223Y-237050D01*
G01X1211700Y-249845D02*
X1212203Y-250583D01*
G01X1220495Y-247384D02*
X1219993Y-246646D01*
G01X1221752Y-247138D02*
X1220998Y-245908D01*
G01X1211197D02*
X1210443Y-247138D01*
G01X1220998Y-251321D02*
X1221752Y-250091D01*
G01X1212203Y-246646D02*
X1211700Y-247384D01*
G01X1219993Y-250583D02*
X1220495Y-249845D01*
G01X1211197Y-251321D02*
X1211951Y-252059D01*
G01X1220998Y-245908D02*
X1220244Y-245170D01*
G01X1211951D02*
X1211197Y-245908D01*
G01X1220244Y-252059D02*
X1220998Y-251321D01*
G01X1212203Y-250583D02*
X1213710Y-251567D01*
G01X1219993Y-246646D02*
X1218485Y-245662D01*
G01X1214464Y-242217D02*
X1213710Y-241725D01*
G01X1211951Y-252059D02*
X1212956Y-252552D01*
G01X1220244Y-245170D02*
X1219239Y-244678D01*
G01X1218736Y-241725D02*
X1217982Y-242217D01*
G01X1213710Y-245662D02*
X1212203Y-246646D01*
G01X1218485Y-251567D02*
X1219993Y-250583D01*
G01X1212956Y-252552D02*
X1213710Y-252798D01*
G01X1212956Y-244678D02*
X1211951Y-245170D01*
G01X1219239Y-252552D02*
X1220244Y-252059D01*
G01X1219239Y-258457D02*
X1220244Y-258703D01*
G01X1219239Y-244678D02*
X1218485Y-244432D01*
G01X1213710Y-251567D02*
X1215218Y-251813D01*
G01X1218485Y-245662D02*
X1216977Y-245416D01*
G01X1213710Y-252798D02*
X1214967Y-253044D01*
G01X1218485Y-244432D02*
X1217229Y-244185D01*
G01X1213710Y-244432D02*
X1212956Y-244678D01*
G01X1218485Y-252798D02*
X1219239Y-252552D01*
G01X1210192Y-258211D02*
X1211449D01*
G01Y-256243D02*
X1210192D01*
G01Y-255012D02*
X1211449D01*
G01X1214967Y-253044D02*
X1217229D01*
G01X1215218Y-251813D02*
X1216977D01*
G01Y-245416D02*
X1215218D01*
G01X1217229Y-244185D02*
X1214967D01*
G01X1217229Y-253044D02*
X1218485Y-252798D01*
G01X1216977Y-251813D02*
X1218485Y-251567D01*
G01X1215218Y-245416D02*
X1213710Y-245662D01*
G01X1214967Y-244185D02*
X1213710Y-244432D01*
G01X1210192Y-235081D02*
Y-233605D01*
G01Y-226715D02*
Y-225239D01*
G01X1215721Y-233605D02*
Y-226715D01*
G01X1217229D02*
Y-233605D01*
G01X1222003Y-225239D02*
Y-226715D01*
G01Y-233605D02*
Y-235081D01*
G01D02*
X1210192D01*
G01Y-233605D02*
X1215721D01*
G01X1217229D02*
X1222003D01*
G01Y-226715D02*
X1217229D01*
G01X1215721D02*
X1210192D01*
G01Y-225239D02*
X1222003D01*
G01X1284444Y-83624D02*
X1225389D01*
G01Y-10256D02*
G03Y51117I17716J30686D01*
G01X1250389Y20430D02*
G03I-7284J0D01*
G01X1246156Y2714D02*
G03I-3051J0D01*
G01X1247239Y38147D02*
G03I-4134J0D01*
G01X1213578Y73856D02*
X1532485D01*
G01X1213578D02*
X1532485D01*
G01X1213578D02*
G03X1205704Y65982I0J-7874D01*
G01X1213578Y73856D02*
G03X1205704Y65982I0J-7874D01*
G01X1253198Y54396D02*
X1300016Y211960D01*
G01X1215878Y420289D02*
Y381313D01*
G01X1235563Y987218D02*
Y416352D01*
G01X2034776D02*
X1223752D01*
G01X1235563D02*
X1223752D01*
G01X1215878Y424226D02*
G03X1223752Y416352I7874J0D01*
G01X1215878Y424226D02*
G03X1223752Y416352I7874J0D01*
G01X1215878Y424226D02*
Y979344D01*
G01Y424226D02*
Y979344D01*
G01X1219658Y704935D02*
Y706165D01*
G01Y708872D02*
Y710102D01*
G01Y712809D02*
Y714039D01*
G01Y716008D02*
Y717238D01*
G01Y719945D02*
Y721175D01*
G01Y723882D02*
Y725112D01*
G01Y727080D02*
Y735939D01*
G01X1220914Y733970D02*
Y727080D01*
G01X1226694Y707149D02*
Y707887D01*
G01Y711086D02*
Y711578D01*
G01Y718222D02*
Y718960D01*
G01Y722159D02*
Y722651D01*
G01X1227699Y725112D02*
Y723882D01*
G01Y722651D02*
Y721667D01*
G01Y718714D02*
Y717730D01*
G01Y714039D02*
Y712809D01*
G01Y711578D02*
Y710594D01*
G01Y707641D02*
Y706657D01*
G01X1230212Y731017D02*
Y732002D01*
G01X1231469Y731756D02*
Y730771D01*
G01D02*
X1231217Y729295D01*
G01X1229961Y729787D02*
X1230212Y731017D01*
G01X1227699Y721667D02*
X1227448Y720929D01*
G01X1227699Y717730D02*
X1227448Y716992D01*
G01X1227699Y710594D02*
X1227448Y709856D01*
G01X1227699Y706657D02*
X1227448Y705919D01*
G01X1226443Y721667D02*
X1226694Y722159D01*
G01X1231217Y729295D02*
X1230715Y728311D01*
G01X1226443Y717730D02*
X1226694Y718222D01*
G01X1230212Y732002D02*
X1229961Y733232D01*
G01X1231217Y733478D02*
X1231469Y731756D01*
G01X1226443Y710594D02*
X1226694Y711086D01*
G01X1226443Y706657D02*
X1226694Y707149D01*
G01X1229458Y729049D02*
X1229961Y729787D01*
G01X1226694Y707887D02*
X1226443Y708380D01*
G01X1226694Y718960D02*
X1226443Y719452D01*
G01X1227448Y708380D02*
X1227699Y707641D01*
G01X1226694Y711578D02*
X1226443Y712317D01*
G01X1227448D02*
X1227699Y711578D01*
G01X1227448Y719452D02*
X1227699Y718714D01*
G01X1226694Y722651D02*
X1226443Y723389D01*
G01X1227448D02*
X1227699Y722651D01*
G01X1230715Y728311D02*
X1229709Y727326D01*
G01X1226191Y721421D02*
X1226443Y721667D01*
G01X1227448Y720929D02*
X1226694Y720191D01*
G01X1226191Y717484D02*
X1226443Y717730D01*
G01X1227448Y716992D02*
X1226945Y716500D01*
G01X1226191Y710348D02*
X1226443Y710594D01*
G01X1227448Y709856D02*
X1226694Y709118D01*
G01X1226191Y706411D02*
X1226443Y706657D01*
G01X1227448Y705919D02*
X1226945Y705427D01*
G01X1228704Y728557D02*
X1229458Y729049D01*
G01X1226443Y708380D02*
X1226191Y708626D01*
G01X1226694Y709118D02*
X1227448Y708380D01*
G01X1226443Y712317D02*
X1225940Y712809D01*
G01X1226945D02*
X1227448Y712317D01*
G01X1226443Y719452D02*
X1226191Y719698D01*
G01X1226694Y720191D02*
X1227448Y719452D01*
G01X1226443Y723389D02*
X1225940Y723882D01*
G01X1226945D02*
X1227448Y723389D01*
G01X1220914Y735939D02*
X1227197Y729049D01*
G01X1226443Y727819D02*
X1220914Y733970D01*
G01X1225689Y721175D02*
X1226191Y721421D01*
G01X1225689Y717238D02*
X1226191Y717484D01*
G01X1225689Y710102D02*
X1226191Y710348D01*
G01X1225689Y706165D02*
X1226191Y706411D01*
G01X1226945Y716500D02*
X1225689Y716008D01*
G01X1226945Y705427D02*
X1225689Y704935D01*
G01X1227197Y727326D02*
X1226443Y727819D01*
G01X1226191Y708626D02*
X1225689Y708872D01*
G01X1226191Y719698D02*
X1225689Y719945D01*
G01X1227197Y729049D02*
X1228202Y728557D01*
G01Y727080D02*
X1227197Y727326D01*
G01X1225689Y704935D02*
X1219658D01*
G01Y706165D02*
X1225689D01*
G01Y708872D02*
X1219658D01*
G01Y710102D02*
X1225689D01*
G01X1227699Y712809D02*
X1226945D01*
G01X1225940D02*
X1219658D01*
G01Y714039D02*
X1227699D01*
G01X1225689Y716008D02*
X1219658D01*
G01Y717238D02*
X1225689D01*
G01Y719945D02*
X1219658D01*
G01Y721175D02*
X1225689D01*
G01X1227699Y723882D02*
X1226945D01*
G01X1225940D02*
X1219658D01*
G01Y725112D02*
X1227699D01*
G01X1228704Y727080D02*
X1228202D01*
G01X1220914D02*
X1219658D01*
G01X1228202Y728557D02*
X1228704D01*
G01X1229709Y727326D02*
X1228704Y727080D01*
G01X1230715Y734462D02*
X1231217Y733478D01*
G01X1229961Y733232D02*
X1229458Y733970D01*
G01D02*
X1228704Y734462D01*
G01X1219658Y737907D02*
Y739137D01*
G01Y759069D02*
Y760545D01*
G01X1219909Y747011D02*
X1219658Y745535D01*
G01X1221165Y746765D02*
X1220914Y745535D01*
G01Y739137D02*
Y737907D01*
G01X1225186Y760545D02*
Y767435D01*
G01X1226694D02*
Y760545D01*
G01X1228704Y734462D02*
Y735693D01*
G01X1231469Y760545D02*
Y759069D01*
G01X1231217Y744059D02*
X1231469Y745535D01*
G01X1229961Y744305D02*
X1230212Y745535D01*
G01X1225689Y755378D02*
X1223930Y751933D01*
G01X1223176Y752425D02*
X1225689Y757100D01*
G01X1220663Y748242D02*
X1219909Y747011D01*
G01X1221668Y747504D02*
X1221165Y746765D01*
G01X1220914Y745535D02*
X1221165Y744305D01*
G01X1230212Y745535D02*
X1229961Y746765D01*
G01X1219658Y745535D02*
X1219909Y744059D01*
G01X1231469Y745535D02*
X1231217Y747011D01*
G01X1230463Y742828D02*
X1231217Y744059D01*
G01X1229458Y743567D02*
X1229961Y744305D01*
G01X1221417Y748980D02*
X1220663Y748242D01*
G01X1229709Y742090D02*
X1230463Y742828D01*
G01X1219909Y744059D02*
X1220663Y742828D01*
G01X1225689Y757100D02*
X1228202Y752425D01*
G01X1227448Y751933D02*
X1225689Y755378D01*
G01X1228202Y752425D02*
X1227448Y751933D01*
G01X1223176Y748488D02*
X1221668Y747504D01*
G01X1227950Y742582D02*
X1229458Y743567D01*
G01X1221165Y744305D02*
X1221668Y743567D01*
G01X1229961Y746765D02*
X1229458Y747504D01*
G01X1231217Y747011D02*
X1230463Y748242D01*
G01X1222422Y749472D02*
X1221417Y748980D01*
G01X1220663Y742828D02*
X1221417Y742090D01*
G01X1229709Y735446D02*
X1230715Y734462D01*
G01X1228704Y741598D02*
X1229709Y742090D01*
G01X1230463Y748242D02*
X1229709Y748980D01*
G01X1223176Y749718D02*
X1222422Y749472D01*
G01X1227950Y741352D02*
X1228704Y741598D01*
G01X1221668Y743567D02*
X1223176Y742582D01*
G01X1229458Y747504D02*
X1227950Y748488D01*
G01X1223930Y751933D02*
X1223176Y752425D01*
G01X1221417Y742090D02*
X1222422Y741598D01*
G01X1229709Y748980D02*
X1228704Y749472D01*
G01X1222422Y741598D02*
X1223176Y741352D01*
G01X1228704Y735693D02*
X1229709Y735446D01*
G01X1228704Y749472D02*
X1227950Y749718D01*
G01X1223176Y742582D02*
X1224684Y742336D01*
G01X1223176Y741352D02*
X1224432Y741106D01*
G01X1227950Y749718D02*
X1226694Y749964D01*
G01X1227950Y748488D02*
X1226443Y748734D01*
G01X1219658Y735939D02*
X1220914D01*
G01Y737907D02*
X1219658D01*
G01Y739137D02*
X1220914D01*
G01X1224432Y741106D02*
X1226694D01*
G01X1224684Y742336D02*
X1226443D01*
G01Y748734D02*
X1224684D01*
G01X1226694Y749964D02*
X1224432D01*
G01X1231469Y759069D02*
X1219658D01*
G01Y760545D02*
X1225186D01*
G01X1226694D02*
X1231469D01*
G01X1226694Y741106D02*
X1227950Y741352D01*
G01X1226443Y742336D02*
X1227950Y742582D01*
G01X1224684Y748734D02*
X1223176Y748488D01*
G01X1224432Y749964D02*
X1223176Y749718D01*
G01X1219658Y767435D02*
Y768911D01*
G01X1231469D02*
Y767435D01*
G01D02*
X1226694D01*
G01X1225186D02*
X1219658D01*
G01Y768911D02*
X1231469D01*
G01X1294618Y829738D02*
X1235563D01*
G01X1320419Y941834D02*
G03I-62711J0D01*
G01X1235563Y964479D02*
Y903107D01*
G01Y964479D02*
Y903107D01*
G01D02*
G03Y964479I17716J30686D01*
G01Y903107D02*
G03Y964479I17716J30686D01*
G01Y903107D02*
G03Y964479I17716J30686D01*
G01X1253280Y920013D02*
Y1022258D01*
G01X1256331Y916077D02*
G03I-3051J0D01*
G01D02*
G03I-3051J0D01*
G01X1223752Y987218D02*
G03X1215878Y979344I0J-7874D01*
G01X1223752Y987218D02*
G03X1215878Y979344I0J-7874D01*
G01X1260563Y933793D02*
G03I-7283J0D01*
G01D02*
G03I-7283J0D01*
G01X1257413Y951510D02*
G03I-4133J0D01*
G01D02*
G03I-4133J0D01*
G01X1223752Y987218D02*
X1542659D01*
G01X1223752D02*
X1542659D01*
G01X1335550Y-457936D02*
G03I-13780J0D01*
G01X1326511Y-482444D02*
G03I-4744J0D01*
G01X1326786Y-457955D02*
G03I-5019J0D01*
G01X1299409Y-229612D02*
Y-251183D01*
G01X1303809D02*
Y-229612D01*
G01X1313490D02*
Y-251183D01*
G01X1299409D02*
X1303809D01*
G01X1313490D02*
X1317891D01*
G01X1301169Y-225118D02*
X1299409Y-229612D01*
G01X1303809D02*
X1304689Y-227815D01*
G01X1312610D02*
X1313490Y-229612D01*
G01X1311730Y-226916D02*
X1312610Y-227815D01*
G01X1302929Y-223321D02*
X1301169Y-225118D01*
G01X1304689Y-227815D02*
X1305569Y-226916D01*
G01X1317010Y-223321D02*
X1314370Y-226017D01*
G01D02*
X1311730Y-223321D01*
G01X1309970Y-226017D02*
X1311730Y-226916D01*
G01X1305569D02*
X1307330Y-226017D01*
G01X1311730Y-223321D02*
X1309090Y-222422D01*
G01X1305569D02*
X1302929Y-223321D01*
G01X1307330Y-226017D02*
X1309970D01*
G01X1309090Y-222422D02*
X1305569D01*
G01X1317891Y-251183D02*
Y-229612D01*
G01D02*
X1318771Y-227815D01*
G01X1319651Y-222422D02*
X1317010Y-223321D01*
G01X1284444Y-4884D02*
Y-83624D01*
G01X1540359Y-4884D02*
X1284444D01*
G01X1300016Y211960D02*
X1310552D01*
G01D02*
X1690211D01*
G01X1294618Y908478D02*
Y829738D01*
G01X1550534Y908478D02*
X1294618D01*
G01X1311350Y878758D02*
X1310957Y876982D01*
G01X1302787Y878557D02*
X1304756Y880525D01*
G01X1301213Y876982D02*
Y900604D01*
G01X1302787Y882887D02*
Y878557D01*
G01X1304461Y897848D02*
Y879738D01*
G01X1304756Y897061D02*
Y880525D01*
G01X1305740Y879541D02*
Y880525D01*
G01X1307610Y879738D02*
Y897848D01*
G01X1309382Y885840D02*
Y878758D01*
G01X1311350D02*
Y885840D01*
G01X1313122Y887472D02*
Y879738D01*
G01X1315484D02*
Y887472D01*
G01X1317256Y885840D02*
Y878758D01*
G01X1309382D02*
X1309776Y876982D01*
G01X1317256Y878758D02*
X1317650Y876982D01*
G01X1366764D02*
X1301213D01*
G01X1365189Y878557D02*
X1302787D01*
G01X1309382Y878758D02*
X1311350D01*
G01X1317256D02*
X1319224D01*
G01X1317256Y879541D02*
X1305740D01*
G01X1363516Y879738D02*
X1304461D01*
G01X1319224Y880525D02*
X1317256D01*
G01X1305740D02*
X1304756D01*
G01X1313122Y882376D02*
X1307610D01*
G01X1315484D02*
X1320996D01*
G01X1308634Y890998D02*
X1309776Y892139D01*
G01X1310957Y893321D02*
X1312098Y894462D01*
G01X1302787Y882887D02*
X1304756Y884856D01*
G01X1309776Y900604D02*
X1309382Y898828D01*
G01X1317650Y900604D02*
X1317256Y898828D01*
G01X1308634Y883124D02*
X1309776Y884265D01*
G01X1310957Y885446D02*
X1312098Y886588D01*
G01X1316508Y890998D02*
X1317650Y892139D01*
G01X1316508Y883124D02*
X1317650Y884265D01*
G01X1302787Y890761D02*
Y899029D01*
G01X1305740Y897061D02*
Y898045D01*
G01X1308634Y894462D02*
Y890998D01*
G01Y886588D02*
Y883124D01*
G01X1309382Y898828D02*
Y891746D01*
G01X1309776Y893321D02*
Y892139D01*
G01Y885446D02*
Y884265D01*
G01X1310957D02*
Y885446D01*
G01Y892139D02*
Y893321D01*
G01X1311350Y898828D02*
Y891746D01*
G01X1312098Y883124D02*
Y886588D01*
G01Y890998D02*
Y894462D01*
G01X1313122Y897848D02*
Y890114D01*
G01Y889777D02*
Y887809D01*
G01X1313516Y898045D02*
Y900604D01*
G01X1315484Y887809D02*
Y889777D01*
G01Y890114D02*
Y897848D01*
G01X1316508Y894462D02*
Y890998D01*
G01Y886588D02*
Y883124D01*
G01X1317256Y898828D02*
Y891746D01*
G01X1317650Y893321D02*
Y892139D01*
G01Y885446D02*
Y884265D01*
G01X1310957Y900604D02*
X1311350Y898828D01*
G01X1304756Y888793D02*
X1302787Y890761D01*
G01X1310957Y884265D02*
X1312098Y883124D01*
G01X1309776Y885446D02*
X1308634Y886588D01*
G01X1304756Y897061D02*
X1302787Y899029D01*
G01X1317650Y885446D02*
X1316508Y886588D01*
G01X1312098Y890998D02*
X1310957Y892139D01*
G01X1309776Y893321D02*
X1308634Y894462D01*
G01X1317650Y893321D02*
X1316508Y894462D01*
G01X1301213Y882887D02*
X1302787D01*
G01X1309382D02*
X1311350D01*
G01X1317256D02*
X1319224D01*
G01X1308634Y883124D02*
X1312098D01*
G01X1316508D02*
X1319972D01*
G01X1319224Y883872D02*
X1317256D01*
G01X1311350D02*
X1309382D01*
G01X1309776Y884265D02*
X1310957D01*
G01X1317650D02*
X1318831D01*
G01X1301213Y884856D02*
X1304756D01*
G01X1318831Y885446D02*
X1317650D01*
G01X1310957D02*
X1309776D01*
G01X1319224Y885840D02*
X1317256D01*
G01X1311350D02*
X1309382D01*
G01X1319972Y886588D02*
X1316508D01*
G01X1312098D02*
X1308634D01*
G01X1320996Y887809D02*
X1315484D01*
G01X1313122D02*
X1307610D01*
G01X1301213Y888793D02*
X1304756D01*
G01X1320996Y889777D02*
X1315484D01*
G01X1313122D02*
X1307610D01*
G01X1301213Y890761D02*
X1302787D01*
G01X1308634Y890998D02*
X1312098D01*
G01X1316508D02*
X1319972D01*
G01X1319224Y891746D02*
X1317256D01*
G01X1311350D02*
X1309382D01*
G01X1309776Y892139D02*
X1310957D01*
G01X1317650D02*
X1318831D01*
G01Y893321D02*
X1317650D01*
G01X1310957D02*
X1309776D01*
G01X1319224Y893714D02*
X1317256D01*
G01X1311350D02*
X1309382D01*
G01X1319972Y894462D02*
X1316508D01*
G01X1312098D02*
X1308634D01*
G01X1319224Y894698D02*
X1317256D01*
G01X1311350D02*
X1309382D01*
G01X1313122Y895210D02*
X1307610D01*
G01X1315484D02*
X1320996D01*
G01X1311350Y897061D02*
X1309382D01*
G01X1305740D02*
X1304756D01*
G01X1363516Y897848D02*
X1304461D01*
G01X1309382Y898045D02*
X1305740D01*
G01X1311350D02*
X1325130D01*
G01X1319224Y898828D02*
X1317256D01*
G01X1311350D02*
X1309382D01*
G01X1302787Y899029D02*
X1327295D01*
G01X1322965Y899423D02*
X1313516D01*
G01Y899817D02*
X1322965D01*
G01X1301213Y900604D02*
X1366764D01*
G01X1316075Y888793D02*
G03I-1772J0D01*
G01X1315681D02*
G03I-1378J0D01*
G01X1321767Y-486380D02*
Y-564169D01*
G01X1324993Y-485922D02*
X1371782Y-536380D01*
G01D02*
X1374931D01*
G01D02*
X1481755D01*
G01X1326232Y-455663D02*
X1368295Y-434067D01*
G01X1325312Y-444619D02*
X1340587Y-387185D01*
G01D02*
X1343737D01*
G01D02*
X1590876D01*
G01X1368295Y-434067D02*
X1371445D01*
G01D02*
X1478269D01*
G01X1327571Y-228713D02*
Y-251183D01*
G01X1331972D02*
Y-222422D01*
G01X1339013Y-229612D02*
Y-251183D01*
G01X1343413D02*
Y-229612D01*
G01X1327571Y-251183D02*
X1331972D01*
G01X1339013D02*
X1343413D01*
G01X1327571Y-222422D02*
Y-225118D01*
G01X1340773D02*
X1339013Y-229612D01*
G01X1343413D02*
X1344293Y-227815D01*
G01X1318771D02*
X1319651Y-226916D01*
G01X1325811D02*
X1327571Y-228713D01*
G01Y-225118D02*
X1325811Y-223321D01*
G01X1342533D02*
X1340773Y-225118D01*
G01X1344293Y-227815D02*
X1345173Y-226916D01*
G01X1319651D02*
X1321411Y-226017D01*
G01X1345173Y-226916D02*
X1346933Y-226017D01*
G01X1323171D02*
X1325811Y-226916D01*
G01Y-223321D02*
X1323171Y-222422D01*
G01X1345173D02*
X1342533Y-223321D01*
G01X1321411Y-226017D02*
X1323171D01*
G01X1348693Y-222422D02*
X1345173D01*
G01X1331972D02*
X1327571D01*
G01X1323171D02*
X1319651D01*
G01X1353094Y-229612D02*
Y-251183D01*
G01X1357494D02*
Y-229612D01*
G01X1367175Y-228713D02*
Y-251183D01*
G01X1371576D02*
Y-222422D01*
G01X1353094Y-251183D02*
X1357494D01*
G01X1367175D02*
X1371576D01*
G01X1367175Y-222422D02*
Y-225118D01*
G01X1352214Y-227815D02*
X1353094Y-229612D01*
G01X1357494D02*
X1358375Y-227815D01*
G01X1351334Y-226916D02*
X1352214Y-227815D01*
G01X1353974Y-226017D02*
X1351334Y-223321D01*
G01X1356614D02*
X1353974Y-226017D01*
G01X1358375Y-227815D02*
X1359254Y-226916D01*
G01X1365415D02*
X1367175Y-228713D01*
G01Y-225118D02*
X1365415Y-223321D01*
G01X1349574Y-226017D02*
X1351334Y-226916D01*
G01X1359254D02*
X1361015Y-226017D01*
G01X1351334Y-223321D02*
X1348693Y-222422D01*
G01X1362775Y-226017D02*
X1365415Y-226916D01*
G01X1359254Y-222422D02*
X1356614Y-223321D01*
G01X1365415D02*
X1362775Y-222422D01*
G01X1346933Y-226017D02*
X1349574D01*
G01X1361015D02*
X1362775D01*
G01X1371576Y-222422D02*
X1367175D01*
G01X1362775D02*
X1359254D01*
G01X1380377Y-243993D02*
X1378616Y-239499D01*
G01D02*
Y-235904D01*
G01D02*
X1380377Y-231410D01*
G01X1338600Y45450D02*
X1339139Y46550D01*
G01X1338061Y49302D02*
X1336983Y48202D01*
G01X1339139Y46550D02*
X1339678Y47101D01*
G01X1346683Y49302D02*
X1345067Y47651D01*
G01X1336983Y48202D02*
X1335906Y45450D01*
G01X1339678Y47101D02*
X1340756Y47651D01*
G01X1339678Y49852D02*
X1338061Y49302D01*
G01X1335906Y45450D02*
Y32242D01*
G01X1338600D02*
Y45450D01*
G01X1344528D02*
Y32242D01*
G01X1343989Y46550D02*
X1344528Y45450D01*
G01X1343450Y47101D02*
X1343989Y46550D01*
G01X1345067Y47651D02*
X1343450Y49302D01*
G01X1342372Y47651D02*
X1343450Y47101D01*
G01Y49302D02*
X1341833Y49852D01*
G01X1335906Y32242D02*
X1338600D01*
G01X1344528D02*
X1347222D01*
G01X1340756Y47651D02*
X1342372D01*
G01X1341833Y49852D02*
X1339678D01*
G01X1347761Y46550D02*
X1348300Y47101D01*
G01X1362311Y49302D02*
X1361233Y48202D01*
G01D02*
X1360155Y45450D01*
G01X1347222D02*
X1347761Y46550D01*
G01X1362849Y45450D02*
X1363388Y46550D01*
G01X1371471Y45450D02*
X1372010Y46550D01*
G01X1363388D02*
X1363927Y47101D01*
G01X1370933Y49302D02*
X1369316Y47651D01*
G01X1372010Y46550D02*
X1372549Y47101D01*
G01X1348300D02*
X1349378Y47651D01*
G01X1363927Y47101D02*
X1365005Y47651D01*
G01X1372549Y47101D02*
X1373627Y47651D01*
G01X1348300Y49852D02*
X1346683Y49302D01*
G01X1363927Y49852D02*
X1362311Y49302D01*
G01X1372549Y49852D02*
X1370933Y49302D01*
G01X1347222Y32242D02*
Y45450D01*
G01X1353150Y49852D02*
Y48202D01*
G01Y46000D02*
Y32242D01*
G01X1355844D02*
Y49852D01*
G01X1360155Y45450D02*
Y32242D01*
G01X1362849D02*
Y45450D01*
G01X1368777D02*
Y32242D01*
G01X1371471D02*
Y45450D01*
G01X1368238Y46550D02*
X1368777Y45450D01*
G01X1352072Y47101D02*
X1353150Y46000D01*
G01Y48202D02*
X1352072Y49302D01*
G01X1367699Y47101D02*
X1368238Y46550D01*
G01X1369316Y47651D02*
X1367699Y49302D01*
G01X1366622Y47651D02*
X1367699Y47101D01*
G01X1350455Y47651D02*
X1352072Y47101D01*
G01Y49302D02*
X1350455Y49852D01*
G01X1367699Y49302D02*
X1366083Y49852D01*
G01X1374705Y47651D02*
X1376321Y47101D01*
G01Y49302D02*
X1374705Y49852D01*
G01X1353150Y32242D02*
X1355844D01*
G01X1360155D02*
X1362849D01*
G01X1368777D02*
X1371471D01*
G01X1349378Y47651D02*
X1350455D01*
G01X1365005D02*
X1366622D01*
G01X1373627D02*
X1374705D01*
G01Y49852D02*
X1372549D01*
G01X1366083D02*
X1363927D01*
G01X1355844D02*
X1353150D01*
G01X1350455D02*
X1348300D01*
G01X1377399D02*
Y48202D01*
G01Y46000D02*
Y32242D01*
G01X1380093D02*
Y49852D01*
G01X1376321Y47101D02*
X1377399Y46000D01*
G01Y48202D02*
X1376321Y49302D01*
G01X1377399Y32242D02*
X1380093D01*
G01Y49852D02*
X1377399D01*
G01X1321366Y385053D02*
X1318807Y387612D01*
G01Y393911D02*
X1319791Y392927D01*
G01X1318807Y479049D02*
Y387612D01*
G01X1319791Y400801D02*
Y392927D01*
G01X1322350Y400801D02*
Y391943D01*
G01X1324425Y402376D02*
Y474128D01*
G01X1325055Y409462D02*
Y385053D01*
G01X1325333Y409462D02*
Y385053D01*
G01X1342287D02*
X1321366D01*
G01X1344846Y387612D02*
X1318807D01*
G01X1322350Y391943D02*
X1318807D01*
G01X1321366Y392927D02*
X1319791D01*
G01X1341303Y399817D02*
X1322350D01*
G01X1344846Y400801D02*
X1318807D01*
G01X1324425Y402376D02*
X1339464D01*
G01X1324425D02*
X1322850Y400801D01*
G01X1322350Y393911D02*
X1321366Y392927D01*
G01X1325005Y420832D02*
X1324661Y421176D01*
G01X1325448Y421962D02*
X1325792Y421619D01*
G01X1324661Y416844D02*
X1324700Y416600D01*
X1324811Y416381D01*
X1324985Y416207D01*
X1325205Y416095D01*
X1325448Y416057D01*
G01X1325792Y416400D02*
X1325548Y416439D01*
X1325329Y416551D01*
X1325155Y416725D01*
X1325043Y416944D01*
X1325005Y417187D01*
G01X1324661Y421176D02*
Y416844D01*
G01X1325005Y417187D02*
Y420832D01*
G01X1344846Y403360D02*
X1318807D01*
G01X1325074Y409462D02*
X1330763D01*
G01X1344846Y415171D02*
X1318807D01*
G01X1325448Y416057D02*
X1338441D01*
G01Y421962D02*
X1325448D01*
G01X1325792Y421619D02*
X1325548Y421580D01*
X1325329Y421468D01*
X1325155Y421295D01*
X1325043Y421076D01*
X1325005Y420832D01*
G01X1325448Y421962D02*
X1325205Y421924D01*
X1324985Y421812D01*
X1324811Y421638D01*
X1324700Y421419D01*
X1324661Y421176D01*
G01X1325900Y410053D02*
X1325789Y410042D01*
X1325684Y410008D01*
X1325586Y409954D01*
X1325499Y409880D01*
X1325428Y409791D01*
X1325376Y409689D01*
X1325344Y409579D01*
X1325333Y409462D01*
G01X1324661Y416844D02*
X1325005Y417187D01*
G01X1325792Y416400D02*
X1325448Y416057D01*
G01X1325645Y410053D02*
G03X1325055Y409462I0J-590D01*
G01X1339819Y430919D02*
G03I-7875J0D01*
G01X1381331Y368321D02*
X1354362D01*
G01Y479049D02*
Y368321D01*
G01X1356528Y369502D02*
X1355347Y368321D01*
G01X1342287Y392927D02*
X1341303Y393911D01*
G01X1339464Y402376D02*
X1341039Y400801D01*
G01X1325900Y410053D02*
Y385053D01*
G01X1330763D02*
Y410053D01*
G01X1333126Y385053D02*
Y410053D01*
G01X1337989D02*
Y385053D01*
G01X1338556Y409462D02*
Y385053D01*
G01X1338834Y409462D02*
Y385053D01*
G01X1339464Y402376D02*
Y474128D01*
G01X1341303Y391943D02*
Y400801D01*
G01X1343862D02*
Y392927D01*
G01X1344846Y387612D02*
Y479049D01*
G01Y391943D02*
X1341303D01*
G01X1343862Y392927D02*
X1342287D01*
G01X1343862D02*
X1344846Y393911D01*
G01Y387612D02*
X1342287Y385053D01*
G01X1338441Y416057D02*
X1338097Y416400D01*
G01X1338884Y417187D02*
X1339228Y416844D01*
G01Y421176D02*
X1339189Y421419D01*
X1339078Y421638D01*
X1338904Y421812D01*
X1338684Y421924D01*
X1338441Y421962D01*
G01X1338884Y420832D02*
Y417187D01*
G01X1339228Y416844D02*
Y421176D01*
G01X1337989Y410053D02*
X1338100Y410042D01*
X1338205Y410008D01*
X1338303Y409954D01*
X1338390Y409880D01*
X1338460Y409791D01*
X1338513Y409689D01*
X1338545Y409579D01*
X1338556Y409462D01*
G01X1338097Y421619D02*
X1338341Y421580D01*
X1338560Y421469D01*
X1338734Y421295D01*
X1338846Y421075D01*
X1338884Y420832D01*
G01Y417187D02*
X1338846Y416944D01*
X1338734Y416725D01*
X1338560Y416551D01*
X1338341Y416439D01*
X1338097Y416400D01*
G01X1333126Y409462D02*
X1338815D01*
G01X1330763Y410053D02*
X1325662D01*
G01X1333126D02*
X1338243D01*
G01X1381331Y415171D02*
X1354362D01*
G01X1338097Y416400D02*
X1325792D01*
G01X1338097Y421619D02*
X1325792D01*
G01X1338441Y416057D02*
X1338684Y416095D01*
X1338904Y416207D01*
X1339078Y416381D01*
X1339189Y416600D01*
X1339228Y416844D01*
G01X1338097Y421619D02*
X1338441Y421962D01*
G01X1339228Y421176D02*
X1338884Y420832D01*
G01X1338834Y409462D02*
G03X1338244Y410053I-590J1D01*
G01X1379165Y369502D02*
X1380347Y368321D01*
G01X1375721Y368911D02*
X1372571D01*
G01X1363122D02*
X1359972D01*
G01X1379165Y369502D02*
X1375721D01*
G01X1372571D02*
X1363122D01*
G01X1359972D02*
X1356528D01*
G01X1356331Y406636D02*
Y368321D01*
G01X1356528Y407030D02*
Y369502D01*
G01X1356724Y407030D02*
Y368321D01*
G01X1359972Y376195D02*
Y368911D01*
G01X1363122Y376195D02*
Y368911D01*
G01X1372571Y376195D02*
Y368911D01*
G01X1375721Y376195D02*
Y368911D01*
G01X1378969Y407030D02*
Y368321D01*
G01X1379165Y407030D02*
Y369502D01*
G01X1379362Y406636D02*
Y368321D01*
G01X1375721Y376195D02*
X1372571D01*
G01X1363122D02*
X1359972D01*
G01X1356331Y406636D02*
X1379362D01*
G01X1379165Y407030D02*
X1356528D01*
G01X1356724D02*
G03X1356331Y406636I1J-394D01*
G01X1379362D02*
G03X1378969Y407030I-394J0D01*
G01X1325005Y446816D02*
X1324661Y447160D01*
G01X1325448Y447946D02*
X1325792Y447603D01*
G01X1324149Y439679D02*
X1322761Y442083D01*
G01X1321945Y456273D02*
X1322732Y454909D01*
G01X1318204Y458960D02*
Y476490D01*
G01X1319661Y454909D02*
Y437966D01*
G01X1322732Y454909D02*
Y437966D01*
G01X1322761Y442083D02*
Y455830D01*
G01X1324661Y440859D02*
X1324700Y440616D01*
X1324811Y440397D01*
X1324985Y440223D01*
X1325205Y440111D01*
X1325448Y440072D01*
G01X1324661Y447160D02*
Y440859D01*
G01X1325005Y441203D02*
Y446816D01*
G01X1325792Y440416D02*
X1325548Y440455D01*
X1325329Y440567D01*
X1325155Y440741D01*
X1325043Y440960D01*
X1325005Y441203D01*
G01Y446816D02*
X1325043Y447059D01*
X1325155Y447279D01*
X1325329Y447453D01*
X1325548Y447565D01*
X1325792Y447603D01*
G01X1326748Y437966D02*
X1322732D01*
G01X1319661D02*
X1318807D01*
G01X1325330Y439679D02*
X1324149D01*
G01X1325448Y440072D02*
X1338441D01*
G01X1322968Y441725D02*
X1326511D01*
G01X1338441Y447946D02*
X1325448D01*
G01X1321945Y456273D02*
X1320448D01*
G01X1321197Y457395D02*
X1319769D01*
G01X1344846Y458869D02*
X1318807D01*
G01X1344846Y461391D02*
X1318807D01*
G01X1325448Y447946D02*
X1325205Y447908D01*
X1324985Y447796D01*
X1324811Y447622D01*
X1324700Y447403D01*
X1324661Y447160D01*
G01X1320448Y456273D02*
X1319661Y454909D01*
G01X1326718Y442083D02*
X1325330Y439679D01*
G01X1324661Y440859D02*
X1325005Y441203D01*
G01X1325792Y440416D02*
X1325448Y440072D01*
G01X1340927Y455427D02*
G03I-8983J0D01*
G01X1322761Y455830D02*
G03X1321197Y457395I-1565J0D01*
G01X1323165Y463124D02*
G03I-1969J0D01*
G01X1318204Y458960D02*
G03X1319769Y457395I1565J0D01*
G01X1321945Y478261D02*
X1322732Y477474D01*
G01X1320002Y469403D02*
X1319785Y469684D01*
X1319661Y470000D01*
G01X1319632Y470661D02*
X1319676Y470205D01*
X1319805Y469774D01*
X1320002Y469403D01*
G01X1324845Y474128D02*
X1324842Y474173D01*
G01X1319632Y470242D02*
X1319639Y470118D01*
X1319661Y469995D01*
G01X1324672Y479049D02*
X1325153Y465269D01*
G01X1325940D02*
X1325459Y479049D01*
G01X1319632Y476490D02*
Y470242D01*
G01X1319661Y469206D02*
Y477474D01*
G01X1322732D02*
Y469206D01*
G01X1322761Y476490D02*
Y470242D01*
G01D02*
X1322754Y470119D01*
X1322732Y469995D01*
G01Y470000D02*
X1322606Y469682D01*
X1322391Y469403D01*
G01X1325153Y465269D02*
X1338736D01*
G01X1319661Y469206D02*
X1318807D01*
G01X1322732D02*
X1340921D01*
G01X1327089Y469403D02*
X1322391D01*
G01X1320002D02*
X1318204D01*
G01Y474128D02*
X1381433D01*
G01X1324802Y475309D02*
X1318807D01*
G01X1322391Y469403D02*
X1322588Y469774D01*
X1322717Y470205D01*
X1322761Y470661D01*
G01X1381433Y476490D02*
X1318204D01*
G01X1322732Y477474D02*
X1319661D01*
G01X1320448Y478261D02*
X1321945D01*
G01X1344846Y479049D02*
X1318807D01*
G01X1320448Y478261D02*
X1319661Y477474D01*
G01X1320002Y469403D02*
G03X1322391I1195J1012D01*
G01X1331388Y425641D02*
X1326666Y430362D01*
G01X1327084Y430780D02*
X1331805Y426058D01*
G01X1332084D02*
X1332501Y425641D01*
G01X1327084Y431058D02*
X1326666Y431476D01*
G01X1330370Y430919D02*
X1331945Y429344D01*
G01X1333519Y430919D02*
X1331945Y432494D01*
G01X1336805Y430780D02*
X1337223Y430362D01*
G01X1332084Y435780D02*
X1336805Y431058D01*
G01X1332501Y436198D02*
X1337223Y431476D01*
G01X1331945Y429344D02*
Y426001D01*
G01Y432494D02*
Y435837D01*
G01X1344374Y474128D02*
Y426883D01*
G01D02*
X1344846D01*
G01X1336863Y430919D02*
X1333519D01*
G01X1330370D02*
X1327026D01*
G01X1326666Y431476D02*
X1331388Y436198D01*
G01X1331805Y435780D02*
X1327084Y431058D01*
G01Y430780D02*
X1326666Y430362D01*
G01X1331945Y432494D02*
X1330370Y430919D01*
G01X1331945Y429344D02*
X1333519Y430919D01*
G01X1331805Y426058D02*
X1331388Y425641D01*
G01X1336805Y431058D02*
X1337223Y431476D01*
G01X1336805Y430780D02*
X1332084Y426058D01*
G01X1337223Y430362D02*
X1332501Y425641D01*
G01X1336685Y430919D02*
G03I-4744J0D01*
G01X1337223Y430362D02*
G03Y431476I-557J557D01*
G01X1331388Y425641D02*
G03X1332501I557J557D01*
G01X1326666Y431476D02*
G03Y430362I557J-557D01*
G01X1327084Y431058D02*
G03Y430780I139J-139D01*
G01X1331805Y426058D02*
G03X1332084I140J139D01*
G01X1336805Y430780D02*
G03Y431058I-139J139D01*
G01X1331805Y435780D02*
X1331388Y436198D01*
G01X1331236Y439679D02*
X1329848Y442083D01*
G01X1329805Y453287D02*
X1327745Y454477D01*
G01X1329845Y454952D02*
X1330875Y454357D01*
G01X1333014Y456497D02*
X1334045Y455902D01*
G01X1338441Y440072D02*
X1338097Y440416D01*
G01X1338884Y441203D02*
X1339228Y440859D01*
G01X1334084Y453287D02*
X1329805Y457567D01*
G01X1330995Y451227D02*
X1329805Y453287D01*
G01X1338322Y439679D02*
X1336935Y442083D01*
G01X1329031Y456273D02*
X1329819Y454909D01*
G01X1330875Y454357D02*
X1331469Y453327D01*
G01X1333014Y456497D02*
X1332419Y457527D01*
G01X1332895Y459627D02*
X1334084Y457567D01*
G01X1345409Y439679D02*
X1344021Y442083D01*
G01X1336118Y456273D02*
X1336905Y454909D01*
G01X1352496Y439679D02*
X1351108Y442083D01*
G01X1343204Y456273D02*
X1343992Y454909D01*
G01X1334084Y457567D02*
X1336145Y456377D01*
G01X1332895Y451227D02*
X1330995Y459627D01*
G01X1338884Y446816D02*
X1338845Y447060D01*
X1338734Y447279D01*
X1338560Y447452D01*
X1338341Y447564D01*
X1338097Y447603D01*
G01X1339228Y447160D02*
X1339189Y447403D01*
X1339078Y447622D01*
X1338904Y447796D01*
X1338684Y447908D01*
X1338441Y447946D01*
G01X1332874Y449458D02*
X1331015Y461396D01*
G01X1330995Y450740D02*
X1330997Y450307D01*
X1331004Y449878D01*
X1331015Y449458D01*
G01X1332895Y460114D02*
X1332892Y460547D01*
X1332885Y460976D01*
X1332874Y461396D01*
G01X1326718Y455830D02*
Y442083D01*
G01X1326748Y454909D02*
Y437966D01*
G01X1328895Y454952D02*
Y455902D01*
G01X1329819Y454909D02*
Y437966D01*
G01X1329848Y442083D02*
Y455830D01*
G01X1330995Y459627D02*
Y460114D01*
G01Y451227D02*
Y450740D01*
G01X1331469Y458477D02*
Y457527D01*
G01Y453327D02*
Y452377D01*
G01X1332419D02*
Y453327D01*
G01Y457527D02*
Y458477D01*
G01X1332895Y451227D02*
Y450740D01*
G01Y459627D02*
Y460114D01*
G01X1333805Y455830D02*
Y442083D01*
G01X1333834Y454909D02*
Y437966D01*
G01X1334995Y454952D02*
Y455902D01*
G01X1336905Y454909D02*
Y437966D01*
G01X1336935Y442083D02*
Y455830D01*
G01X1338884Y446816D02*
Y441203D01*
G01X1339228Y440859D02*
Y447160D01*
G01X1340891Y455830D02*
Y442083D01*
G01X1340921Y454909D02*
Y437966D01*
G01X1343992Y454909D02*
Y437966D01*
G01X1344021Y442083D02*
Y455830D01*
G01X1347978D02*
Y442083D01*
G01X1351108D02*
Y455830D01*
G01X1354996Y455283D02*
Y438551D01*
G01X1355065Y455830D02*
Y455352D01*
G01X1330995Y460114D02*
X1330997Y460548D01*
X1331004Y460977D01*
X1331015Y461396D01*
G01X1325975Y456357D02*
X1325964Y455737D01*
Y455117D01*
X1325975Y454497D01*
G01X1337913D02*
X1337924Y455117D01*
Y455737D01*
X1337913Y456357D01*
G01X1332874Y449458D02*
X1332885Y449878D01*
X1332892Y450307D01*
X1332895Y450740D01*
G01X1327745Y456377D02*
X1336145Y454477D01*
G01X1332874Y461396D02*
X1331015Y449458D01*
G01X1338884Y441203D02*
X1338846Y440960D01*
X1338734Y440741D01*
X1338560Y440567D01*
X1338341Y440455D01*
X1338097Y440416D01*
G01X1332895Y459627D02*
X1330995Y451227D01*
G01X1344846Y437966D02*
X1343992D01*
G01X1340921D02*
X1336905D01*
G01X1333834D02*
X1329819D01*
G01X1354996Y438551D02*
X1354362D01*
G01X1353677Y439679D02*
X1352496D01*
G01X1346590D02*
X1345409D01*
G01X1339504D02*
X1338322D01*
G01X1332417D02*
X1331236D01*
G01X1338097Y440416D02*
X1325792D01*
G01X1325975Y456357D02*
X1337913Y454497D01*
G01X1325975Y456357D02*
X1326395Y456368D01*
X1326823Y456375D01*
X1327258Y456377D01*
G01X1331015Y461396D02*
X1331324Y461403D01*
X1331634Y461407D01*
X1331945Y461408D01*
G01X1336632Y454477D02*
X1337065Y454479D01*
X1337493Y454486D01*
X1337913Y454497D01*
G01X1331945Y449445D02*
X1332254Y449447D01*
X1332564Y449451D01*
X1332874Y449458D01*
G01X1347771Y441725D02*
X1344228D01*
G01X1330055D02*
X1333598D01*
G01X1337141D02*
X1340685D01*
G01X1351315D02*
X1354858D01*
G01X1338097Y447603D02*
X1325792D01*
G01X1331469Y452377D02*
X1332419D01*
G01X1336145Y454477D02*
X1336632D01*
G01X1327745D02*
X1327258D01*
G01X1328895Y454952D02*
X1329845D01*
G01X1334045D02*
X1334995D01*
G01Y455902D02*
X1334045D01*
G01X1329845D02*
X1328895D01*
G01X1343204Y456273D02*
X1341708D01*
G01X1336118D02*
X1334622D01*
G01X1329031D02*
X1327535D01*
G01X1327745Y456377D02*
X1327258D01*
G01X1336145D02*
X1336632D01*
G01X1332419Y458477D02*
X1331469D01*
G01X1354362Y458802D02*
X1381331D01*
G01Y461189D02*
X1354362D01*
G01X1331015Y449458D02*
X1331324Y449451D01*
X1331634Y449447D01*
X1331945Y449445D01*
G01X1332874Y461396D02*
X1332564Y461403D01*
X1332254Y461407D01*
X1331945Y461408D01*
G01X1325975Y454497D02*
X1326395Y454486D01*
X1326824Y454479D01*
X1327258Y454477D01*
G01X1337913Y456357D02*
X1337493Y456368D01*
X1337065Y456375D01*
X1336632Y456377D01*
G01X1338441Y440072D02*
X1338684Y440111D01*
X1338904Y440223D01*
X1339078Y440397D01*
X1339189Y440616D01*
X1339228Y440859D01*
G01X1325975Y454497D02*
X1337913Y456357D01*
G01X1327535Y456273D02*
X1326748Y454909D01*
G01X1329805Y457567D02*
X1330995Y459627D01*
G01X1330875Y456497D02*
X1331469Y457527D01*
G01X1333014Y454357D02*
X1332419Y453327D01*
G01X1334622Y456273D02*
X1333834Y454909D01*
G01X1334084Y453287D02*
X1332895Y451227D01*
G01X1341708Y456273D02*
X1340921Y454909D01*
G01X1333805Y442083D02*
X1332417Y439679D01*
G01X1327745Y454477D02*
X1336145Y456377D01*
G01X1340891Y442083D02*
X1339504Y439679D01*
G01X1347978Y442083D02*
X1346590Y439679D01*
G01X1354996Y441963D02*
X1353677Y439679D01*
G01X1329805Y453287D02*
X1334084Y457567D01*
G01X1338097Y447603D02*
X1338441Y447946D01*
G01X1339228Y447160D02*
X1338884Y446816D01*
G01X1332501Y436198D02*
X1332084Y435780D01*
G01X1355980Y456268D02*
X1354996Y455283D01*
G01X1327745Y456377D02*
X1329805Y457567D01*
G01X1330875Y456497D02*
X1329845Y455902D01*
G01X1333014Y454357D02*
X1334045Y454952D01*
G01X1336145Y454477D02*
X1334084Y453287D01*
G01X1332501Y436198D02*
G03X1331388I-557J-557D01*
G01X1332084Y435780D02*
G03X1331805I-140J-139D01*
G01X1337210Y455427D02*
G03I-5266J0D01*
G01X1336961Y455407D02*
G03I-5020J0D01*
G01X1330995Y460114D02*
G03X1327258Y456377I950J-4687D01*
G01Y454477D02*
G03X1330995Y450740I4687J950D01*
G01X1332895D02*
G03X1336632Y454477I-950J4687D01*
G01Y456377D02*
G03X1332895Y460114I-4687J-950D01*
G01X1335635Y455427D02*
G03I-3691J0D01*
G01X1335576D02*
G03I-3632J0D01*
G01X1351108Y455830D02*
G03X1347978I-1565J0D01*
G01X1344021D02*
G03X1340891I-1565J0D01*
G01X1336935D02*
G03X1333805I-1565J0D01*
G01X1329848D02*
G03X1326718I-1565J0D01*
G01X1330252Y463124D02*
G03I-1969J0D01*
G01X1337338D02*
G03I-1968J0D01*
G01X1344425D02*
G03I-1969J0D01*
G01X1351511D02*
G03I-1968J0D01*
G01X1358195Y455830D02*
G03X1355065I-1565J0D01*
G01X1358598Y463124D02*
G03I-1968J0D01*
G01X1343204Y478261D02*
X1343992Y477474D01*
G01X1341262Y469403D02*
X1341045Y469684D01*
X1340921Y470000D01*
G01X1355435Y469403D02*
X1355219Y469684D01*
X1355094Y470000D01*
G01X1326718Y470661D02*
X1326763Y470205D01*
X1326892Y469774D01*
X1327089Y469403D01*
G01X1333805Y470661D02*
X1333850Y470205D01*
X1333978Y469774D01*
X1334176Y469403D01*
G01X1340891Y470661D02*
X1340936Y470205D01*
X1341065Y469774D01*
X1341262Y469403D01*
G01X1326000Y474128D02*
X1326041Y472749D01*
X1326089Y471373D01*
X1326283Y465269D01*
G01X1326718Y470242D02*
X1326760Y469949D01*
X1326885Y469663D01*
X1327089Y469403D01*
G01X1333805Y470242D02*
X1333847Y469949D01*
X1333971Y469663D01*
X1334176Y469403D01*
G01X1347978Y470242D02*
X1348020Y469949D01*
X1348145Y469663D01*
X1348349Y469403D01*
G01X1347978Y470661D02*
X1348023Y470205D01*
X1348152Y469774D01*
X1348349Y469403D01*
G01X1355065Y470661D02*
X1355109Y470205D01*
X1355238Y469774D01*
X1355435Y469403D01*
G01X1340891Y470242D02*
X1340899Y470118D01*
X1340921Y469995D01*
G01X1355065Y470242D02*
X1355072Y470118D01*
X1355094Y469995D01*
G01X1326718Y476490D02*
Y470242D01*
G01X1329848Y476490D02*
Y470242D01*
G01X1333805Y476490D02*
Y470242D01*
G01X1336935Y476490D02*
Y470242D01*
G01X1340891Y476490D02*
Y470242D01*
G01X1340921Y469206D02*
Y477474D01*
G01X1343992D02*
Y469206D01*
G01X1344021Y476490D02*
Y470242D01*
G01X1347978Y476490D02*
Y470242D01*
G01X1351108Y476490D02*
Y470242D01*
G01X1355065Y476490D02*
Y470242D01*
G01X1355094Y469206D02*
Y477277D01*
G01X1337606Y465269D02*
X1337889Y474128D01*
G01X1338430Y479049D02*
X1337949Y465269D01*
G01X1339217Y479049D02*
X1338736Y465269D01*
G01X1344021Y470242D02*
X1344014Y470119D01*
X1343992Y469995D01*
G01X1339044Y474128D02*
X1339047Y474173D01*
G01X1329848Y470242D02*
X1329809Y469957D01*
X1329686Y469670D01*
X1329477Y469403D01*
G01X1336935Y470242D02*
X1336895Y469957D01*
X1336772Y469670D01*
X1336564Y469403D01*
G01X1351108Y470242D02*
X1351069Y469957D01*
X1350946Y469670D01*
X1350737Y469403D01*
G01X1344846Y469206D02*
X1343992D01*
G01X1354362D02*
X1355094D01*
G01X1355435Y469403D02*
X1350737D01*
G01X1348349D02*
X1343650D01*
G01X1341262D02*
X1336564D01*
G01X1334176D02*
X1329477D01*
G01X1381331Y475309D02*
X1354362D01*
G01X1339086D02*
X1344846D01*
G01X1331945Y473498D02*
X1330939Y473567D01*
X1329923Y473776D01*
X1328932Y474128D01*
G01X1343992Y470000D02*
X1343866Y469682D01*
X1343650Y469403D01*
G01X1358165Y477277D02*
X1355094D01*
G01X1343992Y477474D02*
X1340921D01*
G01X1343204Y478261D02*
X1341708D01*
G01X1381331Y479049D02*
X1354362D01*
G01X1329477Y469403D02*
X1329674Y469774D01*
X1329803Y470205D01*
X1329848Y470661D01*
G01X1336564Y469403D02*
X1336761Y469774D01*
X1336890Y470205D01*
X1336935Y470661D01*
G01X1343650Y469403D02*
X1343848Y469774D01*
X1343976Y470205D01*
X1344021Y470661D01*
G01X1350737Y469403D02*
X1350934Y469774D01*
X1351063Y470205D01*
X1351108Y470661D01*
G01X1341708Y478261D02*
X1340921Y477474D01*
G01X1355882Y478065D02*
X1355094Y477277D01*
G01X1334957Y474128D02*
X1333965Y473776D01*
X1332949Y473567D01*
X1331945Y473498D01*
G01X1327089Y469403D02*
G03X1329477I1194J1012D01*
G01X1334176D02*
G03X1336564I1194J1012D01*
G01X1341262D02*
G03X1343650I1194J1012D01*
G01X1348349D02*
G03X1350737I1194J1012D01*
G01X1355435D02*
G03X1357824I1194J1012D01*
G01X1359309Y432421D02*
X1359441Y432321D01*
G01X1359343Y432187D02*
X1359277Y432254D01*
G01X1359441Y432321D02*
X1359539Y432187D01*
G01X1360589Y432454D02*
X1361409Y431114D01*
G01X1361311Y430880D02*
X1360491Y432254D01*
G01X1359277D02*
X1359178Y432287D01*
G01X1364231Y432454D02*
X1364756Y430880D01*
G01X1359375Y432086D02*
X1359343Y432187D01*
G01X1359539D02*
X1359572Y432086D01*
G01X1364559Y430880D02*
X1364428Y431282D01*
G01X1364100Y432321D02*
X1364395Y431416D01*
G01X1358358Y430880D02*
Y432454D01*
G01X1359146D02*
X1359309Y432421D01*
G01X1358555Y431583D02*
Y430880D01*
G01Y432287D02*
Y431784D01*
G01X1359375Y431985D02*
Y432086D01*
G01X1359572D02*
Y431952D01*
G01X1359835Y430880D02*
Y432454D01*
G01X1360032D02*
Y430880D01*
G01X1360294D02*
Y432454D01*
G01X1360491Y432254D02*
Y430880D01*
G01X1361409Y431114D02*
Y432454D01*
G01X1361606D02*
Y430880D01*
G01X1365018Y431952D02*
Y432220D01*
G01X1365215Y430880D02*
Y432187D01*
G01X1365412Y432454D02*
Y430880D01*
G01D02*
X1365215D01*
G01X1363640D02*
X1363443D01*
G01X1364756D02*
X1364559D01*
G01X1360032D02*
X1359835D01*
G01X1361606D02*
X1361311D01*
G01X1360491D02*
X1360294D01*
G01X1358555D02*
X1358358D01*
G01X1364428Y431282D02*
X1363772D01*
G01X1364395Y431416D02*
X1363804D01*
G01X1359146Y431583D02*
X1358555D01*
G01Y431784D02*
X1359178D01*
G01Y432287D02*
X1358555D01*
G01X1358358Y432454D02*
X1359146D01*
G01X1359835D02*
X1360032D01*
G01X1361409D02*
X1361606D01*
G01X1360294D02*
X1360589D01*
G01X1363969D02*
X1364231D01*
G01X1365215D02*
X1365412D01*
G01X1359343Y431885D02*
X1359375Y431985D01*
G01X1359572Y431952D02*
X1359539Y431852D01*
G01X1363804Y431416D02*
X1364100Y432321D01*
G01X1363772Y431282D02*
X1363640Y430880D01*
G01X1363443D02*
X1363969Y432454D01*
G01X1359309Y431617D02*
X1359146Y431583D01*
G01X1359539Y431852D02*
X1359441Y431717D01*
G01X1365018Y432220D02*
X1365215Y432454D01*
G01Y432187D02*
X1365018Y431952D01*
G01X1359277Y431818D02*
X1359343Y431885D01*
G01X1359441Y431717D02*
X1359309Y431617D01*
G01X1359178Y431784D02*
X1359277Y431818D01*
G01X1357279Y456268D02*
X1358263Y455283D01*
G01X1364366Y456268D02*
X1365350Y455283D01*
G01X1359582Y439679D02*
X1358263Y441963D01*
G01X1366669Y439679D02*
X1365350Y441963D01*
G01X1373756Y439679D02*
X1372437Y441963D01*
G01X1371452Y456268D02*
X1372437Y455283D01*
G01X1378539Y456268D02*
X1379523Y455283D01*
G01X1358195Y455352D02*
Y455830D01*
G01X1358263Y438551D02*
Y455283D01*
G01X1362082D02*
Y438551D01*
G01X1362151Y455830D02*
Y455352D01*
G01X1365281D02*
Y455830D01*
G01X1365350Y455283D02*
Y438551D01*
G01X1369169Y455283D02*
Y438551D01*
G01X1369238Y455830D02*
Y455352D01*
G01X1372368D02*
Y455830D01*
G01X1372437Y455283D02*
Y438551D01*
G01X1376256Y455283D02*
Y438551D01*
G01X1376324Y455830D02*
Y455352D01*
G01X1379523Y455283D02*
Y438551D01*
G01X1381331D02*
X1379523D01*
G01X1376256D02*
X1372437D01*
G01X1369169D02*
X1365350D01*
G01X1362082D02*
X1358263D01*
G01X1374937Y439679D02*
X1373756D01*
G01X1367850D02*
X1366669D01*
G01X1360763D02*
X1359582D01*
G01X1358401Y441725D02*
X1361945D01*
G01X1365488D02*
X1369031D01*
G01X1372574D02*
X1376118D01*
G01X1378539Y456268D02*
X1377240D01*
G01X1371452D02*
X1370153D01*
G01X1364366D02*
X1363067D01*
G01X1357279D02*
X1355980D01*
G01X1379868Y457395D02*
X1377889D01*
G01X1362082Y441963D02*
X1360763Y439679D01*
G01X1369169Y441963D02*
X1367850Y439679D01*
G01X1376256Y441963D02*
X1374937Y439679D01*
G01X1363067Y456268D02*
X1362082Y455283D01*
G01X1370153Y456268D02*
X1369169Y455283D01*
G01X1377240Y456268D02*
X1376256Y455283D01*
G01X1364008Y436155D02*
G03I-2461J0D01*
G01X1363004D02*
G03I-1457J0D01*
G01X1375602D02*
G03I-1456J0D01*
G01X1377889Y457395D02*
G03X1376324Y455830I0J-1565D01*
G01X1372368D02*
G03X1369238I-1565J0D01*
G01X1365281D02*
G03X1362151I-1565J0D01*
G01X1363004Y442061D02*
G03I-1457J0D01*
G01Y447966D02*
G03I-1457J0D01*
G01X1375602Y442061D02*
G03I-1456J0D01*
G01Y447966D02*
G03I-1456J0D01*
G01X1365685Y463124D02*
G03I-1969J0D01*
G01X1363004Y457809D02*
G03I-1457J0D01*
G01Y463714D02*
G03I-1457J0D01*
G01X1372771Y463124D02*
G03I-1968J0D01*
G01X1379858D02*
G03I-1969J0D01*
G01X1379868Y457395D02*
G03X1381433Y458960I0J1565D01*
G01X1375602Y457809D02*
G03I-1456J0D01*
G01Y463714D02*
G03I-1456J0D01*
G01X1357378Y478065D02*
X1358165Y477277D01*
G01X1378637Y478065D02*
X1379425Y477277D01*
G01X1376695Y469403D02*
X1376478Y469684D01*
X1376354Y470000D01*
G01X1362151Y470661D02*
X1362196Y470205D01*
X1362325Y469774D01*
X1362522Y469403D01*
G01X1369238Y470661D02*
X1369283Y470205D01*
X1369411Y469774D01*
X1369609Y469403D01*
G01X1376324Y470661D02*
X1376369Y470205D01*
X1376498Y469774D01*
X1376695Y469403D01*
G01X1358165Y477277D02*
Y469206D01*
G01X1358195Y476490D02*
Y470242D01*
G01X1362151D02*
X1362193Y469949D01*
X1362318Y469663D01*
X1362522Y469403D01*
G01X1369238Y470242D02*
X1369280Y469949D01*
X1369404Y469663D01*
X1369609Y469403D01*
G01X1376324Y470242D02*
X1376332Y470118D01*
X1376354Y469995D01*
G01X1362151Y476490D02*
Y470242D01*
G01X1365281Y476490D02*
Y470242D01*
G01X1369238Y476490D02*
Y470242D01*
G01X1372368Y476490D02*
Y470242D01*
G01X1376324Y476490D02*
Y470242D01*
G01X1376354Y469206D02*
Y477277D01*
G01X1379425D02*
Y469206D01*
G01X1379454Y476490D02*
Y470242D01*
G01X1358195D02*
X1358187Y470119D01*
X1358165Y469995D01*
G01X1379454Y470242D02*
X1379447Y470119D01*
X1379425Y469995D01*
G01X1365281Y470242D02*
X1365242Y469957D01*
X1365119Y469670D01*
X1364910Y469403D01*
G01X1372368Y470242D02*
X1372328Y469957D01*
X1372206Y469670D01*
X1371997Y469403D01*
G01X1358165Y469206D02*
X1376354D01*
G01X1379425D02*
X1381331D01*
G01X1381433Y469403D02*
X1379084D01*
G01X1376695D02*
X1371997D01*
G01X1369609D02*
X1364910D01*
G01X1362522D02*
X1357824D01*
G01X1358165Y470000D02*
X1358039Y469682D01*
X1357824Y469403D01*
G01X1379425Y477277D02*
X1376354D01*
G01X1355882Y478065D02*
X1357378D01*
G01X1377141D02*
X1378637D01*
G01X1379425Y470000D02*
X1379299Y469682D01*
X1379084Y469403D01*
G01X1357824D02*
X1358021Y469774D01*
X1358150Y470205D01*
X1358195Y470661D01*
G01X1364910Y469403D02*
X1365108Y469774D01*
X1365236Y470205D01*
X1365281Y470661D01*
G01X1371997Y469403D02*
X1372194Y469774D01*
X1372323Y470205D01*
X1372368Y470661D01*
G01X1379084Y469403D02*
X1379281Y469774D01*
X1379409Y470205D01*
X1379454Y470661D01*
G01X1377141Y478065D02*
X1376354Y477277D01*
G01X1362522Y469403D02*
G03X1364910I1194J1012D01*
G01X1363004Y469620D02*
G03I-1457J0D01*
G01X1369609Y469403D02*
G03X1371997I1194J1012D01*
G01X1376695D02*
G03X1379084I1194J1012D01*
G01X1375602Y469620D02*
G03I-1456J0D01*
G01X1319224Y878758D02*
X1318831Y876982D01*
G01X1319224Y878758D02*
Y885840D01*
G01X1320996Y879738D02*
Y897848D01*
G01X1323358Y879738D02*
Y897848D01*
G01X1325130Y885840D02*
Y878758D01*
G01D02*
X1325524Y876982D01*
G01X1325130Y878758D02*
X1327098D01*
G01X1333004Y879541D02*
X1319224D01*
G01X1328870Y882376D02*
X1323358D01*
G01X1325524Y900604D02*
X1325130Y898828D01*
G01X1318831Y893321D02*
X1319972Y894462D01*
G01X1318831Y885446D02*
X1319972Y886588D01*
G01X1324382Y890998D02*
X1325524Y892139D01*
G01X1324382Y883124D02*
X1325524Y884265D01*
G01X1318831D02*
Y885446D01*
G01Y892139D02*
Y893321D01*
G01X1319224Y898828D02*
Y891746D01*
G01X1319972Y883124D02*
Y886588D01*
G01Y890998D02*
Y894462D01*
G01X1322965Y900604D02*
Y898045D01*
G01X1324382Y894462D02*
Y890998D01*
G01Y886588D02*
Y883124D01*
G01X1325130Y898828D02*
Y891746D01*
G01X1325524Y893321D02*
Y892139D01*
G01Y885446D02*
Y884265D01*
G01X1318831Y900604D02*
X1319224Y898828D01*
G01X1318831Y884265D02*
X1319972Y883124D01*
G01X1325524Y885446D02*
X1324382Y886588D01*
G01X1319972Y890998D02*
X1318831Y892139D01*
G01X1325524Y893321D02*
X1324382Y894462D01*
G01X1325130Y882887D02*
X1327098D01*
G01X1324382Y883124D02*
X1327847D01*
G01X1327098Y883872D02*
X1325130D01*
G01X1325524Y884265D02*
X1326705D01*
G01Y885446D02*
X1325524D01*
G01X1327098Y885840D02*
X1325130D01*
G01X1327847Y886588D02*
X1324382D01*
G01X1328870Y887809D02*
X1323358D01*
G01X1328870Y889777D02*
X1323358D01*
G01X1324382Y890998D02*
X1327847D01*
G01X1327098Y891746D02*
X1325130D01*
G01X1325524Y892139D02*
X1326705D01*
G01Y893321D02*
X1325524D01*
G01X1327098Y893714D02*
X1325130D01*
G01X1327847Y894462D02*
X1324382D01*
G01X1327098Y894698D02*
X1325130D01*
G01X1323358Y895210D02*
X1328870D01*
G01X1327098Y897061D02*
X1325130D01*
G01X1327098Y898828D02*
X1325130D01*
G01X1327098Y878758D02*
X1326705Y876982D01*
G01X1334972Y878758D02*
X1334579Y876982D01*
G01X1342847Y878758D02*
X1342453Y876982D01*
G01X1350721Y878758D02*
X1350327Y876982D01*
G01X1327098Y878758D02*
Y885840D01*
G01X1328870Y879738D02*
Y897848D01*
G01X1331232Y879738D02*
Y897848D01*
G01X1333004Y885840D02*
Y878758D01*
G01X1334972D02*
Y885840D01*
G01X1336744Y879738D02*
Y897848D01*
G01X1339106Y879738D02*
Y897848D01*
G01X1340878Y885840D02*
Y878758D01*
G01X1342847D02*
Y885840D01*
G01X1344618Y879738D02*
Y897848D01*
G01X1346980Y879738D02*
Y897848D01*
G01X1348752Y885840D02*
Y878758D01*
G01X1350721D02*
Y885840D01*
G01X1352492Y879738D02*
Y887472D01*
G01X1354854Y879738D02*
Y887472D01*
G01X1333004Y878758D02*
X1333398Y876982D01*
G01X1340878Y878758D02*
X1341272Y876982D01*
G01X1348752Y878758D02*
X1349146Y876982D01*
G01X1333004Y878758D02*
X1334972D01*
G01X1340878D02*
X1342847D01*
G01X1348752D02*
X1350721D01*
G01X1362236Y879541D02*
X1350721D01*
G01X1348752D02*
X1334972D01*
G01X1350721Y880525D02*
X1348752D01*
G01X1334972D02*
X1333004D01*
G01X1352492Y882376D02*
X1346980D01*
G01X1344618D02*
X1339106D01*
G01X1336744D02*
X1331232D01*
G01X1354854D02*
X1360366D01*
G01X1326705Y893321D02*
X1327847Y894462D01*
G01X1326705Y885446D02*
X1327847Y886588D01*
G01X1332256Y890998D02*
X1333398Y892139D01*
G01X1334579Y893321D02*
X1335721Y894462D01*
G01X1332256Y883124D02*
X1333398Y884265D01*
G01X1334579Y885446D02*
X1335721Y886588D01*
G01X1340130Y890998D02*
X1341272Y892139D01*
G01X1342453Y893321D02*
X1343595Y894462D01*
G01X1340130Y883124D02*
X1341272Y884265D01*
G01X1342453Y885446D02*
X1343595Y886588D01*
G01X1348004Y890998D02*
X1349146Y892139D01*
G01X1350327Y893321D02*
X1351469Y894462D01*
G01X1348004Y883124D02*
X1349146Y884265D01*
G01X1350327Y885446D02*
X1351469Y886588D01*
G01X1333398Y900604D02*
X1333004Y898828D01*
G01X1341272Y900604D02*
X1340878Y898828D01*
G01X1349146Y900604D02*
X1348752Y898828D01*
G01X1326705Y884265D02*
Y885446D01*
G01Y892139D02*
Y893321D01*
G01X1327098Y898828D02*
Y891746D01*
G01X1327295Y899029D02*
Y900604D01*
G01X1327847Y883124D02*
Y886588D01*
G01Y890998D02*
Y894462D01*
G01X1329264Y900604D02*
Y898045D01*
G01X1332256Y894462D02*
Y890998D01*
G01Y886588D02*
Y883124D01*
G01X1333004Y898828D02*
Y891746D01*
G01X1333398Y893321D02*
Y892139D01*
G01Y885446D02*
Y884265D01*
G01X1334579D02*
Y885446D01*
G01Y892139D02*
Y893321D01*
G01X1334972Y898828D02*
Y891746D01*
G01X1335721Y883124D02*
Y886588D01*
G01Y890998D02*
Y894462D01*
G01X1338713Y900604D02*
Y898045D01*
G01X1340130Y894462D02*
Y890998D01*
G01Y886588D02*
Y883124D01*
G01X1340681Y900604D02*
Y899029D01*
G01X1340878Y898828D02*
Y891746D01*
G01X1341272Y893321D02*
Y892139D01*
G01Y885446D02*
Y884265D01*
G01X1342453D02*
Y885446D01*
G01Y892139D02*
Y893321D01*
G01X1342847Y898828D02*
Y891746D01*
G01X1343595Y883124D02*
Y886588D01*
G01Y890998D02*
Y894462D01*
G01X1345012Y898045D02*
Y900604D01*
G01X1348004Y894462D02*
Y890998D01*
G01Y886588D02*
Y883124D01*
G01X1348752Y898828D02*
Y891746D01*
G01X1349146Y893321D02*
Y892139D01*
G01Y885446D02*
Y884265D01*
G01X1350327D02*
Y885446D01*
G01Y892139D02*
Y893321D01*
G01X1350721Y898828D02*
Y891746D01*
G01X1351469Y883124D02*
Y886588D01*
G01Y890998D02*
Y894462D01*
G01X1352492Y889777D02*
Y887809D01*
G01Y890114D02*
Y897848D01*
G01X1354461Y900604D02*
Y898045D01*
G01X1354854Y887809D02*
Y889777D01*
G01Y890114D02*
Y897848D01*
G01X1326705Y900604D02*
X1327098Y898828D01*
G01X1334579Y900604D02*
X1334972Y898828D01*
G01X1342453Y900604D02*
X1342847Y898828D01*
G01X1350327Y900604D02*
X1350721Y898828D01*
G01X1329000Y898045D02*
X1328728Y898411D01*
X1328397Y898693D01*
X1328031Y898887D01*
X1327656Y898996D01*
X1327295Y899029D01*
G01X1326705Y884265D02*
X1327847Y883124D01*
G01X1334579Y884265D02*
X1335721Y883124D01*
G01X1333398Y885446D02*
X1332256Y886588D01*
G01X1327847Y890998D02*
X1326705Y892139D01*
G01X1342453Y884265D02*
X1343595Y883124D01*
G01X1341272Y885446D02*
X1340130Y886588D01*
G01X1335721Y890998D02*
X1334579Y892139D01*
G01X1333398Y893321D02*
X1332256Y894462D01*
G01X1350327Y884265D02*
X1351469Y883124D01*
G01X1349146Y885446D02*
X1348004Y886588D01*
G01X1341272Y893321D02*
X1340130Y894462D01*
G01X1343595Y890998D02*
X1342453Y892139D01*
G01X1351469Y890998D02*
X1350327Y892139D01*
G01X1349146Y893321D02*
X1348004Y894462D01*
G01X1333004Y882887D02*
X1334972D01*
G01X1340878D02*
X1342847D01*
G01X1348752D02*
X1350721D01*
G01X1332256Y883124D02*
X1335721D01*
G01X1340130D02*
X1343595D01*
G01X1348004D02*
X1351469D01*
G01X1350721Y883872D02*
X1348752D01*
G01X1342847D02*
X1340878D01*
G01X1334972D02*
X1333004D01*
G01X1333398Y884265D02*
X1334579D01*
G01X1341272D02*
X1342453D01*
G01X1349146D02*
X1350327D01*
G01Y885446D02*
X1349146D01*
G01X1342453D02*
X1341272D01*
G01X1334579D02*
X1333398D01*
G01X1350721Y885840D02*
X1348752D01*
G01X1342847D02*
X1340878D01*
G01X1334972D02*
X1333004D01*
G01X1351469Y886588D02*
X1348004D01*
G01X1343595D02*
X1340130D01*
G01X1335721D02*
X1332256D01*
G01X1360366Y887809D02*
X1354854D01*
G01X1352492D02*
X1346980D01*
G01X1344618D02*
X1339106D01*
G01X1336744D02*
X1331232D01*
G01X1360366Y889777D02*
X1354854D01*
G01X1352492D02*
X1346980D01*
G01X1344618D02*
X1339106D01*
G01X1336744D02*
X1331232D01*
G01X1332256Y890998D02*
X1335721D01*
G01X1340130D02*
X1343595D01*
G01X1348004D02*
X1351469D01*
G01X1350721Y891746D02*
X1348752D01*
G01X1342847D02*
X1340878D01*
G01X1334972D02*
X1333004D01*
G01X1333398Y892139D02*
X1334579D01*
G01X1341272D02*
X1342453D01*
G01X1349146D02*
X1350327D01*
G01Y893321D02*
X1349146D01*
G01X1342453D02*
X1341272D01*
G01X1334579D02*
X1333398D01*
G01X1350721Y893714D02*
X1348752D01*
G01X1342847D02*
X1340878D01*
G01X1334972D02*
X1333004D01*
G01X1351469Y894462D02*
X1348004D01*
G01X1343595D02*
X1340130D01*
G01X1335721D02*
X1332256D01*
G01X1350721Y894698D02*
X1348752D01*
G01X1342847D02*
X1340878D01*
G01X1334972D02*
X1333004D01*
G01X1331232Y895210D02*
X1336744D01*
G01X1339106D02*
X1344618D01*
G01X1346980D02*
X1352492D01*
G01X1354854D02*
X1360366D01*
G01X1342847Y897061D02*
X1340878D01*
G01X1327098Y898045D02*
X1329264D01*
G01X1338713D02*
X1340878D01*
G01X1342847D02*
X1356626D01*
G01X1350721Y898828D02*
X1348752D01*
G01X1342847D02*
X1340878D01*
G01X1334972D02*
X1333004D01*
G01X1340681Y899029D02*
X1365189D01*
G01X1345012Y899423D02*
X1354461D01*
G01Y899817D02*
X1345012D01*
G01X1340681Y899029D02*
X1340319Y898996D01*
X1339945Y898886D01*
X1339579Y898692D01*
X1339248Y898411D01*
X1338976Y898045D01*
G01X1355445Y888793D02*
G03I-1772J0D01*
G01X1355051D02*
G03I-1378J0D01*
G01X1358595Y878758D02*
X1358201Y876982D01*
G01X1356626Y885840D02*
Y878758D01*
G01X1358595D02*
Y885840D01*
G01X1360366Y879738D02*
Y897848D01*
G01X1362236Y880525D02*
Y879541D01*
G01X1363221Y897061D02*
Y880525D01*
G01X1363516Y897848D02*
Y879738D01*
G01X1365189Y882887D02*
Y878557D01*
G01X1366764Y876982D02*
Y900604D01*
G01X1356626Y878758D02*
X1357020Y876982D01*
G01X1365189Y878557D02*
X1363221Y880525D01*
G01X1356626Y878758D02*
X1358595D01*
G01X1363221Y880525D02*
X1362236D01*
G01X1359667Y891574D02*
X1360091Y892078D01*
G01Y891502D02*
X1359667Y890998D01*
G01X1359343Y894462D02*
X1358201Y893321D01*
G01X1355878Y890998D02*
X1357020Y892139D01*
G01X1363221Y897061D02*
X1365189Y899029D01*
G01X1357020Y900604D02*
X1356626Y898828D01*
G01X1359343Y886588D02*
X1358201Y885446D01*
G01X1355878Y883124D02*
X1357020Y884265D01*
G01X1363221Y888793D02*
X1365189Y890761D01*
G01X1355878Y894462D02*
Y890998D01*
G01Y886588D02*
Y883124D01*
G01X1356626Y898828D02*
Y891746D01*
G01X1357020Y893321D02*
Y892139D01*
G01Y885446D02*
Y884265D01*
G01X1358201D02*
Y885446D01*
G01Y892139D02*
Y893321D01*
G01X1358595Y898828D02*
Y891746D01*
G01X1359244Y890998D02*
Y894383D01*
G01X1359343Y883124D02*
Y886588D01*
G01Y890998D02*
Y894462D01*
G01X1359667Y894383D02*
Y891574D01*
G01X1360091Y892078D02*
Y891502D01*
G01X1362236Y898045D02*
Y897061D01*
G01X1365189Y899029D02*
Y890761D01*
G01X1358201Y900604D02*
X1358595Y898828D01*
G01X1359343Y883124D02*
X1358201Y884265D01*
G01X1357020Y885446D02*
X1355878Y886588D01*
G01X1363221Y884856D02*
X1365189Y882887D01*
G01X1359343Y890998D02*
X1358201Y892139D01*
G01X1357020Y893321D02*
X1355878Y894462D01*
G01X1356626Y882887D02*
X1358595D01*
G01X1365189D02*
X1366764D01*
G01X1355878Y883124D02*
X1359343D01*
G01X1358595Y883872D02*
X1356626D01*
G01X1357020Y884265D02*
X1358201D01*
G01X1363221Y884856D02*
X1366764D01*
G01X1358201Y885446D02*
X1357020D01*
G01X1358595Y885840D02*
X1356626D01*
G01X1359343Y886588D02*
X1355878D01*
G01X1363221Y888793D02*
X1366764D01*
G01X1365189Y890761D02*
X1366764D01*
G01X1359667Y890998D02*
X1359244D01*
G01X1355878D02*
X1359343D01*
G01X1358595Y891746D02*
X1356626D01*
G01X1357020Y892139D02*
X1358201D01*
G01Y893321D02*
X1357020D01*
G01X1358595Y893714D02*
X1356626D01*
G01X1359244Y894383D02*
X1359667D01*
G01X1359343Y894462D02*
X1355878D01*
G01X1358595Y894698D02*
X1356626D01*
G01X1363221Y897061D02*
X1362236D01*
G01X1358595D02*
X1356626D01*
G01X1362236Y898045D02*
X1358595D01*
G01Y898828D02*
X1356626D01*
G01X1332148Y921982D02*
Y948990D01*
G01X1335524D02*
Y938072D01*
G01Y934624D02*
Y921982D01*
G01X1351278D02*
Y934624D01*
G01Y938072D02*
Y948990D01*
G01X1354654D02*
Y921982D01*
G01D02*
X1351278D01*
G01X1335524D02*
X1332148D01*
G01X1351278Y934624D02*
X1335524D01*
G01Y938072D02*
X1351278D01*
G01X1332148Y948990D02*
X1335524D01*
G01X1351278D02*
X1354654D01*
G01X1378286Y944393D02*
X1376035Y940945D01*
G01X1373785Y942669D02*
X1373222Y940945D01*
G01X1376035D02*
X1375473Y937497D01*
G01X1373222Y940945D02*
X1372659Y938072D01*
G01X1359156Y931176D02*
Y933475D01*
G01Y938072D02*
Y940371D01*
G01X1368158D02*
Y938072D01*
G01Y933475D02*
Y931176D01*
G01X1372659Y938072D02*
Y932900D01*
G01X1375473Y937497D02*
Y933475D01*
G01X1372659Y932900D02*
X1373222Y930027D01*
G01X1375473Y933475D02*
X1376035Y930027D01*
G01X1373222D02*
X1373785Y928303D01*
G01D02*
X1374910Y926004D01*
G01X1376035Y930027D02*
X1378286Y926579D01*
G01X1374910Y926004D02*
X1376598Y924281D01*
G01X1378286Y926579D02*
X1379974Y925430D01*
G01X1376598Y924281D02*
X1379411Y922557D01*
G01D02*
X1382787Y921982D01*
G01X1379974Y925430D02*
X1382787Y924855D01*
G01X1368158Y931176D02*
X1359156D01*
G01Y933475D02*
X1368158D01*
G01Y938072D02*
X1359156D01*
G01Y940371D02*
X1368158D01*
G01X1374910Y944967D02*
X1373785Y942669D01*
G01X1376598Y946691D02*
X1374910Y944967D01*
G01X1379974Y945542D02*
X1378286Y944393D01*
G01X1379411Y948415D02*
X1376598Y946691D01*
G01X1382787Y946117D02*
X1379974Y945542D01*
G01X1382787Y948990D02*
X1379411Y948415D01*
G01X1455633Y1009254D02*
X1356604D01*
G01X1394243Y-879845D02*
Y-898782D01*
G01X1383017Y-238600D02*
X1383897Y-241297D01*
G01X1383017Y-247589D02*
X1380377Y-243993D01*
G01X1383897Y-241297D02*
X1385657Y-243993D01*
G01X1403259D02*
X1405019Y-240398D01*
G01X1387417Y-250285D02*
X1383017Y-247589D01*
G01X1385657Y-243993D02*
X1388297Y-245791D01*
G01X1400619D02*
X1403259Y-243993D01*
G01X1405899Y-247589D02*
X1401499Y-250285D01*
G01X1391818Y-251183D02*
X1387417Y-250285D01*
G01X1388297Y-245791D02*
X1391818Y-246690D01*
G01X1397098Y-251183D02*
X1391818D01*
G01Y-246690D02*
X1397098D01*
G01D02*
X1400619Y-245791D01*
G01X1401499Y-250285D02*
X1397098Y-251183D01*
G01X1380377Y-213433D02*
Y-208939D01*
G01X1383017Y-236803D02*
Y-238600D01*
G01X1383897Y-234106D02*
X1383017Y-236803D01*
G01X1385657Y-231410D02*
X1383897Y-234106D01*
G01X1380377Y-231410D02*
X1383017Y-227815D01*
G01X1404139Y-232309D02*
X1400619Y-229612D01*
G01X1388297D02*
X1385657Y-231410D01*
G01X1383017Y-227815D02*
X1387417Y-225118D01*
G01X1401499D02*
X1405899Y-227815D01*
G01X1400619Y-229612D02*
X1397098Y-228713D01*
G01Y-224219D02*
X1401499Y-225118D01*
G01X1405019Y-240398D02*
X1410299D01*
G01Y-232309D02*
X1404139D01*
G01X1397098Y-228713D02*
X1391818D01*
G01Y-224219D02*
X1397098D01*
G01X1405899Y-213433D02*
X1380377D01*
G01X1387417Y-225118D02*
X1391818Y-224219D01*
G01Y-228713D02*
X1388297Y-229612D01*
G01X1380377Y-208939D02*
X1410299D01*
G01Y-240398D02*
X1408539Y-243993D01*
G01D02*
X1405899Y-247589D01*
G01Y-227815D02*
Y-213433D01*
G01X1410299Y-208939D02*
Y-232309D01*
G01X1417340Y-235904D02*
X1419100Y-238600D01*
G01Y-220624D02*
X1417340Y-223321D01*
G01D02*
X1429661Y-229612D01*
G01X1435822D02*
X1419100Y-220624D01*
G01Y-238600D02*
X1435822Y-229612D01*
G01X1429661D02*
X1417340Y-235904D01*
G01X1387638Y50403D02*
X1389793Y53705D01*
G01X1384943Y50403D02*
X1385482Y52054D01*
G01X1402727Y38295D02*
X1401649Y36094D01*
G01X1400571Y39946D02*
X1398416Y36644D01*
G01X1401649Y36094D02*
X1400032Y34443D01*
G01X1398416Y36644D02*
X1396799Y35544D01*
G01X1400032Y34443D02*
X1397338Y32792D01*
G01X1387099Y47101D02*
X1387638Y50403D01*
G01X1384404Y47651D02*
X1384943Y50403D01*
G01X1403266Y39946D02*
X1402727Y38295D01*
G01X1384404Y42698D02*
Y47651D01*
G01X1387099Y43248D02*
Y47101D01*
G01X1401110Y43248D02*
X1400571Y39946D01*
G01X1403804Y42698D02*
X1403266Y39946D01*
G01X1401110Y47101D02*
Y43248D01*
G01X1403804Y47651D02*
Y42698D01*
G01X1384943Y39946D02*
X1384404Y42698D01*
G01X1387638Y39946D02*
X1387099Y43248D01*
G01X1400571Y50403D02*
X1401110Y47101D01*
G01X1385482Y38295D02*
X1384943Y39946D01*
G01X1403266Y50403D02*
X1403804Y47651D01*
G01X1386560Y36094D02*
X1385482Y38295D01*
G01X1402727Y52054D02*
X1403266Y50403D01*
G01X1389793Y36644D02*
X1387638Y39946D01*
G01X1398416Y53705D02*
X1400571Y50403D01*
G01X1388177Y34443D02*
X1386560Y36094D01*
G01X1390871Y32792D02*
X1388177Y34443D01*
G01X1391410Y35544D02*
X1389793Y36644D01*
G01X1394104Y32242D02*
X1390871Y32792D01*
G01X1394104Y34993D02*
X1391410Y35544D01*
G01X1396799D02*
X1394104Y34993D01*
G01X1397338Y32792D02*
X1394104Y32242D01*
G01X1408115Y49852D02*
Y47651D01*
G01Y43248D02*
Y41047D01*
G01X1416737D02*
Y43248D01*
G01Y47651D02*
Y49852D01*
G01X1421048Y58108D02*
Y32242D01*
G01X1424282D02*
Y44349D01*
G01Y47651D02*
Y58108D01*
G01X1421048Y32242D02*
X1424282D01*
G01X1408115Y41047D02*
X1416737D01*
G01Y43248D02*
X1408115D01*
G01X1424282Y44349D02*
X1439370D01*
G01Y47651D02*
X1424282D01*
G01X1408115D02*
X1416737D01*
G01Y49852D02*
X1408115D01*
G01X1439370Y58108D02*
Y47651D01*
G01Y44349D02*
Y32242D01*
G01D02*
X1442603D01*
G01X1386560Y54255D02*
X1388177Y55906D01*
G01X1389793Y53705D02*
X1391410Y54805D01*
G01X1388177Y55906D02*
X1390871Y57557D01*
G01X1385482Y52054D02*
X1386560Y54255D01*
G01X1401649D02*
X1402727Y52054D01*
G01X1400032Y55906D02*
X1401649Y54255D01*
G01X1396799Y54805D02*
X1398416Y53705D01*
G01X1397338Y57557D02*
X1400032Y55906D01*
G01X1394104Y58108D02*
X1397338Y57557D01*
G01X1394104Y55356D02*
X1396799Y54805D01*
G01X1390871Y57557D02*
X1394104Y58108D01*
G01X1391410Y54805D02*
X1394104Y55356D01*
G01X1424282Y58108D02*
X1421048D01*
G01X1442603D02*
X1439370D01*
G01X1381331Y368321D02*
Y479049D01*
G01X1381433Y476490D02*
Y458960D01*
G01X1396429Y557887D02*
Y589383D01*
G01X1400366D02*
Y576651D01*
G01Y572630D02*
Y557887D01*
G01D02*
X1396429D01*
G01X1418739Y572630D02*
X1400366D01*
G01Y576651D02*
X1418739D01*
G01X1396429Y589383D02*
X1400366D01*
G01X1418739Y557887D02*
Y572630D01*
G01Y576651D02*
Y589383D01*
G01X1422676D02*
Y557887D01*
G01X1440392Y580672D02*
X1441705Y578661D01*
G01X1432518Y573971D02*
X1441705Y569280D01*
G01X1440392Y567269D02*
X1427925Y573971D01*
G01X1422676Y557887D02*
X1418739D01*
G01X1441705Y569280D02*
X1440392Y567269D01*
G01X1427925Y573971D02*
X1440392Y580672D01*
G01X1441705Y578661D02*
X1432518Y573971D01*
G01X1418739Y589383D02*
X1422676D01*
G01X1385601Y925430D02*
X1387289Y926579D01*
G01X1382787Y924855D02*
X1385601Y925430D01*
G01X1382787Y921982D02*
X1386163Y922557D01*
G01X1387289Y944393D02*
X1385601Y945542D01*
G01X1386163Y948415D02*
X1382787Y948990D01*
G01X1385601Y945542D02*
X1382787Y946117D01*
G01X1400230Y938646D02*
X1401355Y939796D01*
G01Y937497D02*
X1400230Y936348D01*
G01X1388977Y924281D02*
X1390665Y926004D01*
G01X1408670Y938072D02*
X1410358Y939796D01*
G01X1390665Y926004D02*
X1391790Y928303D01*
G01X1409795Y936922D02*
X1409233Y935773D01*
G01X1387289Y926579D02*
X1389539Y930027D01*
G01X1410358Y937497D02*
X1409795Y936922D01*
G01X1386163Y922557D02*
X1388977Y924281D01*
G01X1411483Y938072D02*
X1410358Y937497D01*
G01X1401355Y939796D02*
X1403043Y940371D01*
G01Y938072D02*
X1401355Y937497D01*
G01X1410358Y939796D02*
X1412046Y940371D01*
G01X1389539Y930027D02*
X1390102Y933475D01*
G01X1392353Y930027D02*
X1392915Y932900D01*
G01X1391790Y928303D02*
X1392353Y930027D01*
G01X1390102Y933475D02*
Y937497D01*
G01X1392915Y932900D02*
Y938072D01*
G01X1397417Y921982D02*
Y940371D01*
G01X1400230D02*
Y938646D01*
G01Y936348D02*
Y921982D01*
G01X1406419D02*
Y935773D01*
G01X1409233D02*
Y921982D01*
G01X1415422D02*
Y935773D01*
G01X1392915Y938072D02*
X1392353Y940945D01*
G01X1390102Y937497D02*
X1389539Y940945D01*
G01X1392353D02*
X1391790Y942669D01*
G01X1406419Y935773D02*
X1405857Y936922D01*
G01X1415422Y935773D02*
X1414859Y936922D01*
G01X1389539Y940945D02*
X1387289Y944393D01*
G01X1405857Y936922D02*
X1405294Y937497D01*
G01X1406982Y939796D02*
X1408670Y938072D01*
G01X1414859Y936922D02*
X1414297Y937497D01*
G01X1405294D02*
X1404169Y938072D01*
G01X1414297Y937497D02*
X1413171Y938072D01*
G01X1405294Y940371D02*
X1406982Y939796D01*
G01X1414297Y940371D02*
X1415985Y939796D01*
G01X1418235Y921982D02*
X1415422D01*
G01X1409233D02*
X1406419D01*
G01X1400230D02*
X1397417D01*
G01X1413171Y938072D02*
X1411483D01*
G01X1404169D02*
X1403043D01*
G01X1397417Y940371D02*
X1400230D01*
G01X1403043D02*
X1405294D01*
G01X1412046D02*
X1414297D01*
G01X1391790Y942669D02*
X1390665Y944967D01*
G01D02*
X1388977Y946691D01*
G01D02*
X1386163Y948415D01*
G01X1425550Y938646D02*
X1426675Y939796D01*
G01Y937497D02*
X1425550Y936348D01*
G01X1433990Y938072D02*
X1435678Y939796D01*
G01Y937497D02*
X1435115Y936922D01*
G01X1436803Y938072D02*
X1435678Y937497D01*
G01X1426675Y939796D02*
X1428363Y940371D01*
G01Y938072D02*
X1426675Y937497D01*
G01X1435678Y939796D02*
X1437366Y940371D01*
G01X1435115Y936922D02*
X1434552Y935773D01*
G01X1418235D02*
Y921982D01*
G01X1422737D02*
Y940371D01*
G01X1425550D02*
Y938646D01*
G01Y936348D02*
Y921982D01*
G01X1431739D02*
Y935773D01*
G01X1434552D02*
Y921982D01*
G01X1440742D02*
Y935773D01*
G01X1417110Y938646D02*
X1418235Y935773D01*
G01X1431739D02*
X1431176Y936922D01*
G01X1440742Y935773D02*
X1440179Y936922D01*
G01X1415985Y939796D02*
X1417110Y938646D01*
G01X1431176Y936922D02*
X1430614Y937497D01*
G01X1432302Y939796D02*
X1433990Y938072D01*
G01X1440179Y936922D02*
X1439617Y937497D01*
G01X1441304Y939796D02*
X1442430Y938646D01*
G01X1430614Y937497D02*
X1429489Y938072D01*
G01X1439617Y937497D02*
X1438491Y938072D01*
G01X1430614Y940371D02*
X1432302Y939796D01*
G01X1439617Y940371D02*
X1441304Y939796D01*
G01X1443555Y921982D02*
X1440742D01*
G01X1434552D02*
X1431739D01*
G01X1425550D02*
X1422737D01*
G01X1438491Y938072D02*
X1436803D01*
G01X1429489D02*
X1428363D01*
G01X1422737Y940371D02*
X1425550D01*
G01X1428363D02*
X1430614D01*
G01X1437366D02*
X1439617D01*
G01X1394243Y1297911D02*
Y1278974D01*
G01X1442863Y-208939D02*
Y-251183D01*
G01X1448143D02*
Y-231410D01*
G01X1442863Y-251183D02*
X1448143D01*
G01Y-226017D02*
Y-208939D01*
G01Y-231410D02*
X1472786D01*
G01Y-226017D02*
X1448143D01*
G01Y-208939D02*
X1442863D01*
G01X1472786Y-231410D02*
Y-251183D01*
G01X1478066D02*
Y-208939D01*
G01X1472786Y-251183D02*
X1478066D01*
G01X1472786Y-208939D02*
Y-226017D01*
G01X1478066Y-208939D02*
X1472786D01*
G01X1442603Y32242D02*
Y58108D01*
G01X1519680Y34486D02*
G03I-18701J0D01*
G01X1507869D02*
G03I-6890J0D01*
G01X1503486Y53018D02*
X1515762Y143780D01*
G01X1461390Y563248D02*
X1463358Y560568D01*
G01X1446954Y579332D02*
Y584693D01*
G01X1450891Y557887D02*
Y584022D01*
G01X1454828Y589383D02*
Y557887D01*
G01X1460077Y589383D02*
Y571960D01*
G01X1463358Y560568D02*
X1466639Y558558D01*
G01X1467295Y561908D02*
X1465327Y563248D01*
G01X1460077Y565929D02*
X1461390Y563248D01*
G01X1465327D02*
X1464014Y565929D01*
G01X1463358Y575311D02*
Y586033D01*
G01X1466639Y558558D02*
X1469920Y557887D01*
G01Y561238D02*
X1467295Y561908D01*
G01X1473857Y574641D02*
X1476482Y573971D01*
G01X1454828Y557887D02*
X1450891D01*
G01X1469920D02*
X1473857D01*
G01Y561238D02*
X1469920D01*
G01X1464014Y565929D02*
X1460077D01*
G01Y571960D02*
X1464671D01*
G01X1469920Y574641D02*
X1473857D01*
G01Y577991D02*
X1469920D01*
G01X1477138Y577321D02*
X1473857Y577991D01*
G01X1450891Y584022D02*
X1446954Y579332D01*
G01X1476482Y561908D02*
X1473857Y561238D01*
G01Y557887D02*
X1477138Y558558D01*
G01X1469920Y577991D02*
X1466639Y577321D01*
G01X1467295Y573971D02*
X1469920Y574641D01*
G01X1464671Y571960D02*
X1467295Y573971D01*
G01X1466639Y577321D02*
X1463358Y575311D01*
G01X1446954Y584693D02*
X1450891Y589383D01*
G01X1463358Y586033D02*
X1482387D01*
G01Y589383D02*
X1460077D01*
G01X1450891D02*
X1454828D01*
G01X1476482Y573971D02*
X1478450Y572630D01*
G01X1482387D02*
X1480419Y575311D01*
G01X1478450Y572630D02*
X1479762Y570620D01*
G01X1483699Y569280D02*
X1482387Y572630D01*
G01X1479762Y570620D02*
X1480419Y568609D01*
G01D02*
Y567269D01*
G01X1483699Y566599D02*
Y569280D01*
G01X1488949Y557887D02*
Y579332D01*
G01X1492230D02*
Y577321D01*
G01Y574641D02*
Y557887D01*
G01X1498135Y579332D02*
X1500104Y578661D01*
G01X1498135Y575981D02*
X1496823Y576651D01*
G01X1480419Y575311D02*
X1477138Y577321D01*
G01X1498791Y575311D02*
X1498135Y575981D01*
G01X1500104Y578661D02*
X1502072Y576651D01*
G01X1499447Y573971D02*
X1498791Y575311D01*
G01X1499447Y557887D02*
Y573971D01*
G01X1502728D02*
Y557887D01*
G01X1480419Y567269D02*
X1479762Y565259D01*
G01X1502728Y557887D02*
X1499447D01*
G01X1492230D02*
X1488949D01*
G01X1496823Y576651D02*
X1495510D01*
G01X1482387Y563248D02*
X1483699Y566599D01*
G01X1503384Y575311D02*
X1502728Y573971D01*
G01X1488949Y579332D02*
X1492230D01*
G01X1495510D02*
X1498135D01*
G01X1479762Y565259D02*
X1478450Y563248D01*
G01X1480419Y560568D02*
X1482387Y563248D01*
G01X1492230Y577321D02*
X1493542Y578661D01*
G01Y575981D02*
X1492230Y574641D01*
G01X1502072Y576651D02*
X1504041Y578661D01*
G01Y575981D02*
X1503384Y575311D01*
G01X1478450Y563248D02*
X1476482Y561908D01*
G01X1477138Y558558D02*
X1480419Y560568D01*
G01X1505353Y576651D02*
X1504041Y575981D01*
G01X1493542Y578661D02*
X1495510Y579332D01*
G01Y576651D02*
X1493542Y575981D01*
G01X1504041Y578661D02*
X1506009Y579332D01*
G01X1482387Y586033D02*
Y589383D01*
G01X1443555Y935773D02*
Y921982D01*
G01X1442430Y938646D02*
X1443555Y935773D01*
G01X1506683Y953090D02*
X1458782Y1009254D01*
G01X1506539Y965971D02*
X1463472Y1135090D01*
G01X1529854Y947848D02*
G03I-18700J0D01*
G01X1518043D02*
G03I-6889J0D01*
G01X1458782Y1009254D02*
X1455633D01*
G01X1463472Y1135090D02*
X1460323D01*
G01X1540359Y-4884D02*
Y-28506D01*
G01D02*
X1697840D01*
G01X1540359Y65982D02*
Y23710D01*
G01Y65982D02*
Y23710D01*
G01D02*
G03X1556935Y4272I19685J0D01*
G01X1540359Y23710D02*
G03X1556935Y4272I19685J0D01*
G01X1589562Y-947D02*
X1556935Y4272D01*
G01X1589562Y-947D02*
X1556935Y4272D01*
G01X1540359Y65982D02*
G03X1532485Y73856I-7874J0D01*
G01X1540359Y65982D02*
G03X1532485Y73856I-7874J0D01*
G01X1515762Y143780D02*
X1518912D01*
G01D02*
X1805027D01*
G01X1554523Y378645D02*
X1554129Y378715D01*
G01X1552246Y376903D02*
X1552625Y376794D01*
G01X1553535Y376882D02*
X1553615Y376859D01*
G01X1553457Y380180D02*
X1554011Y379976D01*
G01X1552330Y376588D02*
X1552454Y376614D01*
G01X1558453Y378713D02*
X1558079Y378646D01*
G01X1552092Y376588D02*
X1608391D01*
G01X1552092Y376903D02*
X1552246D01*
G01X1552876D02*
X1566419D01*
G01X1567708Y377076D02*
X1565346D01*
G01X1553535D02*
X1552092D01*
G01X1560458D02*
X1564986D01*
G01X1554523Y378950D02*
X1558059D01*
G01X1553555Y380726D02*
X1554145D01*
G01X1558476D02*
X1559067D01*
G01X1564986Y384462D02*
X1560458D01*
G01X1553535D02*
X1552092D01*
G01X1565346D02*
X1567708D01*
G01X1559746Y376903D02*
X1559996Y376794D01*
G01X1560063Y376687D02*
X1560168Y376613D01*
X1560291Y376588D01*
G01X1554489Y378554D02*
X1554495Y378548D01*
X1554509Y378533D01*
X1554525Y378508D01*
X1554538Y378474D01*
X1554544Y378432D01*
X1554541Y378382D01*
X1554528Y378324D01*
X1554507Y378260D01*
X1554479Y378192D01*
X1554444Y378119D01*
X1554401Y378041D01*
X1554353Y377963D01*
X1554308Y377896D01*
X1554268Y377840D01*
X1554235Y377796D01*
X1554209Y377763D01*
X1554193Y377744D01*
X1554188Y377738D01*
G01X1558393Y377741D02*
X1558387Y377747D01*
X1558372Y377767D01*
X1558346Y377799D01*
X1558313Y377843D01*
X1558274Y377897D01*
X1558230Y377962D01*
X1558184Y378038D01*
X1558140Y378117D01*
X1558104Y378193D01*
X1558076Y378260D01*
X1558056Y378323D01*
X1558044Y378380D01*
X1558041Y378430D01*
X1558046Y378471D01*
X1558059Y378505D01*
X1558075Y378529D01*
X1558088Y378544D01*
X1558094Y378550D01*
G01X1560063Y376687D02*
X1559996Y376794D01*
G01X1558094Y378550D02*
X1558393Y377741D01*
G01X1559085Y377003D02*
X1558453Y378713D01*
G01X1559746Y376903D02*
X1558610Y379976D01*
G01X1558795Y380044D02*
X1559996Y376794D01*
G01X1559164Y380180D02*
X1560375Y376903D01*
G01X1552092Y415171D02*
Y376588D01*
G01X1552246Y376903D02*
Y376588D01*
G01X1552876Y376903D02*
Y376588D01*
G01X1553535Y376822D02*
Y384462D01*
G01X1553555Y408854D02*
Y380726D01*
G01X1553948Y408854D02*
Y380726D01*
G01X1554129Y378715D02*
Y408775D01*
G01X1554145Y380726D02*
Y408854D01*
G01X1554523Y408775D02*
Y378645D01*
G01X1554917Y408775D02*
Y376588D01*
G01X1557666Y408775D02*
Y376588D01*
G01X1558059Y408775D02*
Y378950D01*
G01X1558453Y408775D02*
Y378713D01*
G01X1558476Y408854D02*
Y380726D01*
G01X1558673D02*
Y408854D01*
G01X1559067Y380726D02*
Y408854D01*
G01X1559746Y376903D02*
Y376588D01*
G01X1560375D02*
Y376903D01*
G01X1560458Y384462D02*
Y376588D01*
G01X1564986Y384462D02*
Y376588D01*
G01X1565346Y384462D02*
Y376588D01*
G01X1552246Y376903D02*
X1553457Y380180D01*
G01X1553826Y380044D02*
X1552625Y376794D01*
G01X1554011Y379976D02*
X1552876Y376903D01*
G01X1554129Y378715D02*
X1553535Y377108D01*
G01X1554523Y378645D02*
X1554001Y377233D01*
G01D02*
X1553922Y377101D01*
X1553798Y376978D01*
X1553615Y376859D01*
G01X1552625Y376794D02*
X1552558Y376687D01*
X1552454Y376614D01*
G01X1553535Y377013D02*
X1553163Y376793D01*
X1552753Y376646D01*
X1552286Y376588D01*
G01X1553615Y376859D02*
X1553563Y376833D01*
X1553535Y376822D01*
G01X1552876Y376903D02*
X1552780Y376862D01*
X1552699Y376828D01*
X1552645Y376804D01*
X1552625Y376794D01*
G01X1558610Y379976D02*
X1559164Y380180D01*
G01X1559996Y376794D02*
X1560375Y376903D01*
G01X1558393Y377741D02*
G03X1560422Y376588I2029J1209D01*
G01X1558059Y378950D02*
G03X1558094Y378550I2362J5D01*
G01X1554489Y378554D02*
G03X1554523Y378950I-2328J399D01*
G01X1553532Y377028D02*
G03X1554188Y377738I-1370J1924D01*
G01X1558476Y380726D02*
G03X1558610Y379976I2165J0D01*
G01X1554011D02*
G03X1554145Y380726I-2031J750D01*
G01X1553826Y380044D02*
G03X1553948Y380726I-1846J682D01*
G01X1558673D02*
G03X1558795Y380044I1968J0D01*
G01X1553457Y380180D02*
G03X1553555Y380726I-1477J547D01*
G01X1559067D02*
G03X1559164Y380180I1575J-2D01*
G01X1552330Y376588D02*
G03X1552625Y376794I-1J315D01*
G01X1559996D02*
G03X1560291Y376588I296J109D01*
G01X1552092Y403524D02*
X1551765D01*
G01X1554129Y408775D02*
X1554917D01*
G01X1557666D02*
X1558453D01*
G01X1554145Y408854D02*
X1553555D01*
G01X1558476D02*
X1559067D01*
G01X1557634Y408872D02*
X1554949D01*
G01X1554360Y409069D02*
X1558261D01*
G01Y409265D02*
X1554360D01*
G01X1558261Y409659D02*
X1554360D01*
G01X1608391Y411762D02*
X1552092D01*
G01X1608391Y411959D02*
X1552092D01*
G01X1608391Y414580D02*
X1552092D01*
G01X1608391Y415171D02*
X1551765D01*
G01X1554819Y409266D02*
X1554828Y409228D01*
X1554855Y409128D01*
X1554897Y408998D01*
X1554949Y408872D01*
G01X1554735Y409659D02*
X1554774Y409463D01*
X1554806Y409318D01*
X1554819Y409266D01*
G01X1551765Y479049D02*
Y403524D01*
G01X1554360Y409069D02*
Y409659D01*
G01X1558261Y409069D02*
Y409659D01*
G01X1557847D02*
X1557808Y409462D01*
X1557776Y409318D01*
X1557763Y409266D01*
G01X1557634Y408872D02*
X1557688Y409006D01*
X1557730Y409138D01*
X1557755Y409232D01*
X1557763Y409266D01*
G01X1558453Y408775D02*
G03X1557847Y409659I-948J0D01*
G01X1554735D02*
G03X1554129Y408775I342J-884D01*
G01X1554360Y409659D02*
G03X1553555Y408854I0J-805D01*
G01X1559067D02*
G03X1558261Y409659I-806J-1D01*
G01X1554819Y409266D02*
G03X1554523Y408775I258J-490D01*
G01X1558059D02*
G03X1557763Y409266I-554J1D01*
G01X1554360Y409265D02*
G03X1553948Y408854I0J-412D01*
G01X1558673D02*
G03X1558261Y409265I-412J-1D01*
G01X1558476Y408854D02*
G03X1558261Y409069I-215J0D01*
G01X1554360D02*
G03X1554145Y408854I0J-215D01*
G01X1554949Y408872D02*
G03X1554917Y408775I128J-96D01*
G01X1557666D02*
G03X1557634Y408872I-161J1D01*
G01X1562256Y422258D02*
G03I-709J0D01*
G01X1566419Y376903D02*
X1566798Y376794D01*
G01X1566503Y376588D02*
X1566627Y376614D01*
G01X1566419Y376903D02*
Y376588D01*
G01Y376903D02*
X1567630Y380180D01*
G01X1567708Y377013D02*
X1567336Y376793D01*
X1566926Y376646D01*
X1566459Y376588D01*
G01X1554648Y428635D02*
X1554501D01*
G01X1554091D02*
X1553992D01*
G01X1555665D02*
X1555567D01*
G01X1556223D02*
X1556125D01*
G01X1556551D02*
X1556453D01*
G01X1553123D02*
X1553024D01*
G01X1553861D02*
X1553763D01*
G01X1556059Y428837D02*
X1555731D01*
G01X1556043Y428904D02*
X1555747D01*
G01X1553418Y428987D02*
X1553123D01*
G01Y429088D02*
X1553434D01*
G01Y429339D02*
X1553123D01*
G01X1553024Y429423D02*
X1553418D01*
G01X1553763D02*
X1553861D01*
G01X1554550D02*
X1554648D01*
G01X1553992D02*
X1554140D01*
G01X1555830D02*
X1555961D01*
G01X1556453D02*
X1556551D01*
G01X1553418D02*
X1553500Y429406D01*
G01X1553484Y429322D02*
X1553434Y429339D01*
G01X1553500Y429406D02*
X1553566Y429356D01*
G01X1553500Y429004D02*
X1553418Y428987D01*
G01X1553517Y429289D02*
X1553484Y429322D01*
G01X1553566Y429356D02*
X1553615Y429289D01*
G01X1554140Y429423D02*
X1554550Y428753D01*
G01X1554501Y428635D02*
X1554091Y429322D01*
G01X1555961Y429423D02*
X1556223Y428635D01*
G01X1553533Y429239D02*
X1553517Y429289D01*
G01X1553615D02*
X1553631Y429239D01*
G01X1556125Y428635D02*
X1556059Y428837D01*
G01X1555895Y429356D02*
X1556043Y428904D01*
G01X1553024Y428635D02*
Y429423D01*
G01X1553123Y428987D02*
Y428635D01*
G01Y429339D02*
Y429088D01*
G01X1553533Y429189D02*
Y429239D01*
G01X1553631D02*
Y429172D01*
G01X1553763Y428635D02*
Y429423D01*
G01X1553861D02*
Y428635D01*
G01X1553992D02*
Y429423D01*
G01X1554091Y429322D02*
Y428635D01*
G01X1554550Y428753D02*
Y429423D01*
G01X1554648D02*
Y428635D01*
G01X1556354Y429172D02*
Y429306D01*
G01X1556453Y428635D02*
Y429289D01*
G01X1556551Y429423D02*
Y428635D01*
G01X1553517Y429138D02*
X1553533Y429189D01*
G01X1553631Y429172D02*
X1553615Y429121D01*
G01X1555747Y428904D02*
X1555895Y429356D01*
G01X1555731Y428837D02*
X1555665Y428635D01*
G01X1555567D02*
X1555830Y429423D01*
G01X1553615Y429121D02*
X1553566Y429054D01*
G01X1556354Y429306D02*
X1556453Y429423D01*
G01Y429289D02*
X1556354Y429172D01*
G01X1553484Y429105D02*
X1553517Y429138D01*
G01X1553566Y429054D02*
X1553500Y429004D01*
G01X1553434Y429088D02*
X1553484Y429105D01*
G01X1555661Y431313D02*
G03I-1200J0D01*
G01X1555169D02*
G03I-708J0D01*
G01X1562256Y426588D02*
G03I-709J0D01*
G01Y432100D02*
G03I-709J0D01*
G01X1557317Y438435D02*
X1557169D01*
G01X1557842D02*
X1557448D01*
G01X1558432D02*
X1558334D01*
G01X1554184D02*
X1554085D01*
G01X1554971D02*
X1554824D01*
G01X1554413D02*
X1554315D01*
G01X1556300D02*
X1556152D01*
G01X1556759D02*
X1556661D01*
G01X1553446D02*
X1553347D01*
G01X1557842Y438536D02*
X1557547D01*
G01X1556152D02*
X1556300D01*
G01X1551765Y438557D02*
X1553204D01*
G01X1556275D02*
X1560291D01*
G01X1563362D02*
X1567378D01*
G01X1556431Y438771D02*
X1556284D01*
G01X1553741Y438787D02*
X1553446D01*
G01X1556284Y438871D02*
X1556530D01*
G01X1553446Y438887D02*
X1553757D01*
G01X1556530Y439022D02*
X1556431D01*
G01X1556300Y439122D02*
X1556152D01*
G01X1557547D02*
X1557842D01*
G01X1553757Y439139D02*
X1553446D01*
G01X1553347Y439222D02*
X1553741D01*
G01X1554085D02*
X1554184D01*
G01X1554873D02*
X1554971D01*
G01X1554315D02*
X1554463D01*
G01X1556152D02*
X1556300D01*
G01X1556661D02*
X1556808D01*
G01X1557219D02*
X1557317D01*
G01X1557448D02*
X1557842D01*
G01X1558334D02*
X1558432D01*
G01X1565960Y439679D02*
X1564779D01*
G01X1558874D02*
X1557693D01*
G01X1556152Y438435D02*
X1556070Y438452D01*
G01X1553741Y439222D02*
X1553823Y439206D01*
G01X1556300Y439222D02*
X1556382Y439206D01*
G01X1557842Y439222D02*
X1557924Y439206D01*
G01X1556087Y438552D02*
X1556152Y438536D01*
G01X1556365Y439106D02*
X1556300Y439122D01*
G01X1557842D02*
X1557908Y439106D01*
G01X1553806Y439122D02*
X1553757Y439139D01*
G01X1556070Y438452D02*
X1556005Y438485D01*
G01X1556382Y439206D02*
X1556448Y439172D01*
G01X1557924Y439206D02*
X1557989Y439172D01*
G01X1556037Y438586D02*
X1556087Y438552D01*
G01X1556415Y439072D02*
X1556365Y439106D01*
G01X1557908D02*
X1557957Y439072D01*
G01X1557908Y438552D02*
X1557842Y438536D01*
G01X1556300D02*
X1556365Y438552D01*
G01X1556152Y439122D02*
X1556087Y439106D01*
G01X1557924Y438452D02*
X1557842Y438435D01*
G01X1556382Y438452D02*
X1556300Y438435D01*
G01X1556070Y439206D02*
X1556152Y439222D01*
G01X1553823Y438804D02*
X1553741Y438787D01*
G01X1556511Y441725D02*
X1560055D01*
G01X1563598D02*
X1567141D01*
G01X1553992Y456273D02*
X1555488D01*
G01X1561078D02*
X1562574D01*
G01X1554740Y457395D02*
X1553313D01*
G01X1564189Y458869D02*
X1559464D01*
G01X1557102D02*
X1552378D01*
G01X1563204Y461391D02*
X1560448D01*
G01X1556118D02*
X1553362D01*
G01X1553823Y439206D02*
X1553889Y439156D01*
G01X1553839Y439089D02*
X1553806Y439122D01*
G01X1556005Y438485D02*
X1555939Y438552D01*
G01X1556448Y439172D02*
X1556513Y439106D01*
G01X1557989Y439172D02*
X1558055Y439106D01*
G01X1553889Y439156D02*
X1553938Y439089D01*
G01X1556005Y438636D02*
X1556037Y438586D01*
G01X1557957Y439072D02*
X1557989Y439022D01*
G01X1554463Y439222D02*
X1554873Y438552D01*
G01X1556808Y439222D02*
X1557219Y438552D01*
G01X1554824Y438435D02*
X1554413Y439122D01*
G01X1557169Y438435D02*
X1556759Y439122D01*
G01X1557693Y439679D02*
X1556305Y442083D01*
G01X1564779Y439679D02*
X1563391Y442083D01*
G01X1555488Y456273D02*
X1556275Y454909D01*
G01X1562574Y456273D02*
X1563362Y454909D01*
G01X1555939Y438552D02*
X1555906Y438620D01*
G01X1558055Y439106D02*
X1558088Y439038D01*
G01X1553856D02*
X1553839Y439089D01*
G01X1553938D02*
X1553954Y439038D01*
G01X1556431Y439022D02*
X1556415Y439072D01*
G01X1555988Y438703D02*
X1556005Y438636D01*
G01X1557989Y439022D02*
X1558006Y438955D01*
G01X1555906Y438620D02*
X1555890Y438703D01*
G01X1556513Y439106D02*
X1556530Y439022D01*
G01X1558088Y439038D02*
X1558104Y438955D01*
G01X1551748Y458960D02*
Y476490D01*
G01X1552378Y460407D02*
Y438557D01*
G01X1553204D02*
Y443572D01*
G01Y445352D02*
Y450659D01*
G01Y452439D02*
Y454909D01*
G01X1553347Y438435D02*
Y439222D01*
G01X1553446Y438787D02*
Y438435D01*
G01Y439139D02*
Y438887D01*
G01X1553856Y438988D02*
Y439038D01*
G01X1553954D02*
Y438971D01*
G01X1554085Y438435D02*
Y439222D01*
G01X1554184D02*
Y438435D01*
G01X1554315D02*
Y439222D01*
G01X1554413Y439122D02*
Y438435D01*
G01X1554873Y438552D02*
Y439222D01*
G01X1554971D02*
Y438435D01*
G01X1555890Y438703D02*
Y438955D01*
G01X1555988D02*
Y438703D01*
G01X1556275Y454909D02*
Y452439D01*
G01Y450659D02*
Y445352D01*
G01Y443572D02*
Y438557D01*
G01X1556284Y438771D02*
Y438871D01*
G01X1556305Y442083D02*
Y443617D01*
G01Y445308D02*
Y450704D01*
G01Y452394D02*
Y455830D01*
G01X1556431Y438636D02*
Y438771D01*
G01X1556530Y438871D02*
Y438620D01*
G01X1556661Y438435D02*
Y439222D01*
G01X1556759Y439122D02*
Y438435D01*
G01X1557102Y438557D02*
Y460407D01*
G01X1557219Y438552D02*
Y439222D01*
G01X1557317D02*
Y438435D01*
G01X1557448D02*
Y439222D01*
G01X1557547Y438536D02*
Y439122D01*
G01X1558006Y438955D02*
Y438703D01*
G01X1558104Y438955D02*
Y438703D01*
G01X1558235Y438971D02*
Y439106D01*
G01X1558334Y438435D02*
Y439089D01*
G01X1558432Y439222D02*
Y438435D01*
G01X1559464Y460407D02*
Y438557D01*
G01X1560261Y455830D02*
Y452394D01*
G01Y450704D02*
Y445308D01*
G01Y443617D02*
Y442083D01*
G01X1560291Y438557D02*
Y443572D01*
G01Y445352D02*
Y450659D01*
G01Y452439D02*
Y454909D01*
G01X1563362D02*
Y452439D01*
G01Y450659D02*
Y445352D01*
G01Y443572D02*
Y438557D01*
G01X1563391Y442083D02*
Y443617D01*
G01Y445308D02*
Y450704D01*
G01Y452394D02*
Y455830D01*
G01X1564189Y438557D02*
Y460407D01*
G01X1555890Y438955D02*
X1555906Y439038D01*
G01X1558104Y438703D02*
X1558088Y438620D01*
G01X1556005Y439022D02*
X1555988Y438955D01*
G01X1556530Y438620D02*
X1556513Y438552D01*
G01X1558006Y438703D02*
X1557989Y438636D01*
G01X1553839Y438938D02*
X1553856Y438988D01*
G01X1553954Y438971D02*
X1553938Y438921D01*
G01X1556415Y438586D02*
X1556431Y438636D01*
G01X1555906Y439038D02*
X1555939Y439106D01*
G01X1558088Y438620D02*
X1558055Y438552D01*
G01X1553992Y456273D02*
X1553204Y454909D01*
G01X1561078Y456273D02*
X1560291Y454909D01*
G01X1560261Y442083D02*
X1558874Y439679D01*
G01X1556037Y439072D02*
X1556005Y439022D01*
G01X1557989Y438636D02*
X1557957Y438586D01*
G01X1553938Y438921D02*
X1553889Y438854D01*
G01X1558235Y439106D02*
X1558334Y439222D01*
G01Y439089D02*
X1558235Y438971D01*
G01X1553806Y438904D02*
X1553839Y438938D01*
G01X1555939Y439106D02*
X1556005Y439172D01*
G01X1556513Y438552D02*
X1556448Y438485D01*
G01X1558055Y438552D02*
X1557989Y438485D01*
G01X1553889Y438854D02*
X1553823Y438804D01*
G01X1556087Y439106D02*
X1556037Y439072D01*
G01X1556365Y438552D02*
X1556415Y438586D01*
G01X1557957D02*
X1557908Y438552D01*
G01X1556005Y439172D02*
X1556070Y439206D01*
G01X1556448Y438485D02*
X1556382Y438452D01*
G01X1557989Y438485D02*
X1557924Y438452D01*
G01X1553757Y438887D02*
X1553806Y438904D01*
G01X1555661Y441155D02*
G03I-1200J0D01*
G01X1555169Y436825D02*
G03I-708J0D01*
G01Y441155D02*
G03I-708J0D01*
G01X1556275Y443572D02*
G03Y445352I-1299J890D01*
G01X1553204D02*
G03Y443572I1299J-890D01*
G01X1555169Y445486D02*
G03I-708J0D01*
G01X1562256Y436431D02*
G03I-709J0D01*
G01Y440762D02*
G03I-709J0D01*
G01X1560291Y445352D02*
G03Y443572I1299J-890D01*
G01X1562256Y446273D02*
G03I-709J0D01*
G01X1563362Y443572D02*
G03Y445352I-1299J890D01*
G01X1556275Y450659D02*
G03Y452439I-1299J890D01*
G01X1553204D02*
G03Y450659I1299J-890D01*
G01X1555169Y450998D02*
G03I-708J0D01*
G01Y455329D02*
G03I-708J0D01*
G01X1556305Y455830D02*
G03X1554740Y457395I-1565J0D01*
G01X1551748Y458960D02*
G03X1553313Y457395I1565J0D01*
G01X1557102Y460407D02*
G03X1556118Y461391I-984J0D01*
G01X1553362D02*
G03X1552378Y460407I0J-984D01*
G01X1555169Y459659D02*
G03I-708J0D01*
G01X1560291Y452439D02*
G03Y450659I1299J-890D01*
G01X1562256Y450604D02*
G03I-709J0D01*
G01Y454935D02*
G03I-709J0D01*
G01X1560448Y461391D02*
G03X1559464Y460407I0J-984D01*
G01X1562256Y460447D02*
G03I-709J0D01*
G01X1556708Y463124D02*
G03I-1968J0D01*
G01X1563362Y450659D02*
G03Y452439I-1299J890D01*
G01X1563391Y455830D02*
G03X1560261I-1565J0D01*
G01X1564189Y460407D02*
G03X1563204Y461391I-984J0D01*
G01X1563795Y463124D02*
G03I-1969J0D01*
G01X1551765Y469009D02*
X1553204D01*
G01X1556275D02*
X1560291D01*
G01X1563362D02*
X1567378D01*
G01X1567719Y469403D02*
X1563021D01*
G01X1560632D02*
X1555934D01*
G01X1553546D02*
X1551748D01*
G01Y474128D02*
X1806328D01*
G01X1551765Y475309D02*
X1607902D01*
G01X1806315Y476490D02*
X1551748D01*
G01X1563362Y476883D02*
X1560291D01*
G01X1556275D02*
X1553204D01*
G01X1562181Y478065D02*
X1561472D01*
G01X1555094D02*
X1554385D01*
G01X1551765Y479049D02*
X1607902D01*
G01X1555094Y478065D02*
X1556275Y476883D01*
G01X1562181Y478065D02*
X1563362Y476883D01*
G01X1553546Y469403D02*
X1553330Y469683D01*
X1553204Y470000D01*
G01X1560632Y469403D02*
X1560416Y469683D01*
X1560291Y470000D01*
G01X1553175Y470661D02*
X1553221Y470202D01*
X1553347Y469777D01*
X1553546Y469403D01*
G01X1560261Y470661D02*
X1560307Y470202D01*
X1560434Y469777D01*
X1560632Y469403D01*
G01X1553175Y470242D02*
X1553182Y470118D01*
X1553204Y469995D01*
G01X1560261Y470242D02*
X1560269Y470118D01*
X1560291Y469995D01*
G01X1553175Y476490D02*
Y470242D01*
G01X1553204Y469009D02*
Y476883D01*
G01X1556275D02*
Y469009D01*
G01X1556305Y476490D02*
Y470242D01*
G01X1560261Y476490D02*
Y470242D01*
G01X1560291Y469009D02*
Y476883D01*
G01X1563362D02*
Y469009D01*
G01X1563391Y476490D02*
Y470242D01*
G01X1556305D02*
X1556297Y470119D01*
X1556275Y469995D01*
G01X1563391Y470242D02*
X1563384Y470119D01*
X1563362Y469995D01*
G01X1556275Y470000D02*
X1556148Y469680D01*
X1555934Y469403D01*
G01X1563362Y470000D02*
X1563235Y469680D01*
X1563021Y469403D01*
G01X1555934D02*
X1556132Y469778D01*
X1556259Y470202D01*
X1556305Y470661D01*
G01X1563021Y469403D02*
X1563219Y469778D01*
X1563346Y470202D01*
X1563391Y470661D01*
G01X1554385Y478065D02*
X1553204Y476883D01*
G01X1561472Y478065D02*
X1560291Y476883D01*
G01X1553546Y469403D02*
G03X1555934I1194J1012D01*
G01X1555169Y469502D02*
G03I-708J0D01*
G01Y465171D02*
G03I-708J0D01*
G01X1562256Y464777D02*
G03I-709J0D01*
G01X1560632Y469403D02*
G03X1563021I1194J1012D01*
G01X1567348Y442083D02*
X1565960Y439679D01*
G01X1507321Y576651D02*
X1505353D01*
G01X1508634Y575981D02*
X1507321Y576651D01*
G01X1527663Y575981D02*
X1526350Y576651D01*
G01X1509290Y575311D02*
X1508634Y575981D01*
G01X1510602Y578661D02*
X1511915Y577321D01*
G01X1528319Y575311D02*
X1527663Y575981D01*
G01X1529631Y578661D02*
X1531600Y576651D01*
G01X1509946Y573971D02*
X1509290Y575311D01*
G01X1528975Y573971D02*
X1528319Y575311D01*
G01X1511915Y577321D02*
X1513227Y573971D01*
G01X1509946Y557887D02*
Y573971D01*
G01X1513227D02*
Y557887D01*
G01X1518476D02*
Y579332D01*
G01X1521757D02*
Y577321D01*
G01Y574641D02*
Y557887D01*
G01X1528975D02*
Y573971D01*
G01X1532256Y557887D02*
X1528975D01*
G01X1521757D02*
X1518476D01*
G01X1513227D02*
X1509946D01*
G01X1536849Y576651D02*
X1534880D01*
G01X1526350D02*
X1525038D01*
G01X1508634Y579332D02*
X1510602Y578661D01*
G01X1527663Y579332D02*
X1529631Y578661D01*
G01X1532256Y573971D02*
Y557887D01*
G01X1506009Y579332D02*
X1508634D01*
G01X1518476D02*
X1521757D01*
G01X1525038D02*
X1527663D01*
G01X1535537D02*
X1538161D01*
G01X1532912Y575311D02*
X1532256Y573971D01*
G01X1521757Y577321D02*
X1523069Y578661D01*
G01Y575981D02*
X1521757Y574641D01*
G01X1531600Y576651D02*
X1533568Y578661D01*
G01Y575981D02*
X1532912Y575311D01*
G01X1534880Y576651D02*
X1533568Y575981D01*
G01X1523069Y578661D02*
X1525038Y579332D01*
G01Y576651D02*
X1523069Y575981D01*
G01X1533568Y578661D02*
X1535537Y579332D01*
G01X1538817Y575311D02*
X1538161Y575981D01*
G01X1542754Y557887D02*
X1539474D01*
G01X1538161Y579332D02*
X1540130Y578661D01*
G01X1538161Y575981D02*
X1536849Y576651D01*
G01X1540130Y578661D02*
X1541442Y577321D01*
G01X1539474Y573971D02*
X1538817Y575311D01*
G01X1541442Y577321D02*
X1542754Y573971D01*
G01X1539474Y557887D02*
Y573971D01*
G01X1542754D02*
Y557887D01*
G01X1770996Y548970D02*
X1566272D01*
G01D02*
Y811293D01*
G01D02*
X1770996D01*
G01X1554471Y884856D02*
X1537339D01*
G01X1550534Y908478D02*
Y884856D01*
G01D02*
X1708014D01*
G01X1550534Y937072D02*
G03X1567109Y917634I19685J0D01*
G01X1550534Y937072D02*
G03X1567109Y917634I19685J0D01*
G01X1550534Y979344D02*
Y937072D01*
G01Y979344D02*
Y937072D01*
G01Y979344D02*
G03X1542659Y987218I-7874J0D01*
G01X1550534Y979344D02*
G03X1542659Y987218I-7874J0D01*
G01X1550534Y983281D02*
Y1022258D01*
G01X1613912Y-879845D02*
Y-898782D01*
G01X1591530Y-340790D02*
G03I-11810J0D01*
G01X1585625D02*
G03I-5905J0D01*
G01X1648617Y-947D02*
X1589562D01*
G01X1648617D02*
X1589562D01*
G01X1567708Y376882D02*
X1567788Y376859D01*
G01X1594850Y376588D02*
X1594973Y376614D01*
G01X1580676Y376588D02*
X1580800Y376614D01*
G01X1586426Y378646D02*
X1586800Y378713D01*
G01X1572252Y378646D02*
X1572626Y378713D01*
G01X1567049Y376903D02*
X1580592D01*
G01X1581222D02*
X1594765D01*
G01X1595395D02*
X1608391D01*
G01X1596055Y377076D02*
X1593693D01*
G01X1581882D02*
X1579519D01*
G01X1574632D02*
X1579159D01*
G01X1588805D02*
X1593332D01*
G01X1568696Y378950D02*
X1572233D01*
G01X1582869D02*
X1586406D01*
G01X1582492Y380726D02*
X1581901D01*
G01X1568319D02*
X1567728D01*
G01X1572649D02*
X1573240D01*
G01X1586822D02*
X1587413D01*
G01X1593332Y384462D02*
X1588805D01*
G01X1579159D02*
X1574632D01*
G01X1579519D02*
X1581882D01*
G01X1593693D02*
X1596055D01*
G01X1568696Y378645D02*
X1568302Y378715D01*
G01X1582869Y378645D02*
X1582476Y378715D01*
G01X1580592Y376903D02*
X1580972Y376794D01*
G01X1581882Y376882D02*
X1581961Y376859D01*
G01X1594765Y376903D02*
X1595145Y376794D01*
G01X1567630Y380180D02*
X1568184Y379976D01*
G01X1581804Y380180D02*
X1582358Y379976D01*
G01X1573919Y376903D02*
X1574169Y376794D01*
G01X1588092Y376903D02*
X1588343Y376794D01*
G01X1574236Y376687D02*
X1574341Y376613D01*
X1574465Y376588D01*
G01X1588409Y376687D02*
X1588515Y376613D01*
X1588638Y376588D01*
G01X1568663Y378554D02*
X1568668Y378548D01*
X1568682Y378533D01*
X1568698Y378508D01*
X1568711Y378474D01*
X1568717Y378432D01*
X1568714Y378382D01*
X1568701Y378324D01*
X1568680Y378260D01*
X1568652Y378192D01*
X1568617Y378119D01*
X1568574Y378041D01*
X1568526Y377963D01*
X1568481Y377896D01*
X1568441Y377840D01*
X1568408Y377796D01*
X1568382Y377763D01*
X1568366Y377744D01*
X1568361Y377738D01*
G01X1582836Y378554D02*
X1582841Y378548D01*
X1582855Y378533D01*
X1582872Y378508D01*
X1582885Y378474D01*
X1582890Y378432D01*
X1582887Y378382D01*
X1582874Y378324D01*
X1582854Y378260D01*
X1582826Y378192D01*
X1582790Y378119D01*
X1582747Y378041D01*
X1582700Y377963D01*
X1582654Y377896D01*
X1582615Y377840D01*
X1582581Y377796D01*
X1582555Y377763D01*
X1582539Y377744D01*
X1582534Y377738D01*
G01X1572566Y377741D02*
X1572561Y377747D01*
X1572545Y377767D01*
X1572519Y377799D01*
X1572486Y377843D01*
X1572447Y377897D01*
X1572404Y377962D01*
X1572358Y378038D01*
X1572313Y378117D01*
X1572278Y378193D01*
X1572250Y378260D01*
X1572229Y378323D01*
X1572217Y378380D01*
X1572214Y378430D01*
X1572219Y378471D01*
X1572232Y378505D01*
X1572248Y378529D01*
X1572261Y378544D01*
X1572267Y378550D01*
G01X1586739Y377741D02*
X1586734Y377747D01*
X1586718Y377767D01*
X1586693Y377799D01*
X1586659Y377843D01*
X1586621Y377897D01*
X1586577Y377962D01*
X1586531Y378038D01*
X1586487Y378117D01*
X1586451Y378193D01*
X1586423Y378260D01*
X1586402Y378323D01*
X1586390Y378380D01*
X1586387Y378430D01*
X1586393Y378471D01*
X1586405Y378505D01*
X1586421Y378529D01*
X1586435Y378544D01*
X1586440Y378550D01*
G01X1574236Y376687D02*
X1574169Y376794D01*
G01X1588409Y376687D02*
X1588343Y376794D01*
G01X1572267Y378550D02*
X1572566Y377741D01*
G01X1573258Y377003D02*
X1572626Y378713D01*
G01X1573919Y376903D02*
X1572784Y379976D01*
G01X1574169Y376794D02*
X1572968Y380044D01*
G01X1573337Y380180D02*
X1574548Y376903D01*
G01X1586440Y378550D02*
X1586739Y377741D01*
G01X1587432Y377003D02*
X1586800Y378713D01*
G01X1588092Y376903D02*
X1586957Y379976D01*
G01X1588343Y376794D02*
X1587141Y380044D01*
G01X1587511Y380180D02*
X1588722Y376903D01*
G01X1567049D02*
Y376588D01*
G01X1567708Y376822D02*
Y384462D01*
G01X1567728Y408854D02*
Y380726D01*
G01X1568122Y408854D02*
Y380726D01*
G01X1568302Y378715D02*
Y408775D01*
G01X1568319Y380726D02*
Y408854D01*
G01X1568696Y378645D02*
Y408775D01*
G01X1569090D02*
Y376588D01*
G01X1571839D02*
Y408775D01*
G01X1572233D02*
Y378950D01*
G01X1572626Y408775D02*
Y378713D01*
G01X1572649Y408854D02*
Y380726D01*
G01X1572846Y408854D02*
Y380726D01*
G01X1573240D02*
Y408854D01*
G01X1573919Y376903D02*
Y376588D01*
G01X1574548Y376903D02*
Y376588D01*
G01X1574632Y384462D02*
Y376588D01*
G01X1579159Y384462D02*
Y376588D01*
G01X1579519Y384462D02*
Y376588D01*
G01X1580592Y376903D02*
Y376588D01*
G01X1581222Y376903D02*
Y376588D01*
G01X1581882Y376822D02*
Y384462D01*
G01X1581901Y408854D02*
Y380726D01*
G01X1582295Y408854D02*
Y380726D01*
G01X1582476Y378715D02*
Y408775D01*
G01X1582492Y380726D02*
Y408854D01*
G01X1582869Y378645D02*
Y408775D01*
G01X1583263D02*
Y376588D01*
G01X1586012D02*
Y408775D01*
G01X1586406D02*
Y378950D01*
G01X1586800Y408775D02*
Y378713D01*
G01X1586822Y408854D02*
Y380726D01*
G01X1587019Y408854D02*
Y380726D01*
G01X1587413D02*
Y408854D01*
G01X1588092Y376903D02*
Y376588D01*
G01X1588722Y376903D02*
Y376588D01*
G01X1588805Y384462D02*
Y376588D01*
G01X1593332Y384462D02*
Y376588D01*
G01X1593693Y384462D02*
Y376588D01*
G01X1594765Y376903D02*
Y376588D01*
G01X1595395Y376903D02*
Y376588D01*
G01X1568000Y380044D02*
X1566798Y376794D01*
G01X1568184Y379976D02*
X1567049Y376903D01*
G01X1568302Y378715D02*
X1567708Y377108D01*
G01X1568174Y377233D02*
X1568696Y378645D01*
G01X1580592Y376903D02*
X1581804Y380180D01*
G01X1582173Y380044D02*
X1580972Y376794D01*
G01X1582358Y379976D02*
X1581222Y376903D01*
G01X1582476Y378715D02*
X1581882Y377108D01*
G01X1582348Y377233D02*
X1582869Y378645D01*
G01X1594765Y376903D02*
X1595977Y380180D01*
G01X1596346Y380044D02*
X1595145Y376794D01*
G01X1596531Y379976D02*
X1595395Y376903D01*
G01X1568174Y377233D02*
X1568095Y377101D01*
X1567971Y376978D01*
X1567788Y376859D01*
G01X1566798Y376794D02*
X1566732Y376687D01*
X1566627Y376614D01*
G01X1582348Y377233D02*
X1582269Y377101D01*
X1582145Y376978D01*
X1581961Y376859D01*
G01X1580972Y376794D02*
X1580905Y376687D01*
X1580800Y376614D01*
G01X1595145Y376794D02*
X1595078Y376687D01*
X1594974Y376614D01*
G01X1581882Y377013D02*
X1581509Y376793D01*
X1581100Y376646D01*
X1580632Y376588D01*
G01X1596055Y377013D02*
X1595682Y376793D01*
X1595273Y376646D01*
X1594806Y376588D01*
G01X1567788Y376859D02*
X1567763Y376846D01*
X1567736Y376833D01*
X1567708Y376822D01*
G01X1581961Y376859D02*
X1581936Y376846D01*
X1581909Y376833D01*
X1581882Y376822D01*
G01X1567049Y376903D02*
X1566953Y376862D01*
X1566872Y376828D01*
X1566818Y376804D01*
X1566798Y376794D01*
G01X1581222Y376903D02*
X1581126Y376862D01*
X1581045Y376828D01*
X1580991Y376804D01*
X1580972Y376794D01*
G01X1595395Y376903D02*
X1595299Y376862D01*
X1595219Y376828D01*
X1595165Y376804D01*
X1595145Y376794D01*
G01X1572784Y379976D02*
X1573337Y380180D01*
G01X1586957Y379976D02*
X1587511Y380180D01*
G01X1574169Y376794D02*
X1574548Y376903D01*
G01X1588343Y376794D02*
X1588722Y376903D01*
G01X1568663Y378556D02*
G03X1568696Y378950I-2329J393D01*
G01X1567706Y377028D02*
G03X1568361Y377738I-1372J1923D01*
G01X1568184Y379976D02*
G03X1568319Y380726I-2030J753D01*
G01X1568000Y380044D02*
G03X1568122Y380726I-1847J682D01*
G01X1567630Y380180D02*
G03X1567728Y380726I-1477J547D01*
G01X1566503Y376588D02*
G03X1566798Y376794I-1J315D01*
G01X1574169D02*
G03X1574465Y376588I296J109D01*
G01X1580676D02*
G03X1580972Y376794I0J315D01*
G01X1582836Y378556D02*
G03X1582869Y378950I-2329J393D01*
G01X1581879Y377028D02*
G03X1582534Y377738I-1372J1923D01*
G01X1572566Y377741D02*
G03X1574595Y376588I2029J1209D01*
G01X1572233Y378950D02*
G03X1572267Y378550I2362J-1D01*
G01X1582358Y379976D02*
G03X1582492Y380726I-2032J750D01*
G01X1572649D02*
G03X1572784Y379976I2165J3D01*
G01X1582173Y380044D02*
G03X1582295Y380726I-1847J682D01*
G01X1572846D02*
G03X1572968Y380044I1969J0D01*
G01X1573240Y380726D02*
G03X1573337Y380180I1575J-2D01*
G01X1581804D02*
G03X1581901Y380726I-1478J544D01*
G01X1588343Y376794D02*
G03X1588638Y376588I295J109D01*
G01X1586739Y377741D02*
G03X1588768Y376588I2029J1209D01*
G01X1586406Y378950D02*
G03X1586440Y378550I2362J-1D01*
G01X1586822Y380726D02*
G03X1586957Y379976I2165J3D01*
G01X1587019Y380726D02*
G03X1587141Y380044I1969J0D01*
G01X1587413Y380726D02*
G03X1587511Y380180I1575J1D01*
G01X1594850Y376588D02*
G03X1595145Y376794I-1J315D01*
G01X1583263Y408775D02*
X1582476D01*
G01X1569090D02*
X1568302D01*
G01X1571839D02*
X1572626D01*
G01X1586012D02*
X1586800D01*
G01X1567728Y408854D02*
X1568319D01*
G01X1572649D02*
X1573240D01*
G01X1581901D02*
X1582492D01*
G01X1586822D02*
X1587413D01*
G01X1585980Y408872D02*
X1583295D01*
G01X1571807D02*
X1569122D01*
G01X1568534Y409069D02*
X1572434D01*
G01X1582707D02*
X1586608D01*
G01Y409265D02*
X1582707D01*
G01X1572434D02*
X1568534D01*
G01X1586608Y409659D02*
X1582707D01*
G01X1572434D02*
X1568534D01*
G01X1568992Y409266D02*
X1569001Y409228D01*
X1569028Y409128D01*
X1569070Y408998D01*
X1569122Y408872D01*
G01X1583165Y409266D02*
X1583174Y409228D01*
X1583202Y409128D01*
X1583243Y408998D01*
X1583295Y408872D01*
G01X1568992Y409266D02*
X1568979Y409318D01*
X1568947Y409461D01*
X1568908Y409659D01*
G01X1583165Y409266D02*
X1583152Y409318D01*
X1583121Y409461D01*
X1583081Y409659D01*
G01X1568534Y409069D02*
Y409659D01*
G01X1572434Y409069D02*
Y409659D01*
G01X1582707Y409069D02*
Y409659D01*
G01X1586608Y409069D02*
Y409659D01*
G01X1571937Y409266D02*
X1571949Y409318D01*
X1571981Y409461D01*
X1572021Y409659D01*
G01X1586110Y409266D02*
X1586122Y409318D01*
X1586154Y409461D01*
X1586194Y409659D01*
G01X1571807Y408872D02*
X1571861Y409006D01*
X1571903Y409138D01*
X1571928Y409232D01*
X1571937Y409266D01*
G01X1585980Y408872D02*
X1586035Y409006D01*
X1586076Y409138D01*
X1586102Y409232D01*
X1586110Y409266D01*
G01X1568908Y409659D02*
G03X1568302Y408775I342J-884D01*
G01X1568534Y409659D02*
G03X1567728Y408854I-1J-805D01*
G01X1568992Y409266D02*
G03X1568696Y408775I258J-490D01*
G01X1568534Y409265D02*
G03X1568122Y408854I-1J-411D01*
G01X1568534Y409069D02*
G03X1568319Y408854I0J-215D01*
G01X1569122Y408872D02*
G03X1569090Y408775I129J-96D01*
G01X1572626D02*
G03X1572021Y409659I-948J0D01*
G01X1573240Y408854D02*
G03X1572434Y409659I-806J-1D01*
G01X1572233Y408775D02*
G03X1571937Y409266I-555J0D01*
G01X1572846Y408854D02*
G03X1572434Y409265I-412J-1D01*
G01X1572649Y408854D02*
G03X1572434Y409069I-215J0D01*
G01X1571839Y408775D02*
G03X1571807Y408872I-161J1D01*
G01X1576429Y422258D02*
G03I-709J0D01*
G01X1586800Y408775D02*
G03X1586194Y409659I-948J0D01*
G01X1583081D02*
G03X1582476Y408775I343J-884D01*
G01X1582707Y409659D02*
G03X1581901Y408854I-1J-805D01*
G01X1587413D02*
G03X1586608Y409659I-805J0D01*
G01X1586406Y408775D02*
G03X1586110Y409266I-554J0D01*
G01X1583165D02*
G03X1582869Y408775I258J-491D01*
G01X1582707Y409265D02*
G03X1582295Y408854I0J-412D01*
G01X1587019D02*
G03X1586608Y409265I-412J-1D01*
G01X1586822Y408854D02*
G03X1586608Y409069I-215J0D01*
G01X1582707D02*
G03X1582492Y408854I0J-215D01*
G01X1583295Y408872D02*
G03X1583263Y408775I129J-96D01*
G01X1586012D02*
G03X1585980Y408872I-161J1D01*
G01X1590602Y422258D02*
G03I-708J0D01*
G01X1623196Y376588D02*
X1623320Y376614D01*
G01X1609023Y376588D02*
X1609147Y376614D01*
G01X1615146Y378713D02*
X1614772Y378646D01*
G01X1600599D02*
X1600973Y378713D01*
G01X1608785Y376588D02*
X1665084D01*
G01X1608785Y376903D02*
X1608939D01*
G01X1609569D02*
X1623112D01*
G01X1623742D02*
X1637285D01*
G01X1624401Y377076D02*
X1622039D01*
G01X1610228D02*
X1608785D01*
G01X1602978D02*
X1608391D01*
G01X1617151D02*
X1621679D01*
G01X1597043Y378950D02*
X1600579D01*
G01X1611216D02*
X1614752D01*
G01X1625389D02*
X1628926D01*
G01X1625011Y380726D02*
X1624421D01*
G01X1596665D02*
X1596074D01*
G01X1600996D02*
X1601586D01*
G01X1610248D02*
X1610838D01*
G01X1615169D02*
X1615759D01*
G01X1621679Y384462D02*
X1617151D01*
G01X1610228D02*
X1608785D01*
G01X1608391D02*
X1602978D01*
G01X1622039D02*
X1624401D01*
G01X1597043Y378645D02*
X1596649Y378715D01*
G01X1611216Y378645D02*
X1610822Y378715D01*
G01X1625389Y378645D02*
X1624995Y378715D01*
G01X1596055Y376882D02*
X1596135Y376859D01*
G01X1608939Y376903D02*
X1609318Y376794D01*
G01X1610228Y376882D02*
X1610308Y376859D01*
G01X1623112Y376903D02*
X1623491Y376794D01*
G01X1624401Y376882D02*
X1624481Y376859D01*
G01X1595977Y380180D02*
X1596531Y379976D01*
G01X1610150Y380180D02*
X1610704Y379976D01*
G01X1624323Y380180D02*
X1624877Y379976D01*
G01X1602265Y376903D02*
X1602516Y376794D01*
G01X1616439Y376903D02*
X1616689Y376794D01*
G01X1602583Y376687D02*
X1602688Y376613D01*
X1602811Y376588D01*
G01X1616756Y376687D02*
X1616861Y376613D01*
X1616984Y376588D01*
G01X1597009Y378554D02*
X1597015Y378548D01*
X1597028Y378533D01*
X1597045Y378508D01*
X1597058Y378474D01*
X1597063Y378432D01*
X1597060Y378382D01*
X1597048Y378324D01*
X1597027Y378260D01*
X1596999Y378192D01*
X1596963Y378119D01*
X1596921Y378041D01*
X1596873Y377963D01*
X1596828Y377896D01*
X1596788Y377840D01*
X1596754Y377796D01*
X1596728Y377763D01*
X1596712Y377744D01*
X1596708Y377738D01*
G01X1611182Y378554D02*
X1611188Y378548D01*
X1611202Y378533D01*
X1611218Y378508D01*
X1611231Y378474D01*
X1611237Y378432D01*
X1611234Y378382D01*
X1611221Y378324D01*
X1611200Y378260D01*
X1611172Y378192D01*
X1611137Y378119D01*
X1611094Y378041D01*
X1611046Y377963D01*
X1611001Y377896D01*
X1610961Y377840D01*
X1610928Y377796D01*
X1610902Y377763D01*
X1610885Y377744D01*
X1610881Y377738D01*
G01X1625356Y378554D02*
X1625361Y378548D01*
X1625375Y378533D01*
X1625391Y378508D01*
X1625404Y378474D01*
X1625410Y378432D01*
X1625407Y378382D01*
X1625394Y378324D01*
X1625373Y378260D01*
X1625345Y378192D01*
X1625310Y378119D01*
X1625267Y378041D01*
X1625219Y377963D01*
X1625174Y377896D01*
X1625134Y377840D01*
X1625101Y377796D01*
X1625075Y377763D01*
X1625059Y377744D01*
X1625054Y377738D01*
G01X1600912Y377741D02*
X1600907Y377747D01*
X1600891Y377767D01*
X1600866Y377799D01*
X1600833Y377843D01*
X1600794Y377897D01*
X1600750Y377962D01*
X1600704Y378038D01*
X1600660Y378117D01*
X1600624Y378193D01*
X1600596Y378260D01*
X1600576Y378323D01*
X1600563Y378380D01*
X1600560Y378430D01*
X1600566Y378471D01*
X1600578Y378505D01*
X1600595Y378529D01*
X1600608Y378544D01*
X1600613Y378550D01*
G01X1615085Y377741D02*
X1615080Y377747D01*
X1615065Y377767D01*
X1615039Y377799D01*
X1615006Y377843D01*
X1614967Y377897D01*
X1614923Y377962D01*
X1614877Y378038D01*
X1614833Y378117D01*
X1614797Y378193D01*
X1614769Y378260D01*
X1614749Y378323D01*
X1614737Y378380D01*
X1614734Y378430D01*
X1614739Y378471D01*
X1614752Y378505D01*
X1614768Y378529D01*
X1614781Y378544D01*
X1614787Y378550D01*
G01X1602583Y376687D02*
X1602516Y376794D01*
G01X1616756Y376687D02*
X1616689Y376794D01*
G01X1600613Y378550D02*
X1600912Y377741D01*
G01X1601605Y377003D02*
X1600973Y378713D01*
G01X1602265Y376903D02*
X1601130Y379976D01*
G01X1602516Y376794D02*
X1601315Y380044D01*
G01X1601684Y380180D02*
X1602895Y376903D01*
G01X1614787Y378550D02*
X1615085Y377741D01*
G01X1615778Y377003D02*
X1615146Y378713D01*
G01X1616439Y376903D02*
X1615303Y379976D01*
G01X1615488Y380044D02*
X1616689Y376794D01*
G01X1615857Y380180D02*
X1617068Y376903D01*
G01X1596055Y384462D02*
Y376822D01*
G01X1596074Y408854D02*
Y380726D01*
G01X1596468Y408854D02*
Y380726D01*
G01X1596649Y378715D02*
Y408775D01*
G01X1596665Y380726D02*
Y408854D01*
G01X1597043Y408775D02*
Y378645D01*
G01X1597436Y408775D02*
Y376588D01*
G01X1600185Y408775D02*
Y376588D01*
G01X1600579Y408775D02*
Y378950D01*
G01X1600973Y408775D02*
Y378713D01*
G01X1600996Y408854D02*
Y380726D01*
G01X1601193Y408854D02*
Y380726D01*
G01X1601586D02*
Y408854D01*
G01X1602265Y376903D02*
Y376588D01*
G01X1602895Y376903D02*
Y376588D01*
G01X1602978Y384462D02*
Y376588D01*
G01X1608391D02*
Y415171D01*
G01X1608785D02*
Y376588D01*
G01X1608939Y376903D02*
Y376588D01*
G01X1609569Y376903D02*
Y376588D01*
G01X1610228Y376822D02*
Y384462D01*
G01X1610248Y408854D02*
Y380726D01*
G01X1610641Y408854D02*
Y380726D01*
G01X1610822Y378715D02*
Y408775D01*
G01X1610838Y380726D02*
Y408854D01*
G01X1611216Y408775D02*
Y378645D01*
G01X1611609Y408775D02*
Y376588D01*
G01X1614359Y408775D02*
Y376588D01*
G01X1614752Y408775D02*
Y378950D01*
G01X1615146Y408775D02*
Y378713D01*
G01X1615169Y408854D02*
Y380726D01*
G01X1615366D02*
Y408854D01*
G01X1615759Y380726D02*
Y408854D01*
G01X1616439Y376903D02*
Y376588D01*
G01X1617068D02*
Y376903D01*
G01X1617151Y384462D02*
Y376588D01*
G01X1621679Y384462D02*
Y376588D01*
G01X1622039Y384462D02*
Y376588D01*
G01X1623112Y376903D02*
Y376588D01*
G01X1623742Y376903D02*
Y376588D01*
G01X1624401Y376822D02*
Y384462D01*
G01X1624421Y408854D02*
Y380726D01*
G01X1624815Y408854D02*
Y380726D01*
G01X1624995Y378715D02*
Y408775D01*
G01X1625011Y380726D02*
Y408854D01*
G01X1625389Y378645D02*
Y408775D01*
G01X1596649Y378715D02*
X1596055Y377108D01*
G01X1597043Y378645D02*
X1596521Y377233D01*
G01X1608939Y376903D02*
X1610150Y380180D01*
G01X1610519Y380044D02*
X1609318Y376794D01*
G01X1610704Y379976D02*
X1609569Y376903D01*
G01X1610822Y378715D02*
X1610228Y377108D01*
G01X1611216Y378645D02*
X1610694Y377233D01*
G01X1623112Y376903D02*
X1624323Y380180D01*
G01X1624693Y380044D02*
X1623491Y376794D01*
G01X1624877Y379976D02*
X1623742Y376903D01*
G01X1624995Y378715D02*
X1624401Y377108D01*
G01X1624867Y377233D02*
X1625389Y378645D01*
G01X1596521Y377233D02*
X1596442Y377101D01*
X1596318Y376978D01*
X1596135Y376859D01*
G01X1610694Y377233D02*
X1610615Y377101D01*
X1610491Y376978D01*
X1610308Y376859D01*
G01X1609318Y376794D02*
X1609251Y376687D01*
X1609147Y376614D01*
G01X1624867Y377233D02*
X1624788Y377101D01*
X1624664Y376978D01*
X1624481Y376859D01*
G01X1623491Y376794D02*
X1623424Y376687D01*
X1623320Y376614D01*
G01X1609251Y376687D02*
X1609318Y376794D01*
G01X1610228Y377013D02*
X1609856Y376793D01*
X1609446Y376646D01*
X1608979Y376588D01*
G01X1624401Y377013D02*
X1624029Y376793D01*
X1623619Y376646D01*
X1623152Y376588D01*
G01X1596135Y376859D02*
X1596109Y376846D01*
X1596082Y376833D01*
X1596055Y376822D01*
G01X1610308Y376859D02*
X1610256Y376833D01*
X1610228Y376822D01*
G01X1624481Y376859D02*
X1624456Y376846D01*
X1624429Y376833D01*
X1624401Y376822D01*
G01X1609569Y376903D02*
X1609472Y376862D01*
X1609392Y376828D01*
X1609338Y376804D01*
X1609318Y376794D01*
G01X1623742Y376903D02*
X1623646Y376862D01*
X1623565Y376828D01*
X1623511Y376804D01*
X1623491Y376794D01*
G01X1601130Y379976D02*
X1601684Y380180D01*
G01X1615303Y379976D02*
X1615857Y380180D01*
G01X1602516Y376794D02*
X1602895Y376903D01*
G01X1616689Y376794D02*
X1617068Y376903D01*
G01X1600912Y377741D02*
G03X1602941Y376588I2029J1209D01*
G01X1600579Y378950D02*
G03X1600613Y378550I2362J-1D01*
G01X1597009Y378554D02*
G03X1597043Y378950I-2328J399D01*
G01X1596052Y377028D02*
G03X1596708Y377738I-1370J1924D01*
G01X1611182Y378554D02*
G03X1611216Y378950I-2328J399D01*
G01X1610225Y377028D02*
G03X1610881Y377738I-1370J1924D01*
G01X1596531Y379976D02*
G03X1596665Y380726I-2031J750D01*
G01X1600996D02*
G03X1601130Y379976I2165J0D01*
G01X1610704D02*
G03X1610838Y380726I-2031J750D01*
G01X1596346Y380044D02*
G03X1596468Y380726I-1846J682D01*
G01X1601193D02*
G03X1601315Y380044I1968J0D01*
G01X1610519D02*
G03X1610641Y380726I-1846J682D01*
G01X1595977Y380180D02*
G03X1596074Y380726I-1478J544D01*
G01X1601586D02*
G03X1601684Y380180I1575J1D01*
G01X1610150D02*
G03X1610248Y380726I-1477J547D01*
G01X1602516Y376794D02*
G03X1602811Y376588I296J109D01*
G01X1609023D02*
G03X1609318Y376794I-1J315D01*
G01X1615085Y377741D02*
G03X1617115Y376588I2029J1209D01*
G01X1614752Y378950D02*
G03X1614787Y378550I2362J5D01*
G01X1625356Y378554D02*
G03X1625389Y378950I-2330J394D01*
G01X1624398Y377028D02*
G03X1625054Y377738I-1370J1924D01*
G01X1615169Y380726D02*
G03X1615303Y379976I2165J0D01*
G01X1624877D02*
G03X1625011Y380726I-2031J750D01*
G01X1615366D02*
G03X1615488Y380044I1968J0D01*
G01X1624693D02*
G03X1624815Y380726I-1847J682D01*
G01X1624323Y380180D02*
G03X1624421Y380726I-1477J547D01*
G01X1615759D02*
G03X1615857Y380180I1575J1D01*
G01X1616689Y376794D02*
G03X1616984Y376588I296J109D01*
G01X1623196D02*
G03X1623491Y376794I-1J315D01*
G01X1608391Y403524D02*
X1607902D01*
G01X1608785D02*
X1608458D01*
G01X1625783Y408775D02*
X1624995D01*
G01X1597436D02*
X1596649D01*
G01X1600185D02*
X1600973D01*
G01X1610822D02*
X1611609D01*
G01X1614359D02*
X1615146D01*
G01X1610838Y408854D02*
X1610248D01*
G01X1596074D02*
X1596665D01*
G01X1600996D02*
X1601586D01*
G01X1615169D02*
X1615759D01*
G01X1624421D02*
X1625011D01*
G01X1614326Y408872D02*
X1611642D01*
G01X1600153D02*
X1597469D01*
G01X1596880Y409069D02*
X1600781D01*
G01X1611053D02*
X1614954D01*
G01X1625226D02*
X1629127D01*
G01Y409265D02*
X1625226D01*
G01X1614954D02*
X1611053D01*
G01X1600781D02*
X1596880D01*
G01X1629127Y409659D02*
X1625226D01*
G01X1614954D02*
X1611053D01*
G01X1600781D02*
X1596880D01*
G01X1665084Y411762D02*
X1608785D01*
G01X1665084Y411959D02*
X1608785D01*
G01X1665084Y414580D02*
X1608785D01*
G01X1665084Y415171D02*
X1608458D01*
G01X1597338Y409266D02*
X1597348Y409228D01*
X1597375Y409128D01*
X1597416Y408998D01*
X1597469Y408872D01*
G01X1611511Y409266D02*
X1611521Y409228D01*
X1611548Y409128D01*
X1611589Y408998D01*
X1611642Y408872D01*
G01X1597338Y409266D02*
X1597326Y409318D01*
X1597294Y409461D01*
X1597254Y409659D01*
G01X1625685Y409266D02*
X1625672Y409318D01*
X1625640Y409461D01*
X1625601Y409659D01*
G01X1611428D02*
X1611467Y409463D01*
X1611499Y409318D01*
X1611511Y409266D01*
G01X1596880Y409069D02*
Y409659D01*
G01X1600781Y409069D02*
Y409659D01*
G01X1607902Y403524D02*
Y479049D01*
G01X1608458D02*
Y403524D01*
G01X1611053Y409069D02*
Y409659D01*
G01X1614954Y409069D02*
Y409659D01*
G01X1625226Y409069D02*
Y409659D01*
G01X1614540D02*
X1614501Y409462D01*
X1614469Y409318D01*
X1614456Y409266D01*
G01X1600283D02*
X1600296Y409318D01*
X1600328Y409461D01*
X1600367Y409659D01*
G01X1600153Y408872D02*
X1600208Y409006D01*
X1600249Y409138D01*
X1600275Y409232D01*
X1600283Y409266D01*
G01X1614326Y408872D02*
X1614381Y409006D01*
X1614422Y409138D01*
X1614448Y409232D01*
X1614456Y409266D01*
G01X1600973Y408775D02*
G03X1600367Y409659I-948J0D01*
G01X1597254D02*
G03X1596649Y408775I343J-884D01*
G01X1596880Y409659D02*
G03X1596074Y408854I0J-806D01*
G01X1601586D02*
G03X1600781Y409659I-805J0D01*
G01X1600579Y408775D02*
G03X1600283Y409266I-554J1D01*
G01X1597338D02*
G03X1597043Y408775I259J-490D01*
G01X1596880Y409265D02*
G03X1596468Y408854I0J-412D01*
G01X1601193D02*
G03X1600781Y409265I-412J-1D01*
G01X1600996Y408854D02*
G03X1600781Y409069I-215J0D01*
G01X1596880D02*
G03X1596665Y408854I0J-215D01*
G01X1597469Y408872D02*
G03X1597436Y408775I128J-98D01*
G01X1600185D02*
G03X1600153Y408872I-160J1D01*
G01X1604776Y422258D02*
G03I-709J0D01*
G01X1611428Y409659D02*
G03X1610822Y408775I342J-884D01*
G01X1611053Y409659D02*
G03X1610248Y408854I0J-805D01*
G01X1611511Y409266D02*
G03X1611216Y408775I259J-490D01*
G01X1611053Y409265D02*
G03X1610641Y408854I0J-412D01*
G01X1611053Y409069D02*
G03X1610838Y408854I0J-215D01*
G01X1611642Y408872D02*
G03X1611609Y408775I128J-98D01*
G01X1615146D02*
G03X1614540Y409659I-948J0D01*
G01X1615759Y408854D02*
G03X1614954Y409659I-805J0D01*
G01X1614752Y408775D02*
G03X1614456Y409266I-554J1D01*
G01X1615366Y408854D02*
G03X1614954Y409265I-412J-1D01*
G01X1615169Y408854D02*
G03X1614954Y409069I-215J0D01*
G01X1614359Y408775D02*
G03X1614326Y408872I-161J-1D01*
G01X1618949Y422258D02*
G03I-709J0D01*
G01X1625601Y409659D02*
G03X1624995Y408775I342J-884D01*
G01X1625226Y409659D02*
G03X1624421Y408854I0J-805D01*
G01X1625685Y409266D02*
G03X1625389Y408775I258J-490D01*
G01X1625226Y409265D02*
G03X1624815Y408854I0J-411D01*
G01X1625226Y409069D02*
G03X1625011Y408854I0J-215D01*
G01X1625783Y408775D02*
Y376588D01*
G01X1628532D02*
Y408775D01*
G01D02*
X1629319D01*
G01X1628500Y408872D02*
X1625815D01*
G01X1625685Y409266D02*
X1625694Y409228D01*
X1625721Y409128D01*
X1625763Y408998D01*
X1625815Y408872D01*
G01X1628500D02*
X1628554Y409006D01*
X1628596Y409138D01*
X1628621Y409232D01*
X1628630Y409266D01*
G01X1625815Y408872D02*
G03X1625783Y408775I128J-96D01*
G01X1628532D02*
G03X1628500Y408872I-161J1D01*
G01X1569343Y431313D02*
G03I-709J0D01*
G01X1576429Y426588D02*
G03I-709J0D01*
G01Y432100D02*
G03I-709J0D01*
G01X1583516Y431313D02*
G03I-709J0D01*
G01X1590602Y426588D02*
G03I-708J0D01*
G01Y432100D02*
G03I-708J0D01*
G01X1570448Y438557D02*
X1574464D01*
G01X1577535D02*
X1581551D01*
G01X1584622D02*
X1588637D01*
G01X1591708D02*
X1595724D01*
G01X1594307Y439679D02*
X1593126D01*
G01X1587220D02*
X1586039D01*
G01X1580134D02*
X1578952D01*
G01X1573047D02*
X1571866D01*
G01X1570685Y441725D02*
X1574228D01*
G01X1577771D02*
X1581315D01*
G01X1584858D02*
X1588401D01*
G01X1591945D02*
X1595488D01*
G01X1590921Y456273D02*
X1589425D01*
G01X1583834D02*
X1582338D01*
G01X1576748D02*
X1575252D01*
G01X1569661D02*
X1568165D01*
G01X1566551Y458869D02*
X1571275D01*
G01X1573637D02*
X1578362D01*
G01X1580724D02*
X1585448D01*
G01X1587811D02*
X1592535D01*
G01X1594897D02*
X1599622D01*
G01X1591551Y461391D02*
X1588795D01*
G01X1584464D02*
X1581708D01*
G01X1577378D02*
X1574622D01*
G01X1570291D02*
X1567535D01*
G01X1571866Y439679D02*
X1570478Y442083D01*
G01X1578952Y439679D02*
X1577565Y442083D01*
G01X1569661Y456273D02*
X1570448Y454909D01*
G01X1586039Y439679D02*
X1584651Y442083D01*
G01X1576748Y456273D02*
X1577535Y454909D01*
G01X1593126Y439679D02*
X1591738Y442083D01*
G01X1583834Y456273D02*
X1584622Y454909D01*
G01X1590921Y456273D02*
X1591708Y454909D01*
G01X1566551Y460407D02*
Y438557D01*
G01X1567348Y455830D02*
Y452394D01*
G01Y450704D02*
Y445308D01*
G01Y443617D02*
Y442083D01*
G01X1567378Y438557D02*
Y443572D01*
G01Y445352D02*
Y450659D01*
G01Y452439D02*
Y454909D01*
G01X1570448D02*
Y452439D01*
G01Y450659D02*
Y445352D01*
G01Y443572D02*
Y438557D01*
G01X1570478Y442083D02*
Y443617D01*
G01Y445308D02*
Y450704D01*
G01Y452394D02*
Y455830D01*
G01X1571275Y460407D02*
Y438557D01*
G01X1573637Y460407D02*
Y438557D01*
G01X1574435Y455830D02*
Y452394D01*
G01Y450704D02*
Y445308D01*
G01Y443617D02*
Y442083D01*
G01X1574464Y438557D02*
Y443572D01*
G01Y445352D02*
Y450659D01*
G01Y452439D02*
Y454909D01*
G01X1577535D02*
Y452439D01*
G01Y450659D02*
Y445352D01*
G01Y443572D02*
Y438557D01*
G01X1577565Y442083D02*
Y443617D01*
G01Y445308D02*
Y450704D01*
G01Y452394D02*
Y455830D01*
G01X1578362Y460407D02*
Y438557D01*
G01X1580724Y460407D02*
Y438557D01*
G01X1581521Y455830D02*
Y452394D01*
G01Y450704D02*
Y445308D01*
G01Y443617D02*
Y442083D01*
G01X1581551Y438557D02*
Y443572D01*
G01Y445352D02*
Y450659D01*
G01Y452439D02*
Y454909D01*
G01X1584622D02*
Y452439D01*
G01Y450659D02*
Y445352D01*
G01Y443572D02*
Y438557D01*
G01X1584651Y442083D02*
Y443617D01*
G01Y445308D02*
Y450704D01*
G01Y452394D02*
Y455830D01*
G01X1585448Y460407D02*
Y438557D01*
G01X1587811Y460407D02*
Y438557D01*
G01X1588608Y455830D02*
Y452394D01*
G01Y450704D02*
Y445308D01*
G01Y443617D02*
Y442083D01*
G01X1588637Y438557D02*
Y443572D01*
G01Y445352D02*
Y450659D01*
G01Y452439D02*
Y454909D01*
G01X1591708D02*
Y452439D01*
G01Y450659D02*
Y445352D01*
G01Y443572D02*
Y438557D01*
G01X1591738Y442083D02*
Y443617D01*
G01Y445308D02*
Y450704D01*
G01Y452394D02*
Y455830D01*
G01X1592535Y460407D02*
Y438557D01*
G01X1594897Y460407D02*
Y438557D01*
G01X1568165Y456273D02*
X1567378Y454909D01*
G01X1575252Y456273D02*
X1574464Y454909D01*
G01X1582338Y456273D02*
X1581551Y454909D01*
G01X1574435Y442083D02*
X1573047Y439679D01*
G01X1589425Y456273D02*
X1588637Y454909D01*
G01X1581521Y442083D02*
X1580134Y439679D01*
G01X1588608Y442083D02*
X1587220Y439679D01*
G01X1595695Y442083D02*
X1594307Y439679D01*
G01X1567378Y445352D02*
G03Y443572I1299J-890D01*
G01X1570448D02*
G03Y445352I-1299J890D01*
G01X1569343Y436825D02*
G03I-709J0D01*
G01Y441155D02*
G03I-709J0D01*
G01Y445486D02*
G03I-709J0D01*
G01X1567378Y452439D02*
G03Y450659I1299J-890D01*
G01X1570448D02*
G03Y452439I-1299J890D01*
G01X1570478Y455830D02*
G03X1567348I-1565J0D01*
G01X1571275Y460407D02*
G03X1570291Y461391I-984J0D01*
G01X1567535D02*
G03X1566551Y460407I0J-984D01*
G01X1569343Y450998D02*
G03I-709J0D01*
G01Y455329D02*
G03I-709J0D01*
G01Y459659D02*
G03I-709J0D01*
G01X1570882Y463124D02*
G03I-1969J0D01*
G01X1574464Y445352D02*
G03Y443572I1299J-890D01*
G01X1577535D02*
G03Y445352I-1299J890D01*
G01X1581551D02*
G03Y443572I1299J-890D01*
G01X1576429Y436431D02*
G03I-709J0D01*
G01Y440762D02*
G03I-709J0D01*
G01Y446273D02*
G03I-709J0D01*
G01X1583516Y436825D02*
G03I-709J0D01*
G01Y441155D02*
G03I-709J0D01*
G01Y445486D02*
G03I-709J0D01*
G01X1584622Y443572D02*
G03Y445352I-1299J890D01*
G01X1588637D02*
G03Y443572I1299J-890D01*
G01X1591708D02*
G03Y445352I-1299J890D01*
G01X1590602Y436431D02*
G03I-708J0D01*
G01Y440762D02*
G03I-708J0D01*
G01Y446273D02*
G03I-708J0D01*
G01X1574464Y452439D02*
G03Y450659I1299J-890D01*
G01X1577535D02*
G03Y452439I-1299J890D01*
G01X1577565Y455830D02*
G03X1574435I-1565J0D01*
G01X1581708Y461391D02*
G03X1580724Y460407I0J-984D01*
G01X1578362D02*
G03X1577378Y461391I-984J0D01*
G01X1574622D02*
G03X1573637Y460407I-1J-984D01*
G01X1576429Y450604D02*
G03I-709J0D01*
G01Y454935D02*
G03I-709J0D01*
G01Y460447D02*
G03I-709J0D01*
G01X1577968Y463124D02*
G03I-1968J0D01*
G01X1581551Y452439D02*
G03Y450659I1299J-890D01*
G01X1584622D02*
G03Y452439I-1299J890D01*
G01X1583516Y450998D02*
G03I-709J0D01*
G01Y455329D02*
G03I-709J0D01*
G01X1584651Y455830D02*
G03X1581521I-1565J0D01*
G01X1585448Y460407D02*
G03X1584464Y461391I-984J0D01*
G01X1583516Y459659D02*
G03I-709J0D01*
G01X1588637Y452439D02*
G03Y450659I1299J-890D01*
G01X1591708D02*
G03Y452439I-1299J890D01*
G01X1590602Y450604D02*
G03I-708J0D01*
G01Y454935D02*
G03I-708J0D01*
G01X1591738Y455830D02*
G03X1588608I-1565J0D01*
G01X1588795Y461391D02*
G03X1587811Y460407I0J-984D01*
G01X1590602Y460447D02*
G03I-708J0D01*
G01X1585055Y463124D02*
G03I-1969J0D01*
G01X1592141D02*
G03I-1968J0D01*
G01X1595724Y445352D02*
G03Y443572I1299J-890D01*
G01Y452439D02*
G03Y450659I1299J-890D01*
G01X1595882Y461391D02*
G03X1594897Y460407I-1J-984D01*
G01X1592535D02*
G03X1591551Y461391I-984J0D01*
G01X1599228Y463124D02*
G03I-1969J0D01*
G01X1570448Y469009D02*
X1574464D01*
G01X1577535D02*
X1581551D01*
G01X1584622D02*
X1588637D01*
G01X1591708D02*
X1595724D01*
G01X1596065Y469403D02*
X1591367D01*
G01X1588979D02*
X1584280D01*
G01X1581892D02*
X1577194D01*
G01X1574806D02*
X1570107D01*
G01X1591708Y476883D02*
X1588637D01*
G01X1584622D02*
X1581551D01*
G01X1577535D02*
X1574464D01*
G01X1570448D02*
X1567378D01*
G01X1590527Y478065D02*
X1589819D01*
G01X1583441D02*
X1582732D01*
G01X1576354D02*
X1575645D01*
G01X1569267D02*
X1568559D01*
G01X1569267D02*
X1570448Y476883D01*
G01X1576354Y478065D02*
X1577535Y476883D01*
G01X1583441Y478065D02*
X1584622Y476883D01*
G01X1590527Y478065D02*
X1591708Y476883D01*
G01X1567719Y469403D02*
X1567503Y469683D01*
X1567378Y470000D01*
G01X1574806Y469403D02*
X1574589Y469683D01*
X1574464Y470000D01*
G01X1581892Y469403D02*
X1581676Y469683D01*
X1581551Y470000D01*
G01X1588979Y469403D02*
X1588763Y469683D01*
X1588637Y470000D01*
G01X1567348Y470661D02*
X1567394Y470202D01*
X1567521Y469777D01*
X1567719Y469403D01*
G01X1574435Y470661D02*
X1574480Y470202D01*
X1574607Y469777D01*
X1574806Y469403D01*
G01X1581521Y470661D02*
X1581567Y470202D01*
X1581694Y469777D01*
X1581892Y469403D01*
G01X1567348Y470242D02*
X1567356Y470118D01*
X1567378Y469995D01*
G01X1574435Y470242D02*
X1574442Y470118D01*
X1574464Y469995D01*
G01X1588608Y470661D02*
X1588654Y470202D01*
X1588780Y469777D01*
X1588979Y469403D01*
G01X1581521Y470242D02*
X1581529Y470118D01*
X1581551Y469995D01*
G01X1588608Y470242D02*
X1588615Y470118D01*
X1588637Y469995D01*
G01X1567348Y476490D02*
Y470242D01*
G01X1567378Y469009D02*
Y476883D01*
G01X1570448D02*
Y469009D01*
G01X1570478Y476490D02*
Y470242D01*
G01X1574435Y476490D02*
Y470242D01*
G01X1574464Y469009D02*
Y476883D01*
G01X1577535D02*
Y469009D01*
G01X1577565Y476490D02*
Y470242D01*
G01X1581521Y476490D02*
Y470242D01*
G01X1581551Y469009D02*
Y476883D01*
G01X1584622D02*
Y469009D01*
G01X1584651Y476490D02*
Y470242D01*
G01X1588608Y476490D02*
Y470242D01*
G01X1588637Y469009D02*
Y476883D01*
G01X1591708D02*
Y469009D01*
G01X1591738Y476490D02*
Y470242D01*
G01X1570478D02*
X1570471Y470119D01*
X1570448Y469995D01*
G01X1577565Y470242D02*
X1577557Y470119D01*
X1577535Y469995D01*
G01X1584651Y470242D02*
X1584644Y470119D01*
X1584622Y469995D01*
G01X1591738Y470242D02*
X1591730Y470119D01*
X1591708Y469995D01*
G01X1570448Y470000D02*
X1570321Y469680D01*
X1570107Y469403D01*
G01X1577535Y470000D02*
X1577408Y469680D01*
X1577194Y469403D01*
G01X1584622Y470000D02*
X1584495Y469680D01*
X1584280Y469403D01*
G01X1591708Y470000D02*
X1591581Y469680D01*
X1591367Y469403D01*
G01X1570107D02*
X1570306Y469778D01*
X1570432Y470202D01*
X1570478Y470661D01*
G01X1577194Y469403D02*
X1577392Y469778D01*
X1577519Y470202D01*
X1577565Y470661D01*
G01X1584280Y469403D02*
X1584479Y469778D01*
X1584606Y470202D01*
X1584651Y470661D01*
G01X1591367Y469403D02*
X1591565Y469778D01*
X1591692Y470202D01*
X1591738Y470661D01*
G01X1568559Y478065D02*
X1567378Y476883D01*
G01X1575645Y478065D02*
X1574464Y476883D01*
G01X1582732Y478065D02*
X1581551Y476883D01*
G01X1589819Y478065D02*
X1588637Y476883D01*
G01X1567719Y469403D02*
G03X1570107I1194J1012D01*
G01X1569343Y465171D02*
G03I-709J0D01*
G01Y469502D02*
G03I-709J0D01*
G01X1574806Y469403D02*
G03X1577194I1194J1012D01*
G01X1576429Y464777D02*
G03I-709J0D01*
G01X1581892Y469403D02*
G03X1584280I1194J1012D01*
G01X1588979D02*
G03X1591367I1194J1012D01*
G01X1583516Y465171D02*
G03I-709J0D01*
G01X1590602Y464777D02*
G03I-708J0D01*
G01X1583516Y469502D02*
G03I-709J0D01*
G01X1597689Y431313D02*
G03I-709J0D01*
G01X1604776Y426588D02*
G03I-709J0D01*
G01Y432100D02*
G03I-709J0D01*
G01X1611862Y431313D02*
G03I-708J0D01*
G01X1618949Y426588D02*
G03I-709J0D01*
G01Y432100D02*
G03I-709J0D01*
G01X1626035Y431313D02*
G03I-708J0D01*
G01X1602811Y438557D02*
X1598795D01*
G01X1605882D02*
X1607902D01*
G01X1608458D02*
X1609897D01*
G01X1612968D02*
X1616984D01*
G01X1620055D02*
X1624071D01*
G01X1622653Y439679D02*
X1621472D01*
G01X1615567D02*
X1614385D01*
G01X1608480D02*
X1607299D01*
G01X1601393D02*
X1600212D01*
G01X1599031Y441725D02*
X1602574D01*
G01X1606118D02*
X1609661D01*
G01X1613204D02*
X1616748D01*
G01X1620291D02*
X1623834D01*
G01X1626354Y456273D02*
X1624858D01*
G01X1605094D02*
X1603598D01*
G01X1598008D02*
X1596511D01*
G01X1610685D02*
X1612181D01*
G01X1617771D02*
X1619267D01*
G01X1620882Y458869D02*
X1616157D01*
G01X1613795D02*
X1609071D01*
G01X1606708D02*
X1601984D01*
G01X1623244D02*
X1627968D01*
G01X1626984Y461391D02*
X1624228D01*
G01X1619897D02*
X1617141D01*
G01X1612811D02*
X1610055D01*
G01X1605724D02*
X1602968D01*
G01X1598637D02*
X1595882D01*
G01X1600212Y439679D02*
X1598824Y442083D01*
G01X1607299Y439679D02*
X1605911Y442083D01*
G01X1598008Y456273D02*
X1598795Y454909D01*
G01X1614385Y439679D02*
X1612998Y442083D01*
G01X1605094Y456273D02*
X1605882Y454909D01*
G01X1621472Y439679D02*
X1620084Y442083D01*
G01X1612181Y456273D02*
X1612968Y454909D01*
G01X1619267Y456273D02*
X1620055Y454909D01*
G01X1595695Y455830D02*
Y452394D01*
G01Y450704D02*
Y445308D01*
G01Y443617D02*
Y442083D01*
G01X1595724Y438557D02*
Y443572D01*
G01Y445352D02*
Y450659D01*
G01Y452439D02*
Y454909D01*
G01X1598795D02*
Y452439D01*
G01Y450659D02*
Y445352D01*
G01Y443572D02*
Y438557D01*
G01X1598824Y442083D02*
Y443617D01*
G01Y445308D02*
Y450704D01*
G01Y452394D02*
Y455830D01*
G01X1599622Y460407D02*
Y438557D01*
G01X1601984Y460407D02*
Y438557D01*
G01X1602781Y455830D02*
Y452394D01*
G01Y450704D02*
Y445308D01*
G01Y443617D02*
Y442083D01*
G01X1602811Y454909D02*
Y452439D01*
G01Y450659D02*
Y445352D01*
G01Y443572D02*
Y438557D01*
G01X1605882Y454909D02*
Y452439D01*
G01Y450659D02*
Y445352D01*
G01Y443572D02*
Y438557D01*
G01X1605911Y442083D02*
Y443617D01*
G01Y445308D02*
Y450704D01*
G01Y452394D02*
Y455830D01*
G01X1606708Y438557D02*
Y460407D01*
G01X1609071D02*
Y438557D01*
G01X1609868Y455830D02*
Y452394D01*
G01Y450704D02*
Y445308D01*
G01Y443617D02*
Y442083D01*
G01X1609897Y438557D02*
Y443572D01*
G01Y445352D02*
Y450659D01*
G01Y452439D02*
Y454909D01*
G01X1612968D02*
Y452439D01*
G01Y450659D02*
Y445352D01*
G01Y443572D02*
Y438557D01*
G01X1612998Y442083D02*
Y443617D01*
G01Y445308D02*
Y450704D01*
G01Y452394D02*
Y455830D01*
G01X1613795Y438557D02*
Y460407D01*
G01X1616157D02*
Y438557D01*
G01X1616954Y455830D02*
Y452394D01*
G01Y450704D02*
Y445308D01*
G01Y443617D02*
Y442083D01*
G01X1616984Y438557D02*
Y443572D01*
G01Y445352D02*
Y450659D01*
G01Y452439D02*
Y454909D01*
G01X1620055D02*
Y452439D01*
G01Y450659D02*
Y445352D01*
G01Y443572D02*
Y438557D01*
G01X1620084Y442083D02*
Y443617D01*
G01Y445308D02*
Y450704D01*
G01Y452394D02*
Y455830D01*
G01X1620882Y438557D02*
Y460407D01*
G01X1623244D02*
Y438557D01*
G01X1624041Y455830D02*
Y452394D01*
G01Y450704D02*
Y445308D01*
G01Y443617D02*
Y442083D01*
G01X1624071Y438557D02*
Y443572D01*
G01Y445352D02*
Y450659D01*
G01Y452439D02*
Y454909D01*
G01X1596511Y456273D02*
X1595724Y454909D01*
G01X1603598Y456273D02*
X1602811Y454909D01*
G01X1610685Y456273D02*
X1609897Y454909D01*
G01X1602781Y442083D02*
X1601393Y439679D01*
G01X1617771Y456273D02*
X1616984Y454909D01*
G01X1609868Y442083D02*
X1608480Y439679D01*
G01X1624858Y456273D02*
X1624071Y454909D01*
G01X1616954Y442083D02*
X1615567Y439679D01*
G01X1624041Y442083D02*
X1622653Y439679D01*
G01X1598795Y443572D02*
G03Y445352I-1299J890D01*
G01X1597689Y436825D02*
G03I-709J0D01*
G01Y441155D02*
G03I-709J0D01*
G01Y445486D02*
G03I-709J0D01*
G01X1602811Y445352D02*
G03Y443572I1299J-890D01*
G01X1605882D02*
G03Y445352I-1300J890D01*
G01X1604776Y436431D02*
G03I-709J0D01*
G01Y440762D02*
G03I-709J0D01*
G01Y446273D02*
G03I-709J0D01*
G01X1598795Y450659D02*
G03Y452439I-1299J890D01*
G01X1598824Y455830D02*
G03X1595695I-1564J0D01*
G01X1597689Y450998D02*
G03I-709J0D01*
G01Y455329D02*
G03I-709J0D01*
G01Y459659D02*
G03I-709J0D01*
G01X1605882Y450659D02*
G03Y452439I-1300J890D01*
G01X1602811D02*
G03Y450659I1299J-890D01*
G01X1605911Y455830D02*
G03X1602781I-1565J0D01*
G01X1606708Y460407D02*
G03X1605724Y461391I-984J0D01*
G01X1602968D02*
G03X1601984Y460407I0J-984D01*
G01X1599622D02*
G03X1598637Y461391I-984J0D01*
G01X1604776Y450604D02*
G03I-709J0D01*
G01Y454935D02*
G03I-709J0D01*
G01Y460447D02*
G03I-709J0D01*
G01X1606315Y463124D02*
G03I-1969J0D01*
G01X1616984Y445352D02*
G03Y443572I1299J-890D01*
G01X1612968D02*
G03Y445352I-1299J890D01*
G01X1609897D02*
G03Y443572I1299J-890D01*
G01X1618949Y436431D02*
G03I-709J0D01*
G01X1611862Y436825D02*
G03I-708J0D01*
G01X1618949Y440762D02*
G03I-709J0D01*
G01X1611862Y441155D02*
G03I-708J0D01*
G01Y445486D02*
G03I-708J0D01*
G01X1618949Y446273D02*
G03I-709J0D01*
G01X1624071Y445352D02*
G03Y443572I1299J-890D01*
G01X1620055D02*
G03Y445352I-1299J890D01*
G01X1626035Y436825D02*
G03I-708J0D01*
G01Y441155D02*
G03I-708J0D01*
G01Y445486D02*
G03I-708J0D01*
G01X1612968Y450659D02*
G03Y452439I-1299J890D01*
G01X1609897D02*
G03Y450659I1299J-890D01*
G01X1611862Y450998D02*
G03I-708J0D01*
G01Y455329D02*
G03I-708J0D01*
G01X1612998Y455830D02*
G03X1609868I-1565J0D01*
G01X1613795Y460407D02*
G03X1612811Y461391I-984J0D01*
G01X1610055D02*
G03X1609071Y460407I0J-984D01*
G01X1611862Y459659D02*
G03I-708J0D01*
G01X1616984Y452439D02*
G03Y450659I1299J-890D01*
G01X1618949Y450604D02*
G03I-709J0D01*
G01Y454935D02*
G03I-709J0D01*
G01X1617141Y461391D02*
G03X1616157Y460407I0J-984D01*
G01X1618949Y460447D02*
G03I-709J0D01*
G01X1613401Y463124D02*
G03I-1968J0D01*
G01X1624071Y452439D02*
G03Y450659I1299J-890D01*
G01X1620055D02*
G03Y452439I-1299J890D01*
G01X1627171Y455830D02*
G03X1624041I-1565J0D01*
G01X1620084D02*
G03X1616954I-1565J0D01*
G01X1624228Y461391D02*
G03X1623244Y460407I0J-984D01*
G01X1620882D02*
G03X1619897Y461391I-984J0D01*
G01X1626035Y450998D02*
G03I-708J0D01*
G01Y455329D02*
G03I-708J0D01*
G01Y459659D02*
G03I-708J0D01*
G01X1620488Y463124D02*
G03I-1969J0D01*
G01X1627574D02*
G03I-1968J0D01*
G01X1598795Y469009D02*
X1602811D01*
G01X1605882D02*
X1607902D01*
G01X1608458D02*
X1609897D01*
G01X1612968D02*
X1616984D01*
G01X1620055D02*
X1624071D01*
G01X1624412Y469403D02*
X1619713D01*
G01X1617325D02*
X1612627D01*
G01X1610239D02*
X1605540D01*
G01X1603152D02*
X1598454D01*
G01X1608458Y475309D02*
X1664595D01*
G01X1627141Y476883D02*
X1624071D01*
G01X1620055D02*
X1616984D01*
G01X1612968D02*
X1609897D01*
G01X1605882D02*
X1602811D01*
G01X1598795D02*
X1595724D01*
G01X1625960Y478065D02*
X1625252D01*
G01X1618874D02*
X1618165D01*
G01X1611787D02*
X1611078D01*
G01X1604700D02*
X1603992D01*
G01X1597614D02*
X1596905D01*
G01X1608458Y479049D02*
X1664595D01*
G01X1597614Y478065D02*
X1598795Y476883D01*
G01X1604700Y478065D02*
X1605882Y476883D01*
G01X1611787Y478065D02*
X1612968Y476883D01*
G01X1618874Y478065D02*
X1620055Y476883D01*
G01X1596065Y469403D02*
X1595849Y469683D01*
X1595724Y470000D01*
G01X1603152Y469403D02*
X1602936Y469683D01*
X1602811Y470000D01*
G01X1610239Y469403D02*
X1610022Y469683D01*
X1609897Y470000D01*
G01X1617325Y469403D02*
X1617109Y469683D01*
X1616984Y470000D01*
G01X1624412Y469403D02*
X1624196Y469683D01*
X1624071Y470000D01*
G01X1595695Y470661D02*
X1595740Y470202D01*
X1595867Y469777D01*
X1596065Y469403D01*
G01X1602781Y470661D02*
X1602827Y470202D01*
X1602954Y469777D01*
X1603152Y469403D01*
G01X1609868Y470661D02*
X1609913Y470202D01*
X1610040Y469777D01*
X1610239Y469403D01*
G01X1616954Y470661D02*
X1617000Y470202D01*
X1617127Y469777D01*
X1617325Y469403D01*
G01X1595695Y470242D02*
X1595702Y470118D01*
X1595724Y469995D01*
G01X1602781Y470242D02*
X1602789Y470118D01*
X1602811Y469995D01*
G01X1609868Y470242D02*
X1609875Y470118D01*
X1609897Y469995D01*
G01X1595695Y476490D02*
Y470242D01*
G01X1595724Y469009D02*
Y476883D01*
G01X1598795D02*
Y469009D01*
G01X1598824Y476490D02*
Y470242D01*
G01X1624041Y470661D02*
X1624087Y470202D01*
X1624213Y469777D01*
X1624412Y469403D01*
G01X1616954Y470242D02*
X1616962Y470118D01*
X1616984Y469995D01*
G01X1624041Y470242D02*
X1624048Y470118D01*
X1624071Y469995D01*
G01X1602781Y476490D02*
Y470242D01*
G01X1602811Y469009D02*
Y476883D01*
G01X1605882D02*
Y469009D01*
G01X1605911Y476490D02*
Y470242D01*
G01X1609868Y476490D02*
Y470242D01*
G01X1609897Y469009D02*
Y476883D01*
G01X1612968D02*
Y469009D01*
G01X1612998Y476490D02*
Y470242D01*
G01X1616954Y476490D02*
Y470242D01*
G01X1616984Y469009D02*
Y476883D01*
G01X1620055D02*
Y469009D01*
G01X1620084Y476490D02*
Y470242D01*
G01X1624041Y476490D02*
Y470242D01*
G01X1624071Y469009D02*
Y476883D01*
G01X1598824Y470242D02*
X1598817Y470119D01*
X1598795Y469995D01*
G01X1605911Y470242D02*
X1605904Y470119D01*
X1605882Y469995D01*
G01X1612998Y470242D02*
X1612990Y470119D01*
X1612968Y469995D01*
G01X1620084Y470242D02*
X1620077Y470119D01*
X1620055Y469995D01*
G01X1598795Y470000D02*
X1598668Y469680D01*
X1598454Y469403D01*
G01X1605882Y470000D02*
X1605754Y469680D01*
X1605540Y469403D01*
G01X1612968Y470000D02*
X1612841Y469680D01*
X1612627Y469403D01*
G01X1620055Y470000D02*
X1619928Y469680D01*
X1619713Y469403D01*
G01X1598454D02*
X1598652Y469778D01*
X1598779Y470202D01*
X1598824Y470661D01*
G01X1605540Y469403D02*
X1605739Y469778D01*
X1605865Y470202D01*
X1605911Y470661D01*
G01X1612627Y469403D02*
X1612825Y469778D01*
X1612952Y470202D01*
X1612998Y470661D01*
G01X1619713Y469403D02*
X1619912Y469778D01*
X1620039Y470202D01*
X1620084Y470661D01*
G01X1596905Y478065D02*
X1595724Y476883D01*
G01X1603992Y478065D02*
X1602811Y476883D01*
G01X1611078Y478065D02*
X1609897Y476883D01*
G01X1618165Y478065D02*
X1616984Y476883D01*
G01X1625252Y478065D02*
X1624071Y476883D01*
G01X1596065Y469403D02*
G03X1598454I1195J1012D01*
G01X1597689Y465171D02*
G03I-709J0D01*
G01Y469502D02*
G03I-709J0D01*
G01X1603152Y469403D02*
G03X1605540I1194J1012D01*
G01X1604776Y464777D02*
G03I-709J0D01*
G01X1610239Y469403D02*
G03X1612627I1194J1012D01*
G01X1611862Y469502D02*
G03I-708J0D01*
G01Y465171D02*
G03I-708J0D01*
G01X1618949Y464777D02*
G03I-709J0D01*
G01X1617325Y469403D02*
G03X1619713I1194J1012D01*
G01X1624412D02*
G03X1626800I1194J1012D01*
G01X1626035Y465171D02*
G03I-708J0D01*
G01Y469502D02*
G03I-708J0D01*
G01X1627141Y438557D02*
X1631157D01*
G01X1629740Y439679D02*
X1628559D01*
G01X1627378Y441725D02*
X1630921D01*
G01X1628559Y439679D02*
X1627171Y442083D01*
G01X1626354Y456273D02*
X1627141Y454909D01*
G01D02*
Y452439D01*
G01Y450659D02*
Y445352D01*
G01Y443572D02*
Y438557D01*
G01X1627171Y442083D02*
Y443617D01*
G01Y445308D02*
Y450704D01*
G01Y452394D02*
Y455830D01*
G01X1627968Y460407D02*
Y438557D01*
G01X1627141Y443572D02*
G03Y445352I-1299J890D01*
G01Y450659D02*
G03Y452439I-1299J890D01*
G01X1627968Y460407D02*
G03X1626984Y461391I-984J0D01*
G01X1627141Y469009D02*
X1631157D01*
G01X1631498Y469403D02*
X1626800D01*
G01X1625960Y478065D02*
X1627141Y476883D01*
G01D02*
Y469009D01*
G01X1627171Y476490D02*
Y470242D01*
G01D02*
X1627163Y470119D01*
X1627141Y469995D01*
G01Y470000D02*
X1627014Y469680D01*
X1626800Y469403D01*
G01D02*
X1626998Y469778D01*
X1627125Y470202D01*
X1627171Y470661D01*
G01X1589894Y568635D02*
Y528455D01*
G01X1593831Y572572D02*
X1633161D01*
G01X1601705Y572573D02*
G03I-11811J0D01*
G01X1595799D02*
G03I-5905J0D01*
G01X1603673Y615171D02*
X1733595D01*
G01X1603673Y745092D02*
Y615171D01*
G01X1605642Y739187D02*
X1609579Y743124D01*
G01X1605642D02*
Y739187D01*
G01X1609579Y743124D02*
X1605642D01*
G01X1733595Y745092D02*
X1603673D01*
G01X1617925Y780518D02*
X1625717Y784707D01*
G01X1626537Y783450D02*
X1620796Y780518D01*
G01X1598240Y770466D02*
Y790151D01*
G01X1600701D02*
Y782194D01*
G01Y779681D02*
Y770466D01*
G01X1612184D02*
Y779681D01*
G01Y782194D02*
Y790151D01*
G01X1614644D02*
Y770466D01*
G01D02*
X1612184D01*
G01X1600701D02*
X1598240D01*
G01X1612184Y779681D02*
X1600701D01*
G01Y782194D02*
X1612184D01*
G01X1620796Y780518D02*
X1626537Y777587D01*
G01X1625717Y776330D02*
X1617925Y780518D01*
G01X1598240Y790151D02*
X1600701D01*
G01X1612184D02*
X1614644D01*
G01X1626537Y777587D02*
X1625717Y776330D01*
G01Y784707D02*
X1626537Y783450D01*
G01X1617463Y830343D02*
X1614203Y818178D01*
G01X1608514Y846131D02*
Y818178D01*
G01X1610089Y867491D02*
Y818178D01*
G01X1611089Y867491D02*
Y818178D01*
G01X1611589Y867491D02*
Y818178D01*
G01X1613130Y867491D02*
Y818178D01*
G01X1615896Y821013D02*
Y818178D01*
G01X1620424Y821013D02*
Y818178D01*
G01X1621802D02*
Y821013D01*
G01X1608514Y818178D02*
X1650050D01*
G01X1642668Y821013D02*
X1615896D01*
G01X1610089Y847706D02*
X1608514Y846131D01*
G01X1617121Y825428D02*
Y827354D01*
G01Y840389D02*
Y842315D01*
G01X1617463Y830343D02*
Y840343D01*
G01X1617821Y825429D02*
Y827355D01*
G01Y840389D02*
Y842315D01*
G01X1620074Y828184D02*
Y830110D01*
G01Y843145D02*
Y845071D01*
G01X1620774Y828185D02*
Y830111D01*
G01Y843145D02*
Y845071D01*
G01X1623026Y822672D02*
Y824598D01*
G01Y837633D02*
Y839559D01*
G01Y852594D02*
Y854520D01*
G01X1623726Y822673D02*
Y824599D01*
G01Y837633D02*
Y839559D01*
G01Y852594D02*
Y854520D01*
G01X1623026Y822671D02*
X1623726D01*
G01Y822887D02*
X1623026D01*
G01X1623726Y822983D02*
X1623026D01*
G01X1623726Y823045D02*
X1623026D01*
G01X1623726Y823143D02*
X1623026D01*
G01X1623726Y823458D02*
X1623026D01*
G01Y823813D02*
X1623726D01*
G01Y824128D02*
X1623026D01*
G01X1623726Y824226D02*
X1623026D01*
G01X1623726Y824289D02*
X1623026D01*
G01X1623726Y824383D02*
X1623026D01*
G01Y824600D02*
X1623726D01*
G01X1617821Y825427D02*
X1617121D01*
G01X1617821Y825643D02*
X1617121D01*
G01X1617821Y825739D02*
X1617121D01*
G01X1617821Y825801D02*
X1617121D01*
G01X1617821Y825899D02*
X1617121D01*
G01X1617821Y826214D02*
X1617121D01*
G01Y826569D02*
X1617821D01*
G01Y826883D02*
X1617121D01*
G01X1617821Y826982D02*
X1617121D01*
G01X1617821Y827045D02*
X1617121D01*
G01X1617821Y827139D02*
X1617121D01*
G01X1617821Y827356D02*
X1617121D01*
G01X1620774Y828183D02*
X1620074D01*
G01Y828399D02*
X1620774D01*
G01X1620074Y828495D02*
X1620774D01*
G01X1620074Y828557D02*
X1620774D01*
G01Y828655D02*
X1620074D01*
G01Y828970D02*
X1620774D01*
G01X1620074Y829324D02*
X1620774D01*
G01X1620074Y829639D02*
X1620774D01*
G01X1620074Y829738D02*
X1620774D01*
G01X1620074Y829800D02*
X1620774D01*
G01Y829895D02*
X1620074D01*
G01X1620774Y830112D02*
X1620074D01*
G01X1641085Y830343D02*
X1617463D01*
G01X1623026Y837632D02*
X1623726D01*
G01Y837848D02*
X1623026D01*
G01X1623726Y837943D02*
X1623026D01*
G01X1623726Y838006D02*
X1623026D01*
G01X1623726Y838104D02*
X1623026D01*
G01X1623726Y838419D02*
X1623026D01*
G01Y838773D02*
X1623726D01*
G01Y839088D02*
X1623026D01*
G01X1623726Y839187D02*
X1623026D01*
G01X1623726Y839249D02*
X1623026D01*
G01X1623726Y839344D02*
X1623026D01*
G01Y839561D02*
X1623726D01*
G01X1617463Y840343D02*
X1641085D01*
G01X1617821Y840387D02*
X1617121D01*
G01X1617821Y840604D02*
X1617121D01*
G01X1617821Y840699D02*
X1617121D01*
G01X1617821Y840761D02*
X1617121D01*
G01X1617821Y840860D02*
X1617121D01*
G01X1617821Y841175D02*
X1617121D01*
G01Y841529D02*
X1617821D01*
G01Y841844D02*
X1617121D01*
G01X1617821Y841943D02*
X1617121D01*
G01X1617821Y842005D02*
X1617121D01*
G01X1617821Y842100D02*
X1617121D01*
G01X1617821Y842317D02*
X1617121D01*
G01X1620774Y843143D02*
X1620074D01*
G01X1620774Y843360D02*
X1620074D01*
G01X1620774Y843455D02*
X1620074D01*
G01X1620774Y843517D02*
X1620074D01*
G01X1620774Y843616D02*
X1620074D01*
G01X1620774Y843931D02*
X1620074D01*
G01Y844285D02*
X1620774D01*
G01Y844600D02*
X1620074D01*
G01X1620774Y844698D02*
X1620074D01*
G01X1620774Y844761D02*
X1620074D01*
G01X1620774Y844856D02*
X1620074D01*
G01X1620774Y845072D02*
X1620074D01*
G01X1623026Y852592D02*
X1623726D01*
G01X1621213Y844108D02*
G03I-729J0D01*
G01X1618181Y841352D02*
G03I-728J0D01*
G01X1627039D02*
G03I-728J0D01*
G01X1624087Y838596D02*
G03I-729J0D01*
G01X1621213Y829147D02*
G03I-729J0D01*
G01X1618181Y826392D02*
G03I-728J0D01*
G01X1627039D02*
G03I-728J0D01*
G01X1624087Y823636D02*
G03I-729J0D01*
G01X1617121Y855350D02*
Y857276D01*
G01X1617821Y855350D02*
Y857276D01*
G01X1620074Y858106D02*
Y860032D01*
G01X1620774Y858106D02*
Y860032D01*
G01X1623726Y852809D02*
X1623026D01*
G01Y852904D02*
X1623726D01*
G01Y852966D02*
X1623026D01*
G01X1623726Y853065D02*
X1623026D01*
G01Y853380D02*
X1623726D01*
G01X1623026Y853734D02*
X1623726D01*
G01X1623026Y854049D02*
X1623726D01*
G01Y854147D02*
X1623026D01*
G01Y854210D02*
X1623726D01*
G01Y854305D02*
X1623026D01*
G01Y854521D02*
X1623726D01*
G01X1617821Y855348D02*
X1617121D01*
G01X1617821Y855565D02*
X1617121D01*
G01X1617821Y855660D02*
X1617121D01*
G01X1617821Y855722D02*
X1617121D01*
G01X1617821Y855821D02*
X1617121D01*
G01X1617821Y856135D02*
X1617121D01*
G01Y856490D02*
X1617821D01*
G01Y856805D02*
X1617121D01*
G01X1617821Y856903D02*
X1617121D01*
G01X1617821Y856966D02*
X1617121D01*
G01X1617821Y857061D02*
X1617121D01*
G01X1617821Y857277D02*
X1617121D01*
G01X1620774Y858104D02*
X1620074D01*
G01X1620774Y858321D02*
X1620074D01*
G01X1621213Y859069D02*
G03I-729J0D01*
G01X1618181Y856313D02*
G03I-728J0D01*
G01X1627039D02*
G03I-728J0D01*
G01X1624087Y853557D02*
G03I-729J0D01*
G01X1625979Y825428D02*
Y827354D01*
G01Y840389D02*
Y842315D01*
G01X1626679Y825429D02*
Y827355D01*
G01Y840389D02*
Y842315D01*
G01Y825427D02*
X1625979D01*
G01X1626679Y825643D02*
X1625979D01*
G01X1626679Y825739D02*
X1625979D01*
G01X1626679Y825801D02*
X1625979D01*
G01X1626679Y825899D02*
X1625979D01*
G01X1626679Y826214D02*
X1625979D01*
G01Y826569D02*
X1626679D01*
G01Y826883D02*
X1625979D01*
G01X1626679Y826982D02*
X1625979D01*
G01X1626679Y827045D02*
X1625979D01*
G01X1626679Y827139D02*
X1625979D01*
G01X1626679Y827356D02*
X1625979D01*
G01X1626679Y840387D02*
X1625979D01*
G01Y840604D02*
X1626679D01*
G01X1625979Y840699D02*
X1626679D01*
G01X1625979Y840761D02*
X1626679D01*
G01Y840860D02*
X1625979D01*
G01Y841175D02*
X1626679D01*
G01X1625979Y841529D02*
X1626679D01*
G01X1625979Y841844D02*
X1626679D01*
G01X1625979Y841943D02*
X1626679D01*
G01X1625979Y842005D02*
X1626679D01*
G01Y842100D02*
X1625979D01*
G01X1626679Y842317D02*
X1625979D01*
G01X1629992Y829147D02*
G03I-728J0D01*
G01Y844108D02*
G03I-728J0D01*
G01X1625979Y855350D02*
Y857276D01*
G01X1626679Y855350D02*
Y857276D01*
G01Y855348D02*
X1625979D01*
G01X1626679Y855565D02*
X1625979D01*
G01X1626679Y855660D02*
X1625979D01*
G01X1626679Y855722D02*
X1625979D01*
G01X1626679Y855821D02*
X1625979D01*
G01X1626679Y856135D02*
X1625979D01*
G01Y856490D02*
X1626679D01*
G01Y856805D02*
X1625979D01*
G01X1626679Y856903D02*
X1625979D01*
G01X1626679Y856966D02*
X1625979D01*
G01X1626679Y857061D02*
X1625979D01*
G01X1626679Y857277D02*
X1625979D01*
G01X1599736Y912415D02*
X1567109Y917634D01*
G01X1599736Y912415D02*
X1567109Y917634D01*
G01X1599421Y869451D02*
Y884481D01*
G01X1602759Y867491D02*
Y912330D01*
G01X1604334D02*
Y867491D01*
G01X1617121Y870310D02*
Y872236D01*
G01X1617821Y870311D02*
Y872237D01*
G01X1620074Y873066D02*
Y874992D01*
G01X1620774Y873067D02*
Y874993D01*
G01X1623026Y867554D02*
Y869480D01*
G01X1623726Y867555D02*
Y869481D01*
G01X1599421Y869451D02*
X1601381Y867491D01*
G01X1620774Y858416D02*
X1620074D01*
G01X1620774Y858478D02*
X1620074D01*
G01X1620774Y858576D02*
X1620074D01*
G01X1620774Y858891D02*
X1620074D01*
G01Y859246D02*
X1620774D01*
G01Y859561D02*
X1620074D01*
G01X1620774Y859659D02*
X1620074D01*
G01X1620774Y859722D02*
X1620074D01*
G01X1620774Y859817D02*
X1620074D01*
G01X1620774Y860033D02*
X1620074D01*
G01X1601381Y867491D02*
X1657183D01*
G01X1623026Y867553D02*
X1623726D01*
G01Y867769D02*
X1623026D01*
G01Y867865D02*
X1623726D01*
G01Y867927D02*
X1623026D01*
G01X1623726Y868025D02*
X1623026D01*
G01Y868340D02*
X1623726D01*
G01X1623026Y868695D02*
X1623726D01*
G01X1623026Y869009D02*
X1623726D01*
G01Y869108D02*
X1623026D01*
G01Y869171D02*
X1623726D01*
G01Y869265D02*
X1623026D01*
G01Y869482D02*
X1623726D01*
G01X1617821Y870309D02*
X1617121D01*
G01X1617821Y870525D02*
X1617121D01*
G01X1617821Y870621D02*
X1617121D01*
G01X1617821Y870683D02*
X1617121D01*
G01X1617821Y870781D02*
X1617121D01*
G01X1617821Y871096D02*
X1617121D01*
G01Y871450D02*
X1617821D01*
G01Y871765D02*
X1617121D01*
G01X1617821Y871864D02*
X1617121D01*
G01X1617821Y871926D02*
X1617121D01*
G01X1617821Y872021D02*
X1617121D01*
G01X1617821Y872238D02*
X1617121D01*
G01X1620774Y873065D02*
X1620074D01*
G01X1620774Y873281D02*
X1620074D01*
G01X1620774Y873376D02*
X1620074D01*
G01X1620774Y873439D02*
X1620074D01*
G01X1620774Y873537D02*
X1620074D01*
G01X1620774Y873852D02*
X1620074D01*
G01Y874206D02*
X1620774D01*
G01Y874521D02*
X1620074D01*
G01X1620774Y874620D02*
X1620074D01*
G01X1620774Y874682D02*
X1620074D01*
G01X1620774Y874777D02*
X1620074D01*
G01X1620774Y874994D02*
X1620074D01*
G01X1609991Y876982D02*
G03I-4331J0D01*
G01X1609203D02*
G03I-3543J0D01*
G01X1621213Y874029D02*
G03I-729J0D01*
G01X1618181Y871273D02*
G03I-728J0D01*
G01X1627039D02*
G03I-728J0D01*
G01X1624087Y868518D02*
G03I-729J0D01*
G01X1609894Y909378D02*
X1610878Y910362D01*
G01X1601381Y886441D02*
X1599421Y884481D01*
G01X1603988Y886441D02*
X1606941Y889393D01*
G01X1609894Y887425D02*
X1610878Y888409D01*
G01X1601381Y911346D02*
Y886441D01*
G01X1606941Y889393D02*
Y912330D01*
G01X1608909Y910362D02*
Y888409D01*
G01X1610878D02*
Y910362D01*
G01X1611664Y912330D02*
Y886441D01*
G01X1613829Y908393D02*
Y888208D01*
G01X1617121Y904956D02*
Y898788D01*
G01X1617821Y904956D02*
Y898788D01*
G01X1620074Y904956D02*
Y898788D01*
G01X1620774Y904956D02*
Y898788D01*
G01X1621490Y902754D02*
Y906494D01*
G01X1622313Y886780D02*
Y886441D01*
G01X1623026Y904956D02*
Y898788D01*
G01X1623726Y904956D02*
Y898788D01*
G01X1613829Y908393D02*
X1612648Y912330D01*
G01X1621250Y888082D02*
X1622198Y886441D01*
G01X1622509D02*
X1622313Y886780D01*
G01X1608909Y888409D02*
X1610878Y886441D01*
G01X1621250Y888082D02*
X1622313Y886780D01*
G01X1621070Y887492D02*
X1622121Y886441D01*
G01X1609894Y909378D02*
X1606941Y912330D01*
G01X1601381Y886441D02*
X1657183D01*
G01X1637494Y887492D02*
X1621070D01*
G01X1611664Y888082D02*
X1646900D01*
G01X1644735Y888208D02*
X1613829D01*
G01X1647650Y888409D02*
X1610878D01*
G01X1644735Y888995D02*
X1613829D01*
G01X1606941Y889393D02*
X1601381D01*
G01X1654230Y896927D02*
X1604334D01*
G01X1617121Y898788D02*
X1617821D01*
G01X1620074D02*
X1620774D01*
G01X1623026D02*
X1623726D01*
G01X1620774Y899013D02*
X1620074D01*
G01X1623726D02*
X1623026D01*
G01X1617821D02*
X1617121D01*
G01X1636380Y901769D02*
X1622474D01*
G01X1620774Y901977D02*
X1620074D01*
G01X1623726D02*
X1623026D01*
G01X1617821D02*
X1617121D01*
G01X1620774Y904956D02*
X1620074D01*
G01X1623726D02*
X1623026D01*
G01X1617821D02*
X1617121D01*
G01X1622474Y907478D02*
X1636380D01*
G01X1644735Y908393D02*
X1613829D01*
G01X1610878Y910362D02*
X1647650D01*
G01X1646900Y911330D02*
X1611664D01*
G01X1656199Y912330D02*
X1602365D01*
G01X1658791Y912415D02*
X1599736D01*
G01X1658791D02*
X1599736D01*
G01X1622474Y907478D02*
G03X1621490Y906494I0J-984D01*
G01Y902754D02*
G03X1622474Y901769I984J-1D01*
G01X1602365Y912330D02*
G03X1601381Y911346I0J-984D01*
G01X1625979Y870310D02*
Y872236D01*
G01X1626679Y870311D02*
Y872237D01*
G01Y870309D02*
X1625979D01*
G01X1626679Y870525D02*
X1625979D01*
G01X1626679Y870621D02*
X1625979D01*
G01X1626679Y870683D02*
X1625979D01*
G01X1626679Y870781D02*
X1625979D01*
G01X1626679Y871096D02*
X1625979D01*
G01Y871450D02*
X1626679D01*
G01Y871765D02*
X1625979D01*
G01X1626679Y871864D02*
X1625979D01*
G01X1626679Y871926D02*
X1625979D01*
G01X1626679Y872021D02*
X1625979D01*
G01X1626679Y872238D02*
X1625979D01*
G01X1629992Y874029D02*
G03I-728J0D01*
G01Y859069D02*
G03I-728J0D01*
G01X1625979Y904956D02*
Y898788D01*
G01X1626679Y904956D02*
Y898788D01*
G01X1625979D02*
X1626679D01*
G01Y899013D02*
X1625979D01*
G01X1626679Y901977D02*
X1625979D01*
G01X1626679Y904956D02*
X1625979D01*
G01X1613912Y1297911D02*
Y1278974D01*
G01X1677743Y-879845D02*
X2067506D01*
G01X1681264Y4275D02*
X1648617Y-947D01*
G01X1681264Y4275D02*
X1648617Y-947D01*
G01X1681264Y4275D02*
G03X1697840Y23713I-3109J19438D01*
G01X1681264Y4275D02*
G03X1697840Y23713I-3109J19438D01*
G01X1651543Y376588D02*
X1651666Y376614D01*
G01X1637369Y376588D02*
X1637493Y376614D01*
G01X1643119Y378646D02*
X1643493Y378713D01*
G01X1628945Y378646D02*
X1629319Y378713D01*
G01X1637915Y376903D02*
X1651458D01*
G01X1652088D02*
X1665084D01*
G01X1652748Y377076D02*
X1650385D01*
G01X1638574D02*
X1636212D01*
G01X1631324D02*
X1635852D01*
G01X1645498D02*
X1650025D01*
G01X1639562Y378950D02*
X1643099D01*
G01X1653735D02*
X1657272D01*
G01X1653358Y380726D02*
X1652767D01*
G01X1639185D02*
X1638594D01*
G01X1629342D02*
X1629933D01*
G01X1643515D02*
X1644106D01*
G01X1650025Y384462D02*
X1645498D01*
G01X1635852D02*
X1631324D01*
G01X1636212D02*
X1638574D01*
G01X1650385D02*
X1652748D01*
G01X1639562Y378645D02*
X1639169Y378715D01*
G01X1653735Y378645D02*
X1653342Y378715D01*
G01X1637285Y376903D02*
X1637665Y376794D01*
G01X1638574Y376882D02*
X1638654Y376859D01*
G01X1651458Y376903D02*
X1651838Y376794D01*
G01X1652748Y376882D02*
X1652828Y376859D01*
G01X1638497Y380180D02*
X1639050Y379976D01*
G01X1652670Y380180D02*
X1653224Y379976D01*
G01X1630612Y376903D02*
X1630862Y376794D01*
G01X1644785Y376903D02*
X1645035Y376794D01*
G01X1630929Y376687D02*
X1631034Y376613D01*
X1631158Y376588D01*
G01X1645102Y376687D02*
X1645208Y376613D01*
X1645331Y376588D01*
G01X1639529Y378554D02*
X1639534Y378548D01*
X1639548Y378533D01*
X1639565Y378508D01*
X1639578Y378474D01*
X1639583Y378432D01*
X1639580Y378382D01*
X1639567Y378324D01*
X1639547Y378260D01*
X1639519Y378192D01*
X1639483Y378119D01*
X1639440Y378041D01*
X1639393Y377963D01*
X1639347Y377896D01*
X1639308Y377840D01*
X1639274Y377796D01*
X1639248Y377763D01*
X1639232Y377744D01*
X1639227Y377738D01*
G01X1653702Y378554D02*
X1653708Y378548D01*
X1653721Y378533D01*
X1653738Y378508D01*
X1653751Y378474D01*
X1653756Y378432D01*
X1653753Y378382D01*
X1653741Y378324D01*
X1653720Y378260D01*
X1653692Y378192D01*
X1653656Y378119D01*
X1653613Y378041D01*
X1653566Y377963D01*
X1653521Y377896D01*
X1653481Y377840D01*
X1653447Y377796D01*
X1653421Y377763D01*
X1653405Y377744D01*
X1653400Y377738D01*
G01X1629259Y377741D02*
X1629254Y377747D01*
X1629238Y377767D01*
X1629212Y377799D01*
X1629179Y377843D01*
X1629140Y377897D01*
X1629097Y377962D01*
X1629050Y378038D01*
X1629006Y378117D01*
X1628971Y378193D01*
X1628943Y378260D01*
X1628922Y378323D01*
X1628910Y378380D01*
X1628907Y378430D01*
X1628912Y378471D01*
X1628925Y378505D01*
X1628941Y378529D01*
X1628954Y378544D01*
X1628960Y378550D01*
G01X1643432Y377741D02*
X1643427Y377747D01*
X1643411Y377767D01*
X1643385Y377799D01*
X1643352Y377843D01*
X1643313Y377897D01*
X1643270Y377962D01*
X1643224Y378038D01*
X1643180Y378117D01*
X1643144Y378193D01*
X1643116Y378260D01*
X1643095Y378323D01*
X1643083Y378380D01*
X1643080Y378430D01*
X1643085Y378471D01*
X1643098Y378505D01*
X1643114Y378529D01*
X1643128Y378544D01*
X1643133Y378550D01*
G01X1630929Y376687D02*
X1630862Y376794D01*
G01X1645102Y376687D02*
X1645035Y376794D01*
G01X1628960Y378550D02*
X1629259Y377741D01*
G01X1629951Y377003D02*
X1629319Y378713D01*
G01X1630612Y376903D02*
X1629476Y379976D01*
G01X1630862Y376794D02*
X1629661Y380044D01*
G01X1630030Y380180D02*
X1631241Y376903D01*
G01X1643133Y378550D02*
X1643432Y377741D01*
G01X1644124Y377003D02*
X1643493Y378713D01*
G01X1644785Y376903D02*
X1643650Y379976D01*
G01X1645035Y376794D02*
X1643834Y380044D01*
G01X1644204Y380180D02*
X1645415Y376903D01*
G01X1628926Y408775D02*
Y378950D01*
G01X1629319Y408775D02*
Y378713D01*
G01X1629342Y408854D02*
Y380726D01*
G01X1629539Y408854D02*
Y380726D01*
G01X1629933D02*
Y408854D01*
G01X1630612Y376903D02*
Y376588D01*
G01X1631241Y376903D02*
Y376588D01*
G01X1631324Y384462D02*
Y376588D01*
G01X1635852Y384462D02*
Y376588D01*
G01X1636212Y384462D02*
Y376588D01*
G01X1637285Y376903D02*
Y376588D01*
G01X1637915Y376903D02*
Y376588D01*
G01X1638574Y376822D02*
Y384462D01*
G01X1638594Y408854D02*
Y380726D01*
G01X1638988Y408854D02*
Y380726D01*
G01X1639169Y378715D02*
Y408775D01*
G01X1639185Y380726D02*
Y408854D01*
G01X1639562Y378645D02*
Y408775D01*
G01X1639956D02*
Y376588D01*
G01X1642705D02*
Y408775D01*
G01X1643099D02*
Y378950D01*
G01X1643493Y408775D02*
Y378713D01*
G01X1643515Y408854D02*
Y380726D01*
G01X1643712Y408854D02*
Y380726D01*
G01X1644106D02*
Y408854D01*
G01X1644785Y376903D02*
Y376588D01*
G01X1645415Y376903D02*
Y376588D01*
G01X1645498Y384462D02*
Y376588D01*
G01X1650025Y384462D02*
Y376588D01*
G01X1650385Y384462D02*
Y376588D01*
G01X1651458Y376903D02*
Y376588D01*
G01X1652088Y376903D02*
Y376588D01*
G01X1652748Y384462D02*
Y376822D01*
G01X1652767Y408854D02*
Y380726D01*
G01X1653161Y408854D02*
Y380726D01*
G01X1653342Y378715D02*
Y408775D01*
G01X1653358Y380726D02*
Y408854D01*
G01X1653735Y408775D02*
Y378645D01*
G01X1654129Y408775D02*
Y376588D01*
G01X1637285Y376903D02*
X1638497Y380180D01*
G01X1638866Y380044D02*
X1637665Y376794D01*
G01X1639050Y379976D02*
X1637915Y376903D01*
G01X1639169Y378715D02*
X1638574Y377108D01*
G01X1639041Y377233D02*
X1639562Y378645D01*
G01X1651458Y376903D02*
X1652670Y380180D01*
G01X1653039Y380044D02*
X1651838Y376794D01*
G01X1653224Y379976D02*
X1652088Y376903D01*
G01X1653342Y378715D02*
X1652748Y377108D01*
G01X1653735Y378645D02*
X1653214Y377233D01*
G01X1639041D02*
X1638961Y377101D01*
X1638837Y376978D01*
X1638654Y376859D01*
G01X1653214Y377233D02*
X1653135Y377101D01*
X1653011Y376978D01*
X1652828Y376859D01*
G01X1637665Y376794D02*
X1637598Y376687D01*
X1637493Y376614D01*
G01X1651838Y376794D02*
X1651771Y376687D01*
X1651667Y376614D01*
G01X1638574Y377013D02*
X1638202Y376793D01*
X1637793Y376646D01*
X1637325Y376588D01*
G01X1652748Y377013D02*
X1652375Y376793D01*
X1651966Y376646D01*
X1651498Y376588D01*
G01X1638654Y376859D02*
X1638629Y376846D01*
X1638602Y376833D01*
X1638574Y376822D01*
G01X1652828Y376859D02*
X1652802Y376846D01*
X1652775Y376833D01*
X1652748Y376822D01*
G01X1637915Y376903D02*
X1637819Y376862D01*
X1637738Y376828D01*
X1637684Y376804D01*
X1637665Y376794D01*
G01X1629476Y379976D02*
X1630030Y380180D01*
G01X1652088Y376903D02*
X1651992Y376862D01*
X1651911Y376828D01*
X1651858Y376804D01*
X1651838Y376794D01*
G01X1643650Y379976D02*
X1644204Y380180D01*
G01X1630862Y376794D02*
X1631241Y376903D01*
G01X1645035Y376794D02*
X1645415Y376903D01*
G01X1630862Y376794D02*
G03X1631158Y376588I296J109D01*
G01X1637369D02*
G03X1637665Y376794I0J315D01*
G01X1645035D02*
G03X1645331Y376588I296J109D01*
G01X1651543D02*
G03X1651838Y376794I-1J315D01*
G01X1639529Y378554D02*
G03X1639562Y378950I-2329J393D01*
G01X1638572Y377028D02*
G03X1639227Y377738I-1372J1923D01*
G01X1629259Y377741D02*
G03X1631288Y376588I2029J1209D01*
G01X1628926Y378950D02*
G03X1628960Y378550I2362J-1D01*
G01X1639050Y379976D02*
G03X1639185Y380726I-2030J753D01*
G01X1629342D02*
G03X1629476Y379976I2165J0D01*
G01X1638866Y380044D02*
G03X1638988Y380726I-1847J682D01*
G01X1629539D02*
G03X1629661Y380044I1968J0D01*
G01X1629933Y380726D02*
G03X1630030Y380180I1575J-2D01*
G01X1638497D02*
G03X1638594Y380726I-1478J544D01*
G01X1653702Y378556D02*
G03X1653735Y378950I-2329J393D01*
G01X1652745Y377028D02*
G03X1653400Y377738I-1372J1923D01*
G01X1643432Y377741D02*
G03X1645461Y376588I2029J1209D01*
G01X1643099Y378950D02*
G03X1643133Y378550I2362J-1D01*
G01X1653224Y379976D02*
G03X1653358Y380726I-2032J750D01*
G01X1643515D02*
G03X1643650Y379976I2165J3D01*
G01X1653039Y380044D02*
G03X1653161Y380726I-1847J682D01*
G01X1643712D02*
G03X1643834Y380044I1969J0D01*
G01X1644106Y380726D02*
G03X1644204Y380180I1575J1D01*
G01X1652670D02*
G03X1652767Y380726I-1478J544D01*
G01X1654129Y408775D02*
X1653342D01*
G01X1639956D02*
X1639169D01*
G01X1642705D02*
X1643493D01*
G01X1629342Y408854D02*
X1629933D01*
G01X1638594D02*
X1639185D01*
G01X1643515D02*
X1644106D01*
G01X1652767D02*
X1653358D01*
G01X1656846Y408872D02*
X1654161D01*
G01X1642673D02*
X1639988D01*
G01X1639400Y409069D02*
X1643300D01*
G01X1653573D02*
X1657474D01*
G01Y409265D02*
X1653573D01*
G01X1643300D02*
X1639400D01*
G01X1657474Y409659D02*
X1653573D01*
G01X1643300D02*
X1639400D01*
G01X1639858Y409266D02*
X1639867Y409228D01*
X1639895Y409128D01*
X1639936Y408998D01*
X1639988Y408872D01*
G01X1654031Y409266D02*
X1654041Y409228D01*
X1654068Y409128D01*
X1654109Y408998D01*
X1654161Y408872D01*
G01X1639858Y409266D02*
X1639845Y409318D01*
X1639813Y409461D01*
X1639774Y409659D01*
G01X1654031Y409266D02*
X1654019Y409318D01*
X1653987Y409461D01*
X1653947Y409659D01*
G01X1629127Y409069D02*
Y409659D01*
G01X1639400Y409069D02*
Y409659D01*
G01X1643300Y409069D02*
Y409659D01*
G01X1653573Y409069D02*
Y409659D01*
G01X1628630Y409266D02*
X1628642Y409318D01*
X1628674Y409461D01*
X1628713Y409659D01*
G01X1642803Y409266D02*
X1642815Y409318D01*
X1642847Y409461D01*
X1642887Y409659D01*
G01X1642673Y408872D02*
X1642728Y409006D01*
X1642769Y409138D01*
X1642795Y409232D01*
X1642803Y409266D01*
G01X1629319Y408775D02*
G03X1628713Y409659I-948J0D01*
G01X1629933Y408854D02*
G03X1629127Y409659I-806J-1D01*
G01X1628926Y408775D02*
G03X1628630Y409266I-555J0D01*
G01X1629539Y408854D02*
G03X1629127Y409265I-412J-1D01*
G01X1629342Y408854D02*
G03X1629127Y409069I-215J0D01*
G01X1643493Y408775D02*
G03X1642887Y409659I-948J0D01*
G01X1639774D02*
G03X1639169Y408775I343J-884D01*
G01X1639400Y409659D02*
G03X1638594Y408854I-1J-805D01*
G01X1644106D02*
G03X1643300Y409659I-805J0D01*
G01X1643099Y408775D02*
G03X1642803Y409266I-554J0D01*
G01X1639858D02*
G03X1639562Y408775I258J-491D01*
G01X1639400Y409265D02*
G03X1638988Y408854I0J-412D01*
G01X1643712D02*
G03X1643300Y409265I-412J-1D01*
G01X1643515Y408854D02*
G03X1643300Y409069I-215J0D01*
G01X1639400D02*
G03X1639185Y408854I0J-215D01*
G01X1639988Y408872D02*
G03X1639956Y408775I129J-96D01*
G01X1642705D02*
G03X1642673Y408872I-161J1D01*
G01X1633122Y422258D02*
G03I-709J0D01*
G01X1647295D02*
G03I-708J0D01*
G01X1653947Y409659D02*
G03X1653342Y408775I343J-884D01*
G01X1653573Y409659D02*
G03X1652767Y408854I0J-806D01*
G01X1654031Y409266D02*
G03X1653735Y408775I259J-491D01*
G01X1653573Y409265D02*
G03X1653161Y408854I0J-412D01*
G01X1653573Y409069D02*
G03X1653358Y408854I0J-215D01*
G01X1654161Y408872D02*
G03X1654129Y408775I129J-96D01*
G01X1679889Y376588D02*
X1680013Y376614D01*
G01X1665716Y376588D02*
X1665839Y376614D01*
G01X1671839Y378713D02*
X1671465Y378646D01*
G01X1657292D02*
X1657666Y378713D01*
G01X1665478Y376588D02*
X1721777D01*
G01X1665478Y376903D02*
X1665632D01*
G01X1666261D02*
X1679805D01*
G01X1680435D02*
X1693978D01*
G01X1681094Y377076D02*
X1678732D01*
G01X1666921D02*
X1665478D01*
G01X1659671D02*
X1665084D01*
G01X1673844D02*
X1678372D01*
G01X1667909Y378950D02*
X1671445D01*
G01X1682082D02*
X1685619D01*
G01X1681704Y380726D02*
X1681114D01*
G01X1657689D02*
X1658279D01*
G01X1666941D02*
X1667531D01*
G01X1671862D02*
X1672452D01*
G01X1678372Y384462D02*
X1673844D01*
G01X1666921D02*
X1665478D01*
G01X1665084D02*
X1659671D01*
G01X1678732D02*
X1681094D01*
G01X1667909Y378645D02*
X1667515Y378715D01*
G01X1682082Y378645D02*
X1681688Y378715D01*
G01X1665632Y376903D02*
X1666011Y376794D01*
G01X1666921Y376882D02*
X1667001Y376859D01*
G01X1679805Y376903D02*
X1680184Y376794D01*
G01X1681094Y376882D02*
X1681174Y376859D01*
G01X1666843Y380180D02*
X1667397Y379976D01*
G01X1681016Y380180D02*
X1681570Y379976D01*
G01X1658958Y376903D02*
X1659209Y376794D01*
G01X1673132Y376903D02*
X1673382Y376794D01*
G01X1659276Y376687D02*
X1659381Y376613D01*
X1659504Y376588D01*
G01X1673449Y376687D02*
X1673554Y376613D01*
X1673677Y376588D01*
G01X1667875Y378554D02*
X1667881Y378548D01*
X1667895Y378533D01*
X1667911Y378508D01*
X1667924Y378474D01*
X1667930Y378432D01*
X1667926Y378382D01*
X1667914Y378324D01*
X1667893Y378260D01*
X1667865Y378192D01*
X1667830Y378119D01*
X1667787Y378041D01*
X1667739Y377963D01*
X1667694Y377896D01*
X1667654Y377840D01*
X1667621Y377796D01*
X1667595Y377763D01*
X1667578Y377744D01*
X1667574Y377738D01*
G01X1682048Y378554D02*
X1682054Y378548D01*
X1682068Y378533D01*
X1682084Y378508D01*
X1682097Y378474D01*
X1682103Y378432D01*
X1682100Y378382D01*
X1682087Y378324D01*
X1682066Y378260D01*
X1682038Y378192D01*
X1682003Y378119D01*
X1681960Y378041D01*
X1681912Y377963D01*
X1681867Y377896D01*
X1681827Y377840D01*
X1681794Y377796D01*
X1681768Y377763D01*
X1681752Y377744D01*
X1681747Y377738D01*
G01X1657605Y377741D02*
X1657600Y377747D01*
X1657584Y377767D01*
X1657559Y377799D01*
X1657526Y377843D01*
X1657487Y377897D01*
X1657443Y377962D01*
X1657397Y378038D01*
X1657353Y378117D01*
X1657317Y378193D01*
X1657289Y378260D01*
X1657269Y378323D01*
X1657256Y378380D01*
X1657253Y378430D01*
X1657259Y378471D01*
X1657271Y378505D01*
X1657287Y378529D01*
X1657301Y378544D01*
X1657306Y378550D01*
G01X1671778Y377741D02*
X1671773Y377747D01*
X1671758Y377767D01*
X1671732Y377799D01*
X1671699Y377843D01*
X1671660Y377897D01*
X1671616Y377962D01*
X1671570Y378038D01*
X1671526Y378117D01*
X1671490Y378193D01*
X1671462Y378260D01*
X1671442Y378323D01*
X1671430Y378380D01*
X1671426Y378430D01*
X1671432Y378471D01*
X1671445Y378505D01*
X1671461Y378529D01*
X1671474Y378544D01*
X1671480Y378550D01*
G01X1685952Y377741D02*
X1685947Y377747D01*
X1685931Y377767D01*
X1685905Y377799D01*
X1685872Y377843D01*
X1685833Y377897D01*
X1685789Y377962D01*
X1685743Y378038D01*
X1685699Y378117D01*
X1685663Y378193D01*
X1685635Y378260D01*
X1685615Y378323D01*
X1685603Y378380D01*
X1685600Y378430D01*
X1685605Y378471D01*
X1685618Y378505D01*
X1685634Y378529D01*
X1685647Y378544D01*
X1685653Y378550D01*
G01X1659276Y376687D02*
X1659209Y376794D01*
G01X1673449Y376687D02*
X1673382Y376794D01*
G01X1657306Y378550D02*
X1657605Y377741D01*
G01X1658298Y377003D02*
X1657666Y378713D01*
G01X1658958Y376903D02*
X1657823Y379976D01*
G01X1659209Y376794D02*
X1658008Y380044D01*
G01X1658377Y380180D02*
X1659588Y376903D01*
G01X1671480Y378550D02*
X1671778Y377741D01*
G01X1672471Y377003D02*
X1671839Y378713D01*
G01X1673132Y376903D02*
X1671996Y379976D01*
G01X1672181Y380044D02*
X1673382Y376794D01*
G01X1672550Y380180D02*
X1673761Y376903D01*
G01X1656878Y408775D02*
Y376588D01*
G01X1657272Y408775D02*
Y378950D01*
G01X1657666Y408775D02*
Y378713D01*
G01X1657689Y408854D02*
Y380726D01*
G01X1657885Y408854D02*
Y380726D01*
G01X1658279D02*
Y408854D01*
G01X1658958Y376903D02*
Y376588D01*
G01X1659588Y376903D02*
Y376588D01*
G01X1659671Y384462D02*
Y376588D01*
G01X1665084D02*
Y415171D01*
G01X1665478D02*
Y376588D01*
G01X1665632Y376903D02*
Y376588D01*
G01X1666261Y376903D02*
Y376588D01*
G01X1666921Y376822D02*
Y384462D01*
G01X1666941Y408854D02*
Y380726D01*
G01X1667334Y408854D02*
Y380726D01*
G01X1667515Y378715D02*
Y408775D01*
G01X1667531Y380726D02*
Y408854D01*
G01X1667909Y408775D02*
Y378645D01*
G01X1668302Y408775D02*
Y376588D01*
G01X1671052Y408775D02*
Y376588D01*
G01X1671445Y408775D02*
Y378950D01*
G01X1671839Y408775D02*
Y378713D01*
G01X1671862Y408854D02*
Y380726D01*
G01X1672059D02*
Y408854D01*
G01X1672452Y380726D02*
Y408854D01*
G01X1673132Y376903D02*
Y376588D01*
G01X1673761D02*
Y376903D01*
G01X1673844Y384462D02*
Y376588D01*
G01X1678372Y384462D02*
Y376588D01*
G01X1678732Y384462D02*
Y376588D01*
G01X1679805Y376903D02*
Y376588D01*
G01X1680435Y376903D02*
Y376588D01*
G01X1681094Y376822D02*
Y384462D01*
G01X1681114Y408854D02*
Y380726D01*
G01X1681508Y408854D02*
Y380726D01*
G01X1681688Y378715D02*
Y408775D01*
G01X1681704Y380726D02*
Y408854D01*
G01X1682082Y378645D02*
Y408775D01*
G01X1682476D02*
Y376588D01*
G01X1685225D02*
Y408775D01*
G01X1665632Y376903D02*
X1666843Y380180D01*
G01X1667212Y380044D02*
X1666011Y376794D01*
G01X1667397Y379976D02*
X1666261Y376903D01*
G01X1667515Y378715D02*
X1666921Y377108D01*
G01X1667909Y378645D02*
X1667387Y377233D01*
G01X1679805Y376903D02*
X1681016Y380180D01*
G01X1681385Y380044D02*
X1680184Y376794D01*
G01X1681570Y379976D02*
X1680435Y376903D01*
G01X1681688Y378715D02*
X1681094Y377108D01*
G01X1681560Y377233D02*
X1682082Y378645D01*
G01X1667387Y377233D02*
X1667308Y377101D01*
X1667184Y376978D01*
X1667001Y376859D01*
G01X1681560Y377233D02*
X1681481Y377101D01*
X1681357Y376978D01*
X1681174Y376859D01*
G01X1666011Y376794D02*
X1665944Y376687D01*
X1665840Y376614D01*
G01X1680184Y376794D02*
X1680117Y376687D01*
X1680013Y376614D01*
G01X1666921Y377013D02*
X1666548Y376793D01*
X1666139Y376646D01*
X1665672Y376588D01*
G01X1681094Y377013D02*
X1680722Y376793D01*
X1680312Y376646D01*
X1679845Y376588D01*
G01X1667001Y376859D02*
X1666975Y376846D01*
X1666948Y376833D01*
X1666921Y376822D01*
G01X1681174Y376859D02*
X1681122Y376833D01*
X1681094Y376822D01*
G01X1666261Y376903D02*
X1666165Y376862D01*
X1666085Y376828D01*
X1666031Y376804D01*
X1666011Y376794D01*
G01X1680435Y376903D02*
X1680339Y376862D01*
X1680258Y376828D01*
X1680204Y376804D01*
X1680184Y376794D01*
G01X1657823Y379976D02*
X1658377Y380180D01*
G01X1671996Y379976D02*
X1672550Y380180D01*
G01X1659209Y376794D02*
X1659588Y376903D01*
G01X1673382Y376794D02*
X1673761Y376903D01*
G01X1659209Y376794D02*
G03X1659504Y376588I296J109D01*
G01X1665716D02*
G03X1666011Y376794I-1J315D01*
G01X1673382D02*
G03X1673677Y376588I296J109D01*
G01X1657605Y377741D02*
G03X1659634Y376588I2029J1209D01*
G01X1657272Y378950D02*
G03X1657306Y378550I2362J-1D01*
G01X1671778Y377741D02*
G03X1673808Y376588I2029J1209D01*
G01X1671445Y378950D02*
G03X1671480Y378550I2362J5D01*
G01X1667875Y378554D02*
G03X1667909Y378950I-2328J399D01*
G01X1666918Y377028D02*
G03X1667574Y377738I-1370J1924D01*
G01X1657689Y380726D02*
G03X1657823Y379976I2165J0D01*
G01X1671862Y380726D02*
G03X1671996Y379976I2165J0D01*
G01X1667397D02*
G03X1667531Y380726I-2031J750D01*
G01X1657885D02*
G03X1658008Y380044I1968J3D01*
G01X1667212D02*
G03X1667334Y380726I-1846J682D01*
G01X1672059D02*
G03X1672181Y380044I1968J0D01*
G01X1658279Y380726D02*
G03X1658377Y380180I1575J1D01*
G01X1666843D02*
G03X1666941Y380726I-1477J547D01*
G01X1672452D02*
G03X1672550Y380180I1575J1D01*
G01X1679889Y376588D02*
G03X1680184Y376794I-1J315D01*
G01X1682048Y378556D02*
G03X1682082Y378950I-2328J399D01*
G01X1681091Y377028D02*
G03X1681747Y377738I-1370J1924D01*
G01X1681570Y379976D02*
G03X1681704Y380726I-2031J750D01*
G01X1681385Y380044D02*
G03X1681508Y380726I-1846J685D01*
G01X1681016Y380180D02*
G03X1681114Y380726I-1477J547D01*
G01X1665084Y403524D02*
X1664595D01*
G01X1665478D02*
X1665150D01*
G01X1682476Y408775D02*
X1681688D01*
G01X1656878D02*
X1657666D01*
G01X1667515D02*
X1668302D01*
G01X1671052D02*
X1671839D01*
G01X1685225D02*
X1686012D01*
G01X1667531Y408854D02*
X1666941D01*
G01X1657689D02*
X1658279D01*
G01X1671862D02*
X1672452D01*
G01X1681114D02*
X1681704D01*
G01X1685193Y408872D02*
X1682508D01*
G01X1671019D02*
X1668335D01*
G01X1667746Y409069D02*
X1671647D01*
G01X1681919D02*
X1685820D01*
G01Y409265D02*
X1681919D01*
G01X1671647D02*
X1667746D01*
G01X1685820Y409659D02*
X1681919D01*
G01X1671647D02*
X1667746D01*
G01X1721777Y411762D02*
X1665478D01*
G01X1721777Y411959D02*
X1665478D01*
G01X1721777Y414580D02*
X1665478D01*
G01X1721777Y415171D02*
X1665150D01*
G01X1668204Y409266D02*
X1668214Y409228D01*
X1668241Y409128D01*
X1668282Y408998D01*
X1668335Y408872D01*
G01X1682378Y409266D02*
X1682387Y409228D01*
X1682414Y409128D01*
X1682456Y408998D01*
X1682508Y408872D01*
G01X1682378Y409266D02*
X1682365Y409318D01*
X1682333Y409461D01*
X1682294Y409659D01*
G01X1668121D02*
X1668160Y409463D01*
X1668192Y409318D01*
X1668204Y409266D01*
G01X1657474Y409069D02*
Y409659D01*
G01X1664595Y403524D02*
Y479049D01*
G01X1665150D02*
Y403524D01*
G01X1667746Y409069D02*
Y409659D01*
G01X1671647Y409069D02*
Y409659D01*
G01X1681919Y409069D02*
Y409659D01*
G01X1671233D02*
X1671194Y409462D01*
X1671162Y409318D01*
X1671149Y409266D01*
G01X1656976D02*
X1656989Y409318D01*
X1657021Y409461D01*
X1657060Y409659D01*
G01X1685322Y409266D02*
X1685335Y409318D01*
X1685367Y409461D01*
X1685406Y409659D01*
G01X1656846Y408872D02*
X1656901Y409006D01*
X1656942Y409138D01*
X1656968Y409232D01*
X1656976Y409266D01*
G01X1671019Y408872D02*
X1671074Y409006D01*
X1671115Y409138D01*
X1671141Y409232D01*
X1671149Y409266D01*
G01X1685193Y408872D02*
X1685247Y409006D01*
X1685289Y409138D01*
X1685314Y409232D01*
X1685322Y409266D01*
G01X1657666Y408775D02*
G03X1657060Y409659I-948J0D01*
G01X1671839Y408775D02*
G03X1671233Y409659I-948J0D01*
G01X1668121D02*
G03X1667515Y408775I342J-884D01*
G01X1658279Y408854D02*
G03X1657474Y409659I-805J0D01*
G01X1667746D02*
G03X1666941Y408854I0J-805D01*
G01X1672452D02*
G03X1671647Y409659I-805J0D01*
G01X1657272Y408775D02*
G03X1656976Y409266I-554J1D01*
G01X1668204D02*
G03X1667909Y408775I259J-490D01*
G01X1671445D02*
G03X1671149Y409266I-554J1D01*
G01X1657885Y408854D02*
G03X1657474Y409265I-411J0D01*
G01X1667746D02*
G03X1667334Y408854I0J-412D01*
G01X1672059D02*
G03X1671647Y409265I-412J-1D01*
G01X1657689Y408854D02*
G03X1657474Y409069I-215J0D01*
G01X1671862Y408854D02*
G03X1671647Y409069I-215J0D01*
G01X1667746D02*
G03X1667531Y408854I0J-215D01*
G01X1656878Y408775D02*
G03X1656846Y408872I-161J1D01*
G01X1668335D02*
G03X1668302Y408775I128J-98D01*
G01X1671052D02*
G03X1671019Y408872I-161J-1D01*
G01X1661469Y422258D02*
G03I-709J0D01*
G01X1686012Y408775D02*
G03X1685406Y409659I-948J0D01*
G01X1682294D02*
G03X1681688Y408775I342J-884D01*
G01X1681919Y409659D02*
G03X1681114Y408854I0J-805D01*
G01X1685619Y408775D02*
G03X1685322Y409266I-554J0D01*
G01X1682378D02*
G03X1682082Y408775I258J-490D01*
G01X1681919Y409265D02*
G03X1681508Y408854I0J-411D01*
G01X1681919Y409069D02*
G03X1681704Y408854I0J-215D01*
G01X1682508Y408872D02*
G03X1682476Y408775I128J-96D01*
G01X1685225D02*
G03X1685193Y408872I-161J1D01*
G01X1675642Y422258D02*
G03I-709J0D01*
G01X1685638Y378646D02*
X1686012Y378713D01*
G01X1688017Y377076D02*
X1692545D01*
G01X1686035Y380726D02*
X1686626D01*
G01X1692545Y384462D02*
X1688017D01*
G01X1687305Y376903D02*
X1687555Y376794D01*
G01X1687622Y376687D02*
X1687727Y376613D01*
X1687850Y376588D01*
G01X1687622Y376687D02*
X1687555Y376794D01*
G01X1685653Y378550D02*
X1685952Y377741D01*
G01X1686644Y377003D02*
X1686012Y378713D01*
G01X1687305Y376903D02*
X1686169Y379976D01*
G01X1687555Y376794D02*
X1686354Y380044D01*
G01X1686723Y380180D02*
X1687934Y376903D01*
G01X1685619Y408775D02*
Y378950D01*
G01X1686012Y408775D02*
Y378713D01*
G01X1686035Y408854D02*
Y380726D01*
G01X1686232Y408854D02*
Y380726D01*
G01X1686626D02*
Y408854D01*
G01X1687305Y376903D02*
Y376588D01*
G01X1687934Y376903D02*
Y376588D01*
G01X1688017Y384462D02*
Y376588D01*
G01X1686169Y379976D02*
X1686723Y380180D01*
G01X1687555Y376794D02*
X1687934Y376903D01*
G01X1687555Y376794D02*
G03X1687850Y376588I296J109D01*
G01X1685952Y377741D02*
G03X1687981Y376588I2029J1209D01*
G01X1685619Y378950D02*
G03X1685653Y378550I2362J-1D01*
G01X1686035Y380726D02*
G03X1686169Y379976I2165J0D01*
G01X1686232Y380726D02*
G03X1686354Y380044I1968J0D01*
G01X1686626Y380726D02*
G03X1686723Y380180I1575J-2D01*
G01X1686035Y408854D02*
X1686626D01*
G01X1685820Y409069D02*
Y409659D01*
G01X1686626Y408854D02*
G03X1685820Y409659I-806J-1D01*
G01X1686232Y408854D02*
G03X1685820Y409265I-412J-1D01*
G01X1686035Y408854D02*
G03X1685820Y409069I-215J0D01*
G01X1689815Y422258D02*
G03I-709J0D01*
G01X1633122Y426588D02*
G03I-709J0D01*
G01Y432100D02*
G03I-709J0D01*
G01X1647295Y426588D02*
G03I-708J0D01*
G01Y432100D02*
G03I-708J0D01*
G01X1640209Y431313D02*
G03I-709J0D01*
G01X1654382D02*
G03I-709J0D01*
G01X1659504Y438557D02*
X1655488D01*
G01X1634228D02*
X1638244D01*
G01X1641315D02*
X1645330D01*
G01X1648401D02*
X1652417D01*
G01X1651000Y439679D02*
X1649819D01*
G01X1643913D02*
X1642732D01*
G01X1636826D02*
X1635645D01*
G01X1634464Y441725D02*
X1638008D01*
G01X1641551D02*
X1645094D01*
G01X1648637D02*
X1652181D01*
G01X1654700Y456273D02*
X1653204D01*
G01X1647614D02*
X1646118D01*
G01X1640527D02*
X1639031D01*
G01X1633441D02*
X1631945D01*
G01X1630330Y458869D02*
X1635055D01*
G01X1637417D02*
X1642141D01*
G01X1644504D02*
X1649228D01*
G01X1651590D02*
X1656315D01*
G01X1655330Y461391D02*
X1652574D01*
G01X1648244D02*
X1645488D01*
G01X1641157D02*
X1638401D01*
G01X1634071D02*
X1631315D01*
G01X1635645Y439679D02*
X1634258Y442083D01*
G01X1642732Y439679D02*
X1641344Y442083D01*
G01X1633441Y456273D02*
X1634228Y454909D01*
G01X1649819Y439679D02*
X1648431Y442083D01*
G01X1640527Y456273D02*
X1641315Y454909D01*
G01X1656905Y439679D02*
X1655517Y442083D01*
G01X1647614Y456273D02*
X1648401Y454909D01*
G01X1654700Y456273D02*
X1655488Y454909D01*
G01X1630330Y460407D02*
Y438557D01*
G01X1631128Y455830D02*
Y452394D01*
G01Y450704D02*
Y445308D01*
G01Y443617D02*
Y442083D01*
G01X1631157Y438557D02*
Y443572D01*
G01Y445352D02*
Y450659D01*
G01Y452439D02*
Y454909D01*
G01X1634228D02*
Y452439D01*
G01Y450659D02*
Y445352D01*
G01Y443572D02*
Y438557D01*
G01X1634258Y442083D02*
Y443617D01*
G01Y445308D02*
Y450704D01*
G01Y452394D02*
Y455830D01*
G01X1635055Y460407D02*
Y438557D01*
G01X1637417Y460407D02*
Y438557D01*
G01X1638214Y455830D02*
Y452394D01*
G01Y450704D02*
Y445308D01*
G01Y443617D02*
Y442083D01*
G01X1638244Y438557D02*
Y443572D01*
G01Y445352D02*
Y450659D01*
G01Y452439D02*
Y454909D01*
G01X1641315D02*
Y452439D01*
G01Y450659D02*
Y445352D01*
G01Y443572D02*
Y438557D01*
G01X1641344Y442083D02*
Y443617D01*
G01Y445308D02*
Y450704D01*
G01Y452394D02*
Y455830D01*
G01X1642141Y460407D02*
Y438557D01*
G01X1644504Y460407D02*
Y438557D01*
G01X1645301Y455830D02*
Y452394D01*
G01Y450704D02*
Y445308D01*
G01Y443617D02*
Y442083D01*
G01X1645330Y438557D02*
Y443572D01*
G01Y445352D02*
Y450659D01*
G01Y452439D02*
Y454909D01*
G01X1648401D02*
Y452439D01*
G01Y450659D02*
Y445352D01*
G01Y443572D02*
Y438557D01*
G01X1648431Y442083D02*
Y443617D01*
G01Y445308D02*
Y450704D01*
G01Y452394D02*
Y455830D01*
G01X1649228Y460407D02*
Y438557D01*
G01X1651590Y460407D02*
Y438557D01*
G01X1652387Y455830D02*
Y452394D01*
G01Y450704D02*
Y445308D01*
G01Y443617D02*
Y442083D01*
G01X1652417Y438557D02*
Y443572D01*
G01Y445352D02*
Y450659D01*
G01Y452439D02*
Y454909D01*
G01X1655488D02*
Y452439D01*
G01Y450659D02*
Y445352D01*
G01Y443572D02*
Y438557D01*
G01X1655517Y442083D02*
Y443617D01*
G01Y445308D02*
Y450704D01*
G01Y452394D02*
Y455830D01*
G01X1631945Y456273D02*
X1631157Y454909D01*
G01X1639031Y456273D02*
X1638244Y454909D01*
G01X1631128Y442083D02*
X1629740Y439679D01*
G01X1646118Y456273D02*
X1645330Y454909D01*
G01X1638214Y442083D02*
X1636826Y439679D01*
G01X1653204Y456273D02*
X1652417Y454909D01*
G01X1645301Y442083D02*
X1643913Y439679D01*
G01X1652387Y442083D02*
X1651000Y439679D01*
G01X1633122Y436431D02*
G03I-709J0D01*
G01Y440762D02*
G03I-709J0D01*
G01X1640209Y436825D02*
G03I-709J0D01*
G01Y441155D02*
G03I-709J0D01*
G01X1631157Y445352D02*
G03Y443572I1299J-890D01*
G01X1634228D02*
G03Y445352I-1299J890D01*
G01X1638244D02*
G03Y443572I1299J-890D01*
G01X1633122Y446273D02*
G03I-709J0D01*
G01X1640209Y445486D02*
G03I-709J0D01*
G01X1647295Y436431D02*
G03I-708J0D01*
G01Y440762D02*
G03I-708J0D01*
G01X1641315Y443572D02*
G03Y445352I-1300J890D01*
G01X1645330D02*
G03Y443572I1299J-890D01*
G01X1648401D02*
G03Y445352I-1299J890D01*
G01X1647295Y446273D02*
G03I-708J0D01*
G01X1654382Y436825D02*
G03I-709J0D01*
G01Y441155D02*
G03I-709J0D01*
G01X1652417Y445352D02*
G03Y443572I1299J-890D01*
G01X1655488D02*
G03Y445352I-1299J890D01*
G01X1654382Y445486D02*
G03I-709J0D01*
G01X1631157Y452439D02*
G03Y450659I1299J-890D01*
G01X1634228D02*
G03Y452439I-1299J890D01*
G01X1638244D02*
G03Y450659I1299J-890D01*
G01X1633122Y450604D02*
G03I-709J0D01*
G01Y454935D02*
G03I-709J0D01*
G01X1640209Y450998D02*
G03I-709J0D01*
G01Y455329D02*
G03I-709J0D01*
G01X1634258Y455830D02*
G03X1631128I-1565J0D01*
G01X1638401Y461391D02*
G03X1637417Y460407I0J-984D01*
G01X1635055D02*
G03X1634071Y461391I-984J0D01*
G01X1631315D02*
G03X1630330Y460407I-1J-984D01*
G01X1633122Y460447D02*
G03I-709J0D01*
G01X1640209Y459659D02*
G03I-709J0D01*
G01X1641315Y450659D02*
G03Y452439I-1300J890D01*
G01X1645330D02*
G03Y450659I1299J-890D01*
G01X1648401D02*
G03Y452439I-1299J890D01*
G01X1647295Y450604D02*
G03I-708J0D01*
G01Y454935D02*
G03I-708J0D01*
G01X1648431Y455830D02*
G03X1645301I-1565J0D01*
G01X1641344D02*
G03X1638214I-1565J0D01*
G01X1649228Y460407D02*
G03X1648244Y461391I-984J0D01*
G01X1645488D02*
G03X1644504Y460407I0J-984D01*
G01X1642141D02*
G03X1641157Y461391I-984J0D01*
G01X1647295Y460447D02*
G03I-708J0D01*
G01X1634661Y463124D02*
G03I-1969J0D01*
G01X1641748D02*
G03I-1969J0D01*
G01X1648834D02*
G03I-1968J0D01*
G01X1652417Y452439D02*
G03Y450659I1299J-890D01*
G01X1655488D02*
G03Y452439I-1299J890D01*
G01X1654382Y450998D02*
G03I-709J0D01*
G01Y455329D02*
G03I-709J0D01*
G01X1655517Y455830D02*
G03X1652387I-1565J0D01*
G01X1656315Y460407D02*
G03X1655330Y461391I-984J0D01*
G01X1652574D02*
G03X1651590Y460407I0J-984D01*
G01X1654382Y459659D02*
G03I-709J0D01*
G01X1655921Y463124D02*
G03I-1969J0D01*
G01X1634228Y469009D02*
X1638244D01*
G01X1641315D02*
X1645330D01*
G01X1648401D02*
X1652417D01*
G01X1655488D02*
X1659504D01*
G01X1659845Y469403D02*
X1655147D01*
G01X1652758D02*
X1648060D01*
G01X1645672D02*
X1640973D01*
G01X1638585D02*
X1633887D01*
G01X1655488Y476883D02*
X1652417D01*
G01X1648401D02*
X1645330D01*
G01X1641315D02*
X1638244D01*
G01X1634228D02*
X1631157D01*
G01X1654307Y478065D02*
X1653598D01*
G01X1647220D02*
X1646511D01*
G01X1640134D02*
X1639425D01*
G01X1633047D02*
X1632338D01*
G01X1633047D02*
X1634228Y476883D01*
G01X1640134Y478065D02*
X1641315Y476883D01*
G01X1647220Y478065D02*
X1648401Y476883D01*
G01X1654307Y478065D02*
X1655488Y476883D01*
G01X1631498Y469403D02*
X1631282Y469683D01*
X1631157Y470000D01*
G01X1638585Y469403D02*
X1638369Y469683D01*
X1638244Y470000D01*
G01X1645672Y469403D02*
X1645456Y469683D01*
X1645330Y470000D01*
G01X1652758Y469403D02*
X1652542Y469683D01*
X1652417Y470000D01*
G01X1631128Y470661D02*
X1631173Y470202D01*
X1631300Y469777D01*
X1631498Y469403D01*
G01X1638214Y470661D02*
X1638260Y470202D01*
X1638387Y469777D01*
X1638585Y469403D01*
G01X1645301Y470661D02*
X1645347Y470202D01*
X1645473Y469777D01*
X1645672Y469403D01*
G01X1652387Y470661D02*
X1652433Y470202D01*
X1652560Y469777D01*
X1652758Y469403D01*
G01X1631128Y470242D02*
X1631135Y470118D01*
X1631157Y469995D01*
G01X1638214Y470242D02*
X1638222Y470118D01*
X1638244Y469995D01*
G01X1645301Y470242D02*
X1645308Y470118D01*
X1645330Y469995D01*
G01X1631128Y476490D02*
Y470242D01*
G01X1631157Y469009D02*
Y476883D01*
G01X1652387Y470242D02*
X1652395Y470118D01*
X1652417Y469995D01*
G01X1634228Y476883D02*
Y469009D01*
G01X1634258Y476490D02*
Y470242D01*
G01X1638214Y476490D02*
Y470242D01*
G01X1638244Y469009D02*
Y476883D01*
G01X1641315D02*
Y469009D01*
G01X1641344Y476490D02*
Y470242D01*
G01X1645301Y476490D02*
Y470242D01*
G01X1645330Y469009D02*
Y476883D01*
G01X1648401D02*
Y469009D01*
G01X1648431Y476490D02*
Y470242D01*
G01X1652387Y476490D02*
Y470242D01*
G01X1652417Y469009D02*
Y476883D01*
G01X1655488D02*
Y469009D01*
G01X1655517Y476490D02*
Y470242D01*
G01X1634258D02*
X1634250Y470119D01*
X1634228Y469995D01*
G01X1641344Y470242D02*
X1641337Y470119D01*
X1641315Y469995D01*
G01X1648431Y470242D02*
X1648423Y470119D01*
X1648401Y469995D01*
G01X1655517Y470242D02*
X1655510Y470119D01*
X1655488Y469995D01*
G01X1634228Y470000D02*
X1634101Y469680D01*
X1633887Y469403D01*
G01X1641315Y470000D02*
X1641187Y469680D01*
X1640973Y469403D01*
G01X1648401Y470000D02*
X1648274Y469680D01*
X1648060Y469403D01*
G01X1655488Y470000D02*
X1655361Y469680D01*
X1655147Y469403D01*
G01X1633887D02*
X1634085Y469778D01*
X1634212Y470202D01*
X1634258Y470661D01*
G01X1640973Y469403D02*
X1641172Y469778D01*
X1641298Y470202D01*
X1641344Y470661D01*
G01X1648060Y469403D02*
X1648258Y469778D01*
X1648385Y470202D01*
X1648431Y470661D01*
G01X1655147Y469403D02*
X1655345Y469778D01*
X1655472Y470202D01*
X1655517Y470661D01*
G01X1632338Y478065D02*
X1631157Y476883D01*
G01X1639425Y478065D02*
X1638244Y476883D01*
G01X1646511Y478065D02*
X1645330Y476883D01*
G01X1653598Y478065D02*
X1652417Y476883D01*
G01X1631498Y469403D02*
G03X1633887I1195J1012D01*
G01X1638585D02*
G03X1640973I1194J1012D01*
G01X1645672D02*
G03X1648060I1194J1012D01*
G01X1633122Y464777D02*
G03I-709J0D01*
G01X1640209Y465171D02*
G03I-709J0D01*
G01X1647295Y464777D02*
G03I-708J0D01*
G01X1640209Y469502D02*
G03I-709J0D01*
G01X1652758Y469403D02*
G03X1655147I1195J1012D01*
G01X1654382Y465171D02*
G03I-709J0D01*
G01Y469502D02*
G03I-709J0D01*
G01X1661469Y426588D02*
G03I-709J0D01*
G01Y432100D02*
G03I-709J0D01*
G01X1668555Y431313D02*
G03I-709J0D01*
G01X1675642Y426588D02*
G03I-709J0D01*
G01Y432100D02*
G03I-709J0D01*
G01X1682728Y431313D02*
G03I-708J0D01*
G01X1662574Y438557D02*
X1664595D01*
G01X1665150D02*
X1666590D01*
G01X1669661D02*
X1673677D01*
G01X1676748D02*
X1680763D01*
G01X1683834D02*
X1687850D01*
G01X1686433Y439679D02*
X1685252D01*
G01X1679346D02*
X1678165D01*
G01X1672259D02*
X1671078D01*
G01X1665173D02*
X1663992D01*
G01X1658086D02*
X1656905D01*
G01X1655724Y441725D02*
X1659267D01*
G01X1662811D02*
X1666354D01*
G01X1669897D02*
X1673441D01*
G01X1676984D02*
X1680527D01*
G01X1684071D02*
X1687614D01*
G01X1683047Y456273D02*
X1681551D01*
G01X1661787D02*
X1660291D01*
G01X1667378D02*
X1668874D01*
G01X1674464D02*
X1675960D01*
G01X1677574Y458869D02*
X1672850D01*
G01X1670488D02*
X1665763D01*
G01X1663401D02*
X1658677D01*
G01X1679937D02*
X1684661D01*
G01X1683677Y461391D02*
X1680921D01*
G01X1676590D02*
X1673834D01*
G01X1669504D02*
X1666748D01*
G01X1662417D02*
X1659661D01*
G01X1663992Y439679D02*
X1662604Y442083D01*
G01X1671078Y439679D02*
X1669691Y442083D01*
G01X1661787Y456273D02*
X1662574Y454909D01*
G01X1678165Y439679D02*
X1676777Y442083D01*
G01X1668874Y456273D02*
X1669661Y454909D01*
G01X1685252Y439679D02*
X1683864Y442083D01*
G01X1675960Y456273D02*
X1676748Y454909D01*
G01X1683047Y456273D02*
X1683834Y454909D01*
G01X1656315Y460407D02*
Y438557D01*
G01X1658677Y460407D02*
Y438557D01*
G01X1659474Y455830D02*
Y452394D01*
G01Y450704D02*
Y445308D01*
G01Y443617D02*
Y442083D01*
G01X1659504Y454909D02*
Y452439D01*
G01Y450659D02*
Y445352D01*
G01Y443572D02*
Y438557D01*
G01X1662574Y454909D02*
Y452439D01*
G01Y450659D02*
Y445352D01*
G01Y443572D02*
Y438557D01*
G01X1662604Y442083D02*
Y443617D01*
G01Y445308D02*
Y450704D01*
G01Y452394D02*
Y455830D01*
G01X1663401Y438557D02*
Y460407D01*
G01X1665763D02*
Y438557D01*
G01X1666561Y455830D02*
Y452394D01*
G01Y450704D02*
Y445308D01*
G01Y443617D02*
Y442083D01*
G01X1666590Y438557D02*
Y443572D01*
G01Y445352D02*
Y450659D01*
G01Y452439D02*
Y454909D01*
G01X1669661D02*
Y452439D01*
G01Y450659D02*
Y445352D01*
G01Y443572D02*
Y438557D01*
G01X1669691Y442083D02*
Y443617D01*
G01Y445308D02*
Y450704D01*
G01Y452394D02*
Y455830D01*
G01X1670488Y438557D02*
Y460407D01*
G01X1672850D02*
Y438557D01*
G01X1673647Y455830D02*
Y452394D01*
G01Y450704D02*
Y445308D01*
G01Y443617D02*
Y442083D01*
G01X1673677Y438557D02*
Y443572D01*
G01Y445352D02*
Y450659D01*
G01Y452439D02*
Y454909D01*
G01X1676748D02*
Y452439D01*
G01Y450659D02*
Y445352D01*
G01Y443572D02*
Y438557D01*
G01X1676777Y442083D02*
Y443617D01*
G01Y445308D02*
Y450704D01*
G01Y452394D02*
Y455830D01*
G01X1677574Y438557D02*
Y460407D01*
G01X1679937D02*
Y438557D01*
G01X1680734Y455830D02*
Y452394D01*
G01Y450704D02*
Y445308D01*
G01Y443617D02*
Y442083D01*
G01X1680763Y438557D02*
Y443572D01*
G01Y445352D02*
Y450659D01*
G01Y452439D02*
Y454909D01*
G01X1683834D02*
Y452439D01*
G01Y450659D02*
Y445352D01*
G01Y443572D02*
Y438557D01*
G01X1683864Y442083D02*
Y443617D01*
G01Y445308D02*
Y450704D01*
G01Y452394D02*
Y455830D01*
G01X1684661Y460407D02*
Y438557D01*
G01X1660291Y456273D02*
X1659504Y454909D01*
G01X1667378Y456273D02*
X1666590Y454909D01*
G01X1659474Y442083D02*
X1658086Y439679D01*
G01X1674464Y456273D02*
X1673677Y454909D01*
G01X1666561Y442083D02*
X1665173Y439679D01*
G01X1681551Y456273D02*
X1680763Y454909D01*
G01X1673647Y442083D02*
X1672259Y439679D01*
G01X1680734Y442083D02*
X1679346Y439679D01*
G01X1661469Y436431D02*
G03I-709J0D01*
G01Y440762D02*
G03I-709J0D01*
G01X1659504Y445352D02*
G03Y443572I1299J-890D01*
G01X1661469Y446273D02*
G03I-709J0D01*
G01X1668555Y436825D02*
G03I-709J0D01*
G01Y441155D02*
G03I-709J0D01*
G01X1662574Y443572D02*
G03Y445352I-1299J890D01*
G01X1669661Y443572D02*
G03Y445352I-1299J890D01*
G01X1666590D02*
G03Y443572I1299J-890D01*
G01X1668555Y445486D02*
G03I-709J0D01*
G01X1662574Y450659D02*
G03Y452439I-1299J890D01*
G01X1659504D02*
G03Y450659I1299J-890D01*
G01X1661469Y450604D02*
G03I-709J0D01*
G01Y454935D02*
G03I-709J0D01*
G01X1662604Y455830D02*
G03X1659474I-1565J0D01*
G01X1663401Y460407D02*
G03X1662417Y461391I-984J0D01*
G01X1659661D02*
G03X1658677Y460407I0J-984D01*
G01X1661469Y460447D02*
G03I-709J0D01*
G01X1669661Y450659D02*
G03Y452439I-1299J890D01*
G01X1666590D02*
G03Y450659I1299J-890D01*
G01X1668555Y450998D02*
G03I-709J0D01*
G01Y455329D02*
G03I-709J0D01*
G01X1669691Y455830D02*
G03X1666561I-1565J0D01*
G01X1673834Y461391D02*
G03X1672850Y460407I0J-984D01*
G01X1670488D02*
G03X1669504Y461391I-984J0D01*
G01X1666748D02*
G03X1665763Y460407I-1J-984D01*
G01X1668555Y459659D02*
G03I-709J0D01*
G01X1663008Y463124D02*
G03I-1969J0D01*
G01X1670094D02*
G03I-1968J0D01*
G01X1675642Y436431D02*
G03I-709J0D01*
G01Y440762D02*
G03I-709J0D01*
G01X1682728Y436825D02*
G03I-708J0D01*
G01Y441155D02*
G03I-708J0D01*
G01X1680763Y445352D02*
G03Y443572I1299J-890D01*
G01X1683834D02*
G03Y445352I-1299J890D01*
G01X1676748Y443572D02*
G03Y445352I-1299J890D01*
G01X1673677D02*
G03Y443572I1299J-890D01*
G01X1675642Y446273D02*
G03I-709J0D01*
G01X1682728Y445486D02*
G03I-708J0D01*
G01X1680763Y452439D02*
G03Y450659I1299J-890D01*
G01X1683834D02*
G03Y452439I-1299J890D01*
G01X1676748Y450659D02*
G03Y452439I-1299J890D01*
G01X1673677D02*
G03Y450659I1299J-890D01*
G01X1675642Y450604D02*
G03I-709J0D01*
G01Y454935D02*
G03I-709J0D01*
G01X1682728Y450998D02*
G03I-708J0D01*
G01Y455329D02*
G03I-708J0D01*
G01X1683864Y455830D02*
G03X1680734I-1565J0D01*
G01X1676777D02*
G03X1673647I-1565J0D01*
G01X1684661Y460407D02*
G03X1683677Y461391I-984J0D01*
G01X1680921D02*
G03X1679937Y460407I0J-984D01*
G01X1677574D02*
G03X1676590Y461391I-984J0D01*
G01X1675642Y460447D02*
G03I-709J0D01*
G01X1682728Y459659D02*
G03I-708J0D01*
G01X1677181Y463124D02*
G03I-1969J0D01*
G01X1684267D02*
G03I-1968J0D01*
G01X1662574Y469009D02*
X1664595D01*
G01X1665150D02*
X1666590D01*
G01X1669661D02*
X1673677D01*
G01X1676748D02*
X1680763D01*
G01X1683834D02*
X1687850D01*
G01X1688191Y469403D02*
X1683493D01*
G01X1681105D02*
X1676406D01*
G01X1674018D02*
X1669320D01*
G01X1666932D02*
X1662233D01*
G01X1665150Y475309D02*
X1721288D01*
G01X1683834Y476883D02*
X1680763D01*
G01X1676748D02*
X1673677D01*
G01X1669661D02*
X1666590D01*
G01X1662574D02*
X1659504D01*
G01X1682653Y478065D02*
X1681945D01*
G01X1675567D02*
X1674858D01*
G01X1668480D02*
X1667771D01*
G01X1661393D02*
X1660685D01*
G01X1665150Y479049D02*
X1721288D01*
G01X1661393Y478065D02*
X1662574Y476883D01*
G01X1668480Y478065D02*
X1669661Y476883D01*
G01X1675567Y478065D02*
X1676748Y476883D01*
G01X1682653Y478065D02*
X1683834Y476883D01*
G01X1659845Y469403D02*
X1659629Y469683D01*
X1659504Y470000D01*
G01X1666932Y469403D02*
X1666715Y469683D01*
X1666590Y470000D01*
G01X1674018Y469403D02*
X1673802Y469683D01*
X1673677Y470000D01*
G01X1681105Y469403D02*
X1680889Y469683D01*
X1680763Y470000D01*
G01X1659474Y470661D02*
X1659520Y470202D01*
X1659647Y469777D01*
X1659845Y469403D01*
G01X1666561Y470661D02*
X1666606Y470202D01*
X1666733Y469777D01*
X1666932Y469403D01*
G01X1673647Y470661D02*
X1673693Y470202D01*
X1673820Y469777D01*
X1674018Y469403D01*
G01X1680734Y470661D02*
X1680780Y470202D01*
X1680906Y469777D01*
X1681105Y469403D01*
G01X1659474Y470242D02*
X1659482Y470118D01*
X1659504Y469995D01*
G01X1666561Y470242D02*
X1666568Y470118D01*
X1666590Y469995D01*
G01X1673647Y470242D02*
X1673655Y470118D01*
X1673677Y469995D01*
G01X1680734Y470242D02*
X1680741Y470118D01*
X1680763Y469995D01*
G01X1659474Y476490D02*
Y470242D01*
G01X1659504Y469009D02*
Y476883D01*
G01X1662574D02*
Y469009D01*
G01X1662604Y476490D02*
Y470242D01*
G01X1666561Y476490D02*
Y470242D01*
G01X1666590Y469009D02*
Y476883D01*
G01X1669661D02*
Y469009D01*
G01X1669691Y476490D02*
Y470242D01*
G01X1673647Y476490D02*
Y470242D01*
G01X1673677Y469009D02*
Y476883D01*
G01X1676748D02*
Y469009D01*
G01X1676777Y476490D02*
Y470242D01*
G01X1680734Y476490D02*
Y470242D01*
G01X1680763Y469009D02*
Y476883D01*
G01X1683834D02*
Y469009D01*
G01X1683864Y476490D02*
Y470242D01*
G01X1662604D02*
X1662597Y470119D01*
X1662574Y469995D01*
G01X1669691Y470242D02*
X1669683Y470119D01*
X1669661Y469995D01*
G01X1676777Y470242D02*
X1676770Y470119D01*
X1676748Y469995D01*
G01X1683864Y470242D02*
X1683856Y470119D01*
X1683834Y469995D01*
G01X1662574Y470000D02*
X1662447Y469680D01*
X1662233Y469403D01*
G01X1669661Y470000D02*
X1669534Y469680D01*
X1669320Y469403D01*
G01X1676748Y470000D02*
X1676621Y469680D01*
X1676406Y469403D01*
G01X1683834Y470000D02*
X1683707Y469680D01*
X1683493Y469403D01*
G01X1662233D02*
X1662432Y469778D01*
X1662558Y470202D01*
X1662604Y470661D01*
G01X1669320Y469403D02*
X1669518Y469778D01*
X1669645Y470202D01*
X1669691Y470661D01*
G01X1676406Y469403D02*
X1676605Y469778D01*
X1676732Y470202D01*
X1676777Y470661D01*
G01X1683493Y469403D02*
X1683691Y469778D01*
X1683818Y470202D01*
X1683864Y470661D01*
G01X1660685Y478065D02*
X1659504Y476883D01*
G01X1667771Y478065D02*
X1666590Y476883D01*
G01X1674858Y478065D02*
X1673677Y476883D01*
G01X1681945Y478065D02*
X1680763Y476883D01*
G01X1659845Y469403D02*
G03X1662233I1194J1012D01*
G01X1666932D02*
G03X1669320I1194J1012D01*
G01X1661469Y464777D02*
G03I-709J0D01*
G01X1668555Y469502D02*
G03I-709J0D01*
G01Y465171D02*
G03I-709J0D01*
G01X1675642Y464777D02*
G03I-709J0D01*
G01X1682728Y465171D02*
G03I-708J0D01*
G01X1674018Y469403D02*
G03X1676406I1194J1012D01*
G01X1681105D02*
G03X1683493I1194J1012D01*
G01X1682728Y469502D02*
G03I-708J0D01*
G01X1689815Y426588D02*
G03I-709J0D01*
G01Y432100D02*
G03I-709J0D01*
G01X1690134Y456273D02*
X1688637D01*
G01X1687023Y458869D02*
X1691748D01*
G01X1690763Y461391D02*
X1688008D01*
G01X1690134Y456273D02*
X1690921Y454909D01*
G01X1687023Y460407D02*
Y438557D01*
G01X1687821Y455830D02*
Y452394D01*
G01Y450704D02*
Y445308D01*
G01Y443617D02*
Y442083D01*
G01X1687850Y438557D02*
Y443572D01*
G01Y445352D02*
Y450659D01*
G01Y452439D02*
Y454909D01*
G01X1688637Y456273D02*
X1687850Y454909D01*
G01X1687821Y442083D02*
X1686433Y439679D01*
G01X1689815Y436431D02*
G03I-709J0D01*
G01Y440762D02*
G03I-709J0D01*
G01X1687850Y445352D02*
G03Y443572I1299J-890D01*
G01X1689815Y446273D02*
G03I-709J0D01*
G01X1687850Y452439D02*
G03Y450659I1299J-890D01*
G01X1689815Y450604D02*
G03I-709J0D01*
G01Y454935D02*
G03I-709J0D01*
G01X1690950Y455830D02*
G03X1687821I-1565J0D01*
G01X1688008Y461391D02*
G03X1687023Y460407I-1J-984D01*
G01X1689815Y460447D02*
G03I-709J0D01*
G01X1691354Y463124D02*
G03I-1969J0D01*
G01X1695278Y469403D02*
X1690580D01*
G01X1690921Y476883D02*
X1687850D01*
G01X1689740Y478065D02*
X1689031D01*
G01X1689740D02*
X1690921Y476883D01*
G01X1688191Y469403D02*
X1687975Y469683D01*
X1687850Y470000D01*
G01X1687821Y470661D02*
X1687866Y470202D01*
X1687993Y469777D01*
X1688191Y469403D01*
G01X1687821Y470242D02*
X1687828Y470118D01*
X1687850Y469995D01*
G01X1687821Y476490D02*
Y470242D01*
G01X1687850Y469009D02*
Y476883D01*
G01X1690921Y470000D02*
X1690794Y469680D01*
X1690580Y469403D01*
G01D02*
X1690778Y469778D01*
X1690905Y470202D01*
X1690950Y470661D01*
G01X1689031Y478065D02*
X1687850Y476883D01*
G01X1689815Y464777D02*
G03I-709J0D01*
G01X1688191Y469403D02*
G03X1690580I1194J1012D01*
G01X1650661Y656647D02*
X1686606D01*
G01X1650661Y703616D02*
Y656647D01*
G01X1686606D02*
Y703616D01*
G01D02*
X1650661D01*
G01X1632689Y788476D02*
X1631459Y787220D01*
G01X1635150Y787638D02*
X1633919Y786801D01*
G01X1639250Y772979D02*
X1640481Y773817D01*
G01X1657705Y782613D02*
X1655245Y780937D01*
G01X1634739Y789733D02*
X1632689Y788476D01*
G01X1639661Y770885D02*
X1641711Y772142D01*
G01X1630638Y785544D02*
X1630228Y784288D01*
G01X1631459Y787220D02*
X1630638Y785544D01*
G01X1633919Y786801D02*
X1632279Y784288D01*
G01X1640481Y773817D02*
X1642121Y776330D01*
G01X1655655Y788476D02*
X1654424Y786801D01*
G01X1641711Y772142D02*
X1642941Y773398D01*
G01X1629818Y782194D02*
Y778424D01*
G01X1631869Y781775D02*
Y778843D01*
G01X1632279Y784288D02*
X1631869Y781775D01*
G01X1642121Y776330D02*
X1642532Y778843D01*
G01X1630228Y784288D02*
X1629818Y782194D01*
G01X1644172Y776330D02*
X1644582Y778424D01*
G01X1643762Y775074D02*
X1644172Y776330D01*
G01X1654424Y786801D02*
X1653604Y784707D01*
G01X1642941Y773398D02*
X1643762Y775074D01*
G01X1642532Y778843D02*
Y781775D01*
G01X1644582Y778424D02*
Y782194D01*
G01X1647863Y770466D02*
Y772561D01*
G01X1649913D02*
Y770466D01*
G01X1653194Y781775D02*
Y778843D01*
G01X1655245Y780937D02*
Y781775D01*
G01X1653604Y784707D02*
X1653194Y781775D01*
G01X1655245D02*
X1655655Y784288D01*
G01X1630228Y776330D02*
X1630638Y775074D01*
G01X1629818Y778424D02*
X1630228Y776330D01*
G01X1644582Y782194D02*
X1644172Y784288D01*
G01X1631869Y778843D02*
X1632279Y776330D01*
G01X1642532Y781775D02*
X1642121Y784288D01*
G01X1653194Y778843D02*
X1653604Y775911D01*
G01X1631459Y773398D02*
X1632689Y772142D01*
G01X1632279Y776330D02*
X1633919Y773817D01*
G01X1642121Y784288D02*
X1640481Y786801D01*
G01X1630638Y775074D02*
X1631459Y773398D01*
G01X1643762Y785544D02*
X1642941Y787220D01*
G01X1653604Y775911D02*
X1654424Y773817D01*
G01X1644172Y784288D02*
X1643762Y785544D01*
G01X1637200Y772561D02*
X1639250Y772979D01*
G01X1637200Y788057D02*
X1635150Y787638D01*
G01X1637200Y770466D02*
X1639661Y770885D01*
G01X1649913Y770466D02*
X1647863D01*
G01Y772561D02*
X1649913D01*
G01X1634739Y770885D02*
X1637200Y770466D01*
G01X1635150Y772979D02*
X1637200Y772561D01*
G01X1632689Y772142D02*
X1634739Y770885D01*
G01X1641711Y788476D02*
X1639661Y789733D01*
G01X1633919Y773817D02*
X1635150Y772979D01*
G01X1640481Y786801D02*
X1639250Y787638D01*
G01X1642941Y787220D02*
X1641711Y788476D01*
G01X1654424Y773817D02*
X1655655Y772142D01*
G01X1637200Y790151D02*
X1634739Y789733D01*
G01X1639661D02*
X1637200Y790151D01*
G01X1639250Y787638D02*
X1637200Y788057D01*
G01X1656885Y786801D02*
X1658115Y787638D01*
G01Y780518D02*
X1656885Y779681D01*
G01X1657705Y789733D02*
X1655655Y788476D01*
G01X1681491Y782194D02*
X1680671Y781775D01*
G01X1658115Y787638D02*
X1659346Y788057D01*
G01Y780937D02*
X1658115Y780518D01*
G01X1674109Y783450D02*
X1675340Y783869D01*
G01Y782194D02*
X1674109Y781775D01*
G01X1680671Y783450D02*
X1681902Y783869D01*
G01X1662217Y772561D02*
X1663447Y772979D01*
G01X1656065Y785544D02*
X1656885Y786801D01*
G01Y779681D02*
X1656065Y778843D01*
G01X1673289Y782613D02*
X1674109Y783450D01*
G01Y781775D02*
X1673289Y780937D01*
G01X1679441Y782194D02*
X1680671Y783450D01*
G01Y781775D02*
X1680261Y781356D01*
G01X1663447Y772979D02*
X1664677Y773817D01*
G01X1663857Y770885D02*
X1665908Y772142D01*
G01X1655655Y784288D02*
X1656065Y785544D01*
G01Y778843D02*
X1655655Y777587D01*
G01X1665497Y775074D02*
X1665908Y776330D01*
G01X1667138Y773817D02*
X1667958Y775911D01*
G01X1680261Y781356D02*
X1679851Y780518D01*
G01X1664677Y773817D02*
X1665497Y775074D01*
G01X1665908Y772142D02*
X1667138Y773817D01*
G01X1655655Y777587D02*
Y776330D01*
G01X1665908D02*
Y777587D01*
G01X1667958Y775911D02*
Y778005D01*
G01X1671239Y770466D02*
Y783869D01*
G01X1673289D02*
Y782613D01*
G01Y780937D02*
Y770466D01*
G01X1677800D02*
Y780518D01*
G01X1679851D02*
Y770466D01*
G01X1684362D02*
Y780518D01*
G01X1667958Y778005D02*
X1667138Y780100D01*
G01X1655655Y776330D02*
X1656065Y775074D01*
G01X1665908Y777587D02*
X1665497Y778843D01*
G01X1667138Y785544D02*
X1666728Y786801D01*
G01X1661806Y770466D02*
X1663857Y770885D01*
G01X1659756Y783031D02*
X1657705Y782613D01*
G01X1659756Y790151D02*
X1657705Y789733D01*
G01X1686413Y770466D02*
X1684362D01*
G01X1679851D02*
X1677800D01*
G01X1673289D02*
X1671239D01*
G01X1659756D02*
X1661806D01*
G01X1659346Y772561D02*
X1662217D01*
G01Y780937D02*
X1659346D01*
G01X1682722Y782194D02*
X1681491D01*
G01X1676160D02*
X1675340D01*
G01X1661806Y783031D02*
X1659756D01*
G01X1671239Y783869D02*
X1673289D01*
G01X1675340D02*
X1676980D01*
G01X1681902D02*
X1683542D01*
G01X1665087Y785544D02*
X1667138D01*
G01X1657705Y770885D02*
X1659756Y770466D01*
G01X1658115Y772979D02*
X1659346Y772561D01*
G01X1655655Y772142D02*
X1657705Y770885D01*
G01X1665908Y781356D02*
X1663857Y782613D01*
G01X1656885Y773817D02*
X1658115Y772979D01*
G01X1664677Y779681D02*
X1663447Y780518D01*
G01X1665497Y778843D02*
X1664677Y779681D01*
G01X1667138Y780100D02*
X1665908Y781356D01*
G01X1677390D02*
X1676980Y781775D01*
G01X1666728Y786801D02*
X1665497Y788476D01*
G01X1656065Y775074D02*
X1656885Y773817D01*
G01X1664267Y786801D02*
X1665087Y785544D01*
G01X1677800Y780518D02*
X1677390Y781356D01*
G01X1684362Y780518D02*
X1683952Y781356D01*
G01X1685593Y782613D02*
X1686413Y780518D01*
G01X1659346Y788057D02*
X1661806D01*
G01X1661396Y790151D02*
X1659756D01*
G01X1663857Y782613D02*
X1661806Y783031D01*
G01X1663447Y789733D02*
X1661396Y790151D01*
G01X1663447Y780518D02*
X1662217Y780937D01*
G01X1661806Y788057D02*
X1663037Y787638D01*
G01X1676980Y783869D02*
X1678211Y783450D01*
G01X1683542Y783869D02*
X1684772Y783450D01*
G01X1676980Y781775D02*
X1676160Y782194D01*
G01X1683542Y781775D02*
X1682722Y782194D01*
G01X1665497Y788476D02*
X1663447Y789733D01*
G01X1663037Y787638D02*
X1664267Y786801D01*
G01X1678211Y783450D02*
X1679441Y782194D01*
G01X1683952Y781356D02*
X1683542Y781775D01*
G01X1684772Y783450D02*
X1685593Y782613D01*
G01X1686413Y780518D02*
Y770466D01*
G01X1689693D02*
Y783869D01*
G01X1691744Y770466D02*
X1689693D01*
G01Y783869D02*
X1691744D01*
G01X1630857Y818178D02*
Y821013D01*
G01X1632235D02*
Y818178D01*
G01X1642668D02*
Y821013D01*
G01X1645434Y867491D02*
Y818178D01*
G01X1646975D02*
Y867491D01*
G01X1647475Y818178D02*
Y867491D01*
G01X1648475D02*
Y818178D01*
G01X1650050Y846131D02*
Y818178D01*
G01X1641085Y830343D02*
X1644344Y818178D01*
G01X1628932Y828184D02*
Y830110D01*
G01Y843145D02*
Y845071D01*
G01X1629632Y828185D02*
Y830111D01*
G01Y843145D02*
Y845071D01*
G01X1631885Y822672D02*
Y824598D01*
G01Y837633D02*
Y839559D01*
G01Y852594D02*
Y854520D01*
G01X1632585Y822673D02*
Y824599D01*
G01Y837633D02*
Y839559D01*
G01Y852594D02*
Y854520D01*
G01X1634837Y825428D02*
Y827354D01*
G01Y840389D02*
Y842315D01*
G01X1635537Y825429D02*
Y827355D01*
G01Y840389D02*
Y842315D01*
G01X1637790Y828184D02*
Y830110D01*
G01Y843145D02*
Y845071D01*
G01X1638490Y828185D02*
Y830111D01*
G01Y843145D02*
Y845071D01*
G01X1640743Y822672D02*
Y824598D01*
G01Y837633D02*
Y839559D01*
G01Y852594D02*
Y854520D01*
G01X1641085Y840343D02*
Y830343D01*
G01X1641443Y822673D02*
Y824599D01*
G01Y837633D02*
Y839559D01*
G01Y852594D02*
Y854520D01*
G01X1648475Y847706D02*
X1650050Y846131D01*
G01X1631885Y822671D02*
X1632585D01*
G01X1640743D02*
X1641443D01*
G01Y822887D02*
X1640743D01*
G01X1632585D02*
X1631885D01*
G01X1641443Y822983D02*
X1640743D01*
G01X1632585D02*
X1631885D01*
G01X1641443Y823045D02*
X1640743D01*
G01X1632585D02*
X1631885D01*
G01X1641443Y823143D02*
X1640743D01*
G01X1632585D02*
X1631885D01*
G01X1641443Y823458D02*
X1640743D01*
G01X1632585D02*
X1631885D01*
G01Y823813D02*
X1632585D01*
G01X1640743D02*
X1641443D01*
G01Y824128D02*
X1640743D01*
G01X1632585D02*
X1631885D01*
G01X1641443Y824226D02*
X1640743D01*
G01X1632585D02*
X1631885D01*
G01X1641443Y824289D02*
X1640743D01*
G01X1632585D02*
X1631885D01*
G01X1641443Y824383D02*
X1640743D01*
G01X1632585D02*
X1631885D01*
G01Y824600D02*
X1632585D01*
G01X1640743D02*
X1641443D01*
G01X1635537Y825427D02*
X1634837D01*
G01X1635537Y825643D02*
X1634837D01*
G01X1635537Y825739D02*
X1634837D01*
G01X1635537Y825801D02*
X1634837D01*
G01X1635537Y825899D02*
X1634837D01*
G01X1635537Y826214D02*
X1634837D01*
G01Y826569D02*
X1635537D01*
G01Y826883D02*
X1634837D01*
G01X1635537Y826982D02*
X1634837D01*
G01X1635537Y827045D02*
X1634837D01*
G01X1635537Y827139D02*
X1634837D01*
G01X1635537Y827356D02*
X1634837D01*
G01X1638490Y828183D02*
X1637790D01*
G01X1629632D02*
X1628932D01*
G01X1638490Y828399D02*
X1637790D01*
G01X1629632D02*
X1628932D01*
G01X1638490Y828495D02*
X1637790D01*
G01X1629632D02*
X1628932D01*
G01X1638490Y828557D02*
X1637790D01*
G01X1629632D02*
X1628932D01*
G01X1638490Y828655D02*
X1637790D01*
G01X1629632D02*
X1628932D01*
G01X1638490Y828970D02*
X1637790D01*
G01X1629632D02*
X1628932D01*
G01Y829324D02*
X1629632D01*
G01X1637790D02*
X1638490D01*
G01Y829639D02*
X1637790D01*
G01X1629632D02*
X1628932D01*
G01X1638490Y829738D02*
X1637790D01*
G01X1629632D02*
X1628932D01*
G01X1638490Y829800D02*
X1637790D01*
G01X1629632D02*
X1628932D01*
G01X1638490Y829895D02*
X1637790D01*
G01X1629632D02*
X1628932D01*
G01X1638490Y830112D02*
X1637790D01*
G01X1629632D02*
X1628932D01*
G01X1631885Y837632D02*
X1632585D01*
G01X1640743D02*
X1641443D01*
G01Y837848D02*
X1640743D01*
G01X1632585D02*
X1631885D01*
G01X1641443Y837943D02*
X1640743D01*
G01X1632585D02*
X1631885D01*
G01X1641443Y838006D02*
X1640743D01*
G01X1632585D02*
X1631885D01*
G01X1641443Y838104D02*
X1640743D01*
G01X1632585D02*
X1631885D01*
G01X1641443Y838419D02*
X1640743D01*
G01X1631885D02*
X1632585D01*
G01X1631885Y838773D02*
X1632585D01*
G01X1640743D02*
X1641443D01*
G01Y839088D02*
X1640743D01*
G01X1632585D02*
X1631885D01*
G01X1641443Y839187D02*
X1640743D01*
G01X1632585D02*
X1631885D01*
G01X1641443Y839249D02*
X1640743D01*
G01X1632585D02*
X1631885D01*
G01X1641443Y839344D02*
X1640743D01*
G01X1632585D02*
X1631885D01*
G01Y839561D02*
X1632585D01*
G01X1640743D02*
X1641443D01*
G01X1635537Y840387D02*
X1634837D01*
G01X1635537Y840604D02*
X1634837D01*
G01X1635537Y840699D02*
X1634837D01*
G01X1635537Y840761D02*
X1634837D01*
G01X1635537Y840860D02*
X1634837D01*
G01X1635537Y841175D02*
X1634837D01*
G01Y841529D02*
X1635537D01*
G01Y841844D02*
X1634837D01*
G01X1635537Y841943D02*
X1634837D01*
G01X1635537Y842005D02*
X1634837D01*
G01X1635537Y842100D02*
X1634837D01*
G01X1635537Y842317D02*
X1634837D01*
G01X1638490Y843143D02*
X1637790D01*
G01X1629632D02*
X1628932D01*
G01X1638490Y843360D02*
X1637790D01*
G01X1629632D02*
X1628932D01*
G01X1638490Y843455D02*
X1637790D01*
G01X1629632D02*
X1628932D01*
G01X1638490Y843517D02*
X1637790D01*
G01X1629632D02*
X1628932D01*
G01X1638490Y843616D02*
X1637790D01*
G01X1629632D02*
X1628932D01*
G01X1638490Y843931D02*
X1637790D01*
G01X1629632D02*
X1628932D01*
G01Y844285D02*
X1629632D01*
G01X1637790D02*
X1638490D01*
G01Y844600D02*
X1637790D01*
G01X1629632D02*
X1628932D01*
G01X1638490Y844698D02*
X1637790D01*
G01X1629632D02*
X1628932D01*
G01X1638490Y844761D02*
X1637790D01*
G01X1629632D02*
X1628932D01*
G01X1638490Y844856D02*
X1637790D01*
G01X1629632D02*
X1628932D01*
G01X1638490Y845072D02*
X1637790D01*
G01X1629632D02*
X1628932D01*
G01X1631885Y852592D02*
X1632585D01*
G01X1640743D02*
X1641443D01*
G01X1638890Y829147D02*
G03I-729J0D01*
G01X1641803Y823636D02*
G03I-728J0D01*
G01X1635937Y826392D02*
G03I-728J0D01*
G01X1632984Y823636D02*
G03I-728J0D01*
G01X1638890Y844108D02*
G03I-729J0D01*
G01X1641803Y838596D02*
G03I-728J0D01*
G01X1635937Y841352D02*
G03I-728J0D01*
G01X1632984Y838596D02*
G03I-728J0D01*
G01X1628932Y858106D02*
Y860032D01*
G01X1629632Y858106D02*
Y860032D01*
G01X1634837Y855350D02*
Y857276D01*
G01X1635537Y855350D02*
Y857276D01*
G01X1637790Y858106D02*
Y860032D01*
G01X1638490Y858106D02*
Y860032D01*
G01X1641443Y852809D02*
X1640743D01*
G01X1632585D02*
X1631885D01*
G01X1641443Y852904D02*
X1640743D01*
G01X1632585D02*
X1631885D01*
G01X1641443Y852966D02*
X1640743D01*
G01X1632585D02*
X1631885D01*
G01X1641443Y853065D02*
X1640743D01*
G01X1632585D02*
X1631885D01*
G01X1641443Y853380D02*
X1640743D01*
G01X1632585D02*
X1631885D01*
G01Y853734D02*
X1632585D01*
G01X1640743D02*
X1641443D01*
G01Y854049D02*
X1640743D01*
G01X1632585D02*
X1631885D01*
G01X1641443Y854147D02*
X1640743D01*
G01X1632585D02*
X1631885D01*
G01X1641443Y854210D02*
X1640743D01*
G01X1632585D02*
X1631885D01*
G01X1641443Y854305D02*
X1640743D01*
G01X1632585D02*
X1631885D01*
G01Y854521D02*
X1632585D01*
G01X1640743D02*
X1641443D01*
G01X1635537Y855348D02*
X1634837D01*
G01X1635537Y855565D02*
X1634837D01*
G01X1635537Y855660D02*
X1634837D01*
G01X1635537Y855722D02*
X1634837D01*
G01X1635537Y855821D02*
X1634837D01*
G01X1635537Y856135D02*
X1634837D01*
G01Y856490D02*
X1635537D01*
G01Y856805D02*
X1634837D01*
G01X1635537Y856903D02*
X1634837D01*
G01X1635537Y856966D02*
X1634837D01*
G01X1635537Y857061D02*
X1634837D01*
G01X1635537Y857277D02*
X1634837D01*
G01X1638490Y858104D02*
X1637790D01*
G01X1629632D02*
X1628932D01*
G01X1638490Y858321D02*
X1637790D01*
G01X1629632D02*
X1628932D01*
G01X1638890Y859069D02*
G03I-729J0D01*
G01X1641803Y853557D02*
G03I-728J0D01*
G01X1635937Y856313D02*
G03I-728J0D01*
G01X1632984Y853557D02*
G03I-728J0D01*
G01X1642177Y869296D02*
X1642482Y869659D01*
G01Y869244D02*
X1642177Y868880D01*
G01X1628932Y873066D02*
Y874992D01*
G01X1629632Y873067D02*
Y874993D01*
G01X1631885Y867554D02*
Y869480D01*
G01X1632585Y867555D02*
Y869481D01*
G01X1634837Y870310D02*
Y872236D01*
G01X1635537Y870311D02*
Y872237D01*
G01X1637790Y873066D02*
Y874992D01*
G01X1638490Y873067D02*
Y874993D01*
G01X1640743Y867554D02*
Y869480D01*
G01X1641443Y867555D02*
Y869481D01*
G01X1642177Y868880D02*
Y869296D01*
G01X1642482Y867218D02*
Y869244D01*
G01X1642787Y869659D02*
Y867218D01*
G01X1654230Y912330D02*
Y867491D01*
G01X1638490Y858416D02*
X1637790D01*
G01X1629632D02*
X1628932D01*
G01X1638490Y858478D02*
X1637790D01*
G01X1629632D02*
X1628932D01*
G01X1638490Y858576D02*
X1637790D01*
G01X1629632D02*
X1628932D01*
G01X1638490Y858891D02*
X1637790D01*
G01X1629632D02*
X1628932D01*
G01Y859246D02*
X1629632D01*
G01X1637790D02*
X1638490D01*
G01Y859561D02*
X1637790D01*
G01X1629632D02*
X1628932D01*
G01X1638490Y859659D02*
X1637790D01*
G01X1629632D02*
X1628932D01*
G01X1638490Y859722D02*
X1637790D01*
G01X1629632D02*
X1628932D01*
G01X1638490Y859817D02*
X1637790D01*
G01X1629632D02*
X1628932D01*
G01X1638490Y860033D02*
X1637790D01*
G01X1629632D02*
X1628932D01*
G01X1642787Y867218D02*
X1642482D01*
G01X1631885Y867553D02*
X1632585D01*
G01X1640743D02*
X1641443D01*
G01Y867769D02*
X1640743D01*
G01X1632585D02*
X1631885D01*
G01X1641443Y867865D02*
X1640743D01*
G01X1632585D02*
X1631885D01*
G01X1641443Y867927D02*
X1640743D01*
G01X1632585D02*
X1631885D01*
G01X1641443Y868025D02*
X1640743D01*
G01X1632585D02*
X1631885D01*
G01X1641443Y868340D02*
X1640743D01*
G01X1632585D02*
X1631885D01*
G01Y868695D02*
X1632585D01*
G01X1640743D02*
X1641443D01*
G01Y869009D02*
X1640743D01*
G01X1632585D02*
X1631885D01*
G01X1641443Y869108D02*
X1640743D01*
G01X1632585D02*
X1631885D01*
G01X1641443Y869171D02*
X1640743D01*
G01X1632585D02*
X1631885D01*
G01X1641443Y869265D02*
X1640743D01*
G01X1632585D02*
X1631885D01*
G01Y869482D02*
X1632585D01*
G01X1640743D02*
X1641443D01*
G01X1642482Y869659D02*
X1642787D01*
G01X1635537Y870309D02*
X1634837D01*
G01X1635537Y870525D02*
X1634837D01*
G01X1635537Y870621D02*
X1634837D01*
G01X1635537Y870683D02*
X1634837D01*
G01X1635537Y870781D02*
X1634837D01*
G01X1635537Y871096D02*
X1634837D01*
G01Y871450D02*
X1635537D01*
G01Y871765D02*
X1634837D01*
G01X1635537Y871864D02*
X1634837D01*
G01X1635537Y871926D02*
X1634837D01*
G01X1635537Y872021D02*
X1634837D01*
G01X1635537Y872238D02*
X1634837D01*
G01X1638490Y873065D02*
X1637790D01*
G01X1629632D02*
X1628932D01*
G01X1638490Y873281D02*
X1637790D01*
G01X1629632D02*
X1628932D01*
G01X1638490Y873376D02*
X1637790D01*
G01X1629632D02*
X1628932D01*
G01X1638490Y873439D02*
X1637790D01*
G01X1629632D02*
X1628932D01*
G01X1638490Y873537D02*
X1637790D01*
G01X1629632D02*
X1628932D01*
G01X1638490Y873852D02*
X1637790D01*
G01X1629632D02*
X1628932D01*
G01Y874206D02*
X1629632D01*
G01X1637790D02*
X1638490D01*
G01Y874521D02*
X1637790D01*
G01X1629632D02*
X1628932D01*
G01X1638490Y874620D02*
X1637790D01*
G01X1629632D02*
X1628932D01*
G01X1638490Y874682D02*
X1637790D01*
G01X1629632D02*
X1628932D01*
G01X1638490Y874777D02*
X1637790D01*
G01X1629632D02*
X1628932D01*
G01X1638490Y874994D02*
X1637790D01*
G01X1629632D02*
X1628932D01*
G01X1657235Y876982D02*
G03I-4331J0D01*
G01X1656447D02*
G03I-3543J0D01*
G01X1638890Y874029D02*
G03I-729J0D01*
G01X1641803Y868518D02*
G03I-728J0D01*
G01X1635937Y871273D02*
G03I-728J0D01*
G01X1632984Y868518D02*
G03I-728J0D01*
G01X1651587Y912330D02*
X1648634Y909378D01*
G01X1636443Y886441D02*
X1637494Y887492D01*
G01X1649618Y888409D02*
X1647650Y886441D01*
G01X1637313Y888082D02*
X1636250Y886780D01*
G01D02*
X1636054Y886441D01*
G01X1636366D02*
X1637313Y888082D01*
G01X1645916Y912330D02*
X1644735Y908393D01*
G01X1628932Y904956D02*
Y898788D01*
G01X1629632Y904956D02*
Y898788D01*
G01X1631885Y904956D02*
Y898788D01*
G01X1632585Y904956D02*
Y898788D01*
G01X1634837Y904956D02*
Y898788D01*
G01X1635537Y904956D02*
Y898788D01*
G01X1636250Y886780D02*
Y886441D01*
G01X1637364Y906494D02*
Y902754D01*
G01X1637790Y904956D02*
Y898788D01*
G01X1638490Y904956D02*
Y898788D01*
G01X1640743Y904956D02*
Y898788D01*
G01X1641443Y904956D02*
Y898788D01*
G01X1644735Y908393D02*
Y888208D01*
G01X1646900Y912330D02*
Y886441D01*
G01X1647650Y910362D02*
Y888409D01*
G01X1649618Y910362D02*
Y888409D01*
G01X1651587Y912330D02*
Y889393D01*
G01X1648634Y887425D02*
X1647650Y888409D01*
G01X1651587Y889393D02*
X1654539Y886441D01*
G01X1647650Y910362D02*
X1648634Y909378D01*
G01X1651587Y889393D02*
X1657183D01*
G01X1628932Y898788D02*
X1629632D01*
G01X1631885D02*
X1632585D01*
G01X1634837D02*
X1635537D01*
G01X1637790D02*
X1638490D01*
G01X1640743D02*
X1641443D01*
G01Y899013D02*
X1640743D01*
G01X1638490D02*
X1637790D01*
G01X1635537D02*
X1634837D01*
G01X1632585D02*
X1631885D01*
G01X1629632D02*
X1628932D01*
G01X1641443Y901977D02*
X1640743D01*
G01X1638490D02*
X1637790D01*
G01X1635537D02*
X1634837D01*
G01X1632585D02*
X1631885D01*
G01X1629632D02*
X1628932D01*
G01X1641443Y904956D02*
X1640743D01*
G01X1638490D02*
X1637790D01*
G01X1635537D02*
X1634837D01*
G01X1632585D02*
X1631885D01*
G01X1629632D02*
X1628932D01*
G01X1637364Y906494D02*
G03X1636380Y907478I-984J0D01*
G01Y901769D02*
G03X1637364Y902754I-1J985D01*
G01X1659106Y869415D02*
X1657183Y867491D01*
G01X1655805Y912330D02*
Y867491D01*
G01X1659106Y884517D02*
Y869415D01*
G01X1657183Y911346D02*
Y886441D01*
G01D02*
X1659106Y884517D01*
G01X1691438Y917637D02*
X1658791Y912415D01*
G01X1691438Y917637D02*
X1658791Y912415D01*
G01X1657183Y911346D02*
G03X1656199Y912330I-984J0D01*
G01X1733687Y-840475D02*
Y-584569D01*
G01Y-840475D02*
X2678569D01*
G01Y-780211D02*
X1733687D01*
G01Y-735085D02*
X2264914D01*
G01X1733687Y-644833D02*
X2678569D01*
G01X1733687Y-689959D02*
X2678569D01*
G01X1733687Y-584569D02*
X2678569D01*
G01X1749011Y-125711D02*
G03I-11811J0D01*
G01X1739002Y-137384D02*
X1746471Y-185771D01*
G01D02*
X1749621D01*
G01D02*
X2012351D01*
G01X1743105Y-125711D02*
G03I-5905J0D01*
G01X1697840Y-28506D02*
Y-4884D01*
G01D02*
X1953735D01*
G01X1697840Y65982D02*
Y23713D01*
G01Y65982D02*
Y23713D01*
G01X1755901Y34486D02*
G03I-18701J0D01*
G01X1744090D02*
G03I-6890J0D01*
G01X1705714Y73856D02*
G03X1697840Y65982I0J-7874D01*
G01X1705714Y73856D02*
G03X1697840Y65982I0J-7874D01*
G01X1705714Y73856D02*
X2024601D01*
G01X1705714D02*
X2024601D01*
G01X1742356Y52461D02*
X1757258Y104410D01*
G01X1708235Y376588D02*
X1708359Y376614D01*
G01X1694062Y376588D02*
X1694186Y376614D01*
G01X1713985Y378646D02*
X1714359Y378713D01*
G01X1699811Y378646D02*
X1700185Y378713D01*
G01X1694608Y376903D02*
X1708151D01*
G01X1708781D02*
X1721777D01*
G01X1709441Y377076D02*
X1707078D01*
G01X1695267D02*
X1692905D01*
G01X1702191D02*
X1706718D01*
G01X1696255Y378950D02*
X1699792D01*
G01X1710428D02*
X1713965D01*
G01X1710051Y380726D02*
X1709460D01*
G01X1695878D02*
X1695287D01*
G01X1700208D02*
X1700799D01*
G01X1714382D02*
X1714972D01*
G01X1706718Y384462D02*
X1702191D01*
G01X1692905D02*
X1695267D01*
G01X1707078D02*
X1709441D01*
G01X1696255Y378645D02*
X1695861Y378715D01*
G01X1710428Y378645D02*
X1710035Y378715D01*
G01X1693978Y376903D02*
X1694358Y376794D01*
G01X1695267Y376882D02*
X1695347Y376859D01*
G01X1708151Y376903D02*
X1708531Y376794D01*
G01X1709441Y376882D02*
X1709521Y376859D01*
G01X1695189Y380180D02*
X1695743Y379976D01*
G01X1709363Y380180D02*
X1709917Y379976D01*
G01X1701478Y376903D02*
X1701728Y376794D01*
G01X1701795Y376687D02*
X1701900Y376613D01*
X1702024Y376588D01*
G01X1696222Y378554D02*
X1696227Y378548D01*
X1696241Y378533D01*
X1696258Y378508D01*
X1696271Y378474D01*
X1696276Y378432D01*
X1696273Y378382D01*
X1696260Y378324D01*
X1696239Y378260D01*
X1696211Y378192D01*
X1696176Y378119D01*
X1696133Y378041D01*
X1696085Y377963D01*
X1696040Y377896D01*
X1696000Y377840D01*
X1695967Y377796D01*
X1695941Y377763D01*
X1695925Y377744D01*
X1695920Y377738D01*
G01X1710395Y378554D02*
X1710400Y378548D01*
X1710414Y378533D01*
X1710431Y378508D01*
X1710444Y378474D01*
X1710449Y378432D01*
X1710446Y378382D01*
X1710434Y378324D01*
X1710413Y378260D01*
X1710385Y378192D01*
X1710349Y378119D01*
X1710306Y378041D01*
X1710259Y377963D01*
X1710213Y377896D01*
X1710174Y377840D01*
X1710140Y377796D01*
X1710114Y377763D01*
X1710098Y377744D01*
X1710093Y377738D01*
G01X1700125Y377741D02*
X1700120Y377747D01*
X1700104Y377767D01*
X1700078Y377799D01*
X1700045Y377843D01*
X1700006Y377897D01*
X1699963Y377962D01*
X1699917Y378038D01*
X1699872Y378117D01*
X1699837Y378193D01*
X1699809Y378260D01*
X1699788Y378323D01*
X1699776Y378380D01*
X1699773Y378430D01*
X1699778Y378471D01*
X1699791Y378505D01*
X1699807Y378529D01*
X1699821Y378544D01*
X1699826Y378550D01*
G01X1714298Y377741D02*
X1714293Y377747D01*
X1714277Y377767D01*
X1714252Y377799D01*
X1714219Y377843D01*
X1714180Y377897D01*
X1714136Y377962D01*
X1714090Y378038D01*
X1714046Y378117D01*
X1714010Y378193D01*
X1713982Y378260D01*
X1713961Y378323D01*
X1713949Y378380D01*
X1713946Y378430D01*
X1713952Y378471D01*
X1713964Y378505D01*
X1713980Y378529D01*
X1713994Y378544D01*
X1713999Y378550D01*
G01X1701795Y376687D02*
X1701728Y376794D01*
G01X1699826Y378550D02*
X1700125Y377741D01*
G01X1700817Y377003D02*
X1700185Y378713D01*
G01X1701478Y376903D02*
X1700343Y379976D01*
G01X1701728Y376794D02*
X1700527Y380044D01*
G01X1700897Y380180D02*
X1702108Y376903D01*
G01X1713999Y378550D02*
X1714298Y377741D01*
G01X1714991Y377003D02*
X1714359Y378713D01*
G01X1715651Y376903D02*
X1714516Y379976D01*
G01X1715902Y376794D02*
X1714700Y380044D01*
G01X1715070Y380180D02*
X1716281Y376903D01*
G01X1692545Y384462D02*
Y376588D01*
G01X1692905Y384462D02*
Y376588D01*
G01X1693978Y376903D02*
Y376588D01*
G01X1694608Y376903D02*
Y376588D01*
G01X1695267Y376822D02*
Y384462D01*
G01X1695287Y408854D02*
Y380726D01*
G01X1695681Y408854D02*
Y380726D01*
G01X1695861Y378715D02*
Y408775D01*
G01X1695878Y380726D02*
Y408854D01*
G01X1696255Y378645D02*
Y408775D01*
G01X1696649D02*
Y376588D01*
G01X1699398D02*
Y408775D01*
G01X1699792D02*
Y378950D01*
G01X1700185Y408775D02*
Y378713D01*
G01X1700208Y408854D02*
Y380726D01*
G01X1700405Y408854D02*
Y380726D01*
G01X1700799D02*
Y408854D01*
G01X1701478Y376903D02*
Y376588D01*
G01X1702108Y376903D02*
Y376588D01*
G01X1702191Y384462D02*
Y376588D01*
G01X1706718Y384462D02*
Y376588D01*
G01X1707078Y384462D02*
Y376588D01*
G01X1708151Y376903D02*
Y376588D01*
G01X1708781Y376903D02*
Y376588D01*
G01X1709441Y384462D02*
Y376822D01*
G01X1709460Y408854D02*
Y380726D01*
G01X1709854Y408854D02*
Y380726D01*
G01X1710035Y378715D02*
Y408775D01*
G01X1710051Y380726D02*
Y408854D01*
G01X1710428Y408775D02*
Y378645D01*
G01X1710822Y408775D02*
Y376588D01*
G01X1713571Y408775D02*
Y376588D01*
G01X1713965Y408775D02*
Y378950D01*
G01X1714359Y408775D02*
Y378713D01*
G01X1714382Y408854D02*
Y380726D01*
G01X1714578Y408854D02*
Y380726D01*
G01X1714972D02*
Y408854D01*
G01X1693978Y376903D02*
X1695189Y380180D01*
G01X1695559Y380044D02*
X1694358Y376794D01*
G01X1695743Y379976D02*
X1694608Y376903D01*
G01X1695861Y378715D02*
X1695267Y377108D01*
G01X1695734Y377233D02*
X1696255Y378645D01*
G01X1708151Y376903D02*
X1709363Y380180D01*
G01X1709732Y380044D02*
X1708531Y376794D01*
G01X1709917Y379976D02*
X1708781Y376903D01*
G01X1710035Y378715D02*
X1709441Y377108D01*
G01X1710428Y378645D02*
X1709907Y377233D01*
G01X1695734D02*
X1695654Y377101D01*
X1695530Y376978D01*
X1695347Y376859D01*
G01X1709907Y377233D02*
X1709828Y377101D01*
X1709704Y376978D01*
X1709521Y376859D01*
G01X1694358Y376794D02*
X1694291Y376687D01*
X1694186Y376614D01*
G01X1708531Y376794D02*
X1708464Y376687D01*
X1708359Y376614D01*
G01X1695267Y377013D02*
X1694895Y376793D01*
X1694485Y376646D01*
X1694018Y376588D01*
G01X1709441Y377013D02*
X1709068Y376793D01*
X1708659Y376646D01*
X1708191Y376588D01*
G01X1695347Y376859D02*
X1695322Y376846D01*
X1695295Y376833D01*
X1695267Y376822D01*
G01X1709521Y376859D02*
X1709495Y376846D01*
X1709468Y376833D01*
X1709441Y376822D01*
G01X1694608Y376903D02*
X1694512Y376862D01*
X1694431Y376828D01*
X1694377Y376804D01*
X1694358Y376794D01*
G01X1708781Y376903D02*
X1708685Y376862D01*
X1708604Y376828D01*
X1708550Y376804D01*
X1708531Y376794D01*
G01X1700343Y379976D02*
X1700897Y380180D01*
G01X1714516Y379976D02*
X1715070Y380180D01*
G01X1701728Y376794D02*
X1702108Y376903D01*
G01X1694062Y376588D02*
G03X1694358Y376794I0J315D01*
G01X1696222Y378554D02*
G03X1696255Y378950I-2329J393D01*
G01X1695265Y377028D02*
G03X1695920Y377738I-1372J1923D01*
G01X1695743Y379976D02*
G03X1695878Y380726I-2030J753D01*
G01X1695559Y380044D02*
G03X1695681Y380726I-1847J682D01*
G01X1695189Y380180D02*
G03X1695287Y380726I-1477J547D01*
G01X1701728Y376794D02*
G03X1702024Y376588I296J109D01*
G01X1708235D02*
G03X1708531Y376794I0J315D01*
G01X1714298Y377741D02*
G03X1716327Y376588I2029J1209D01*
G01X1713965Y378950D02*
G03X1713999Y378550I2362J-1D01*
G01X1710395Y378554D02*
G03X1710428Y378950I-2329J393D01*
G01X1709438Y377028D02*
G03X1710093Y377738I-1372J1923D01*
G01X1700125Y377741D02*
G03X1702154Y376588I2029J1209D01*
G01X1699792Y378950D02*
G03X1699826Y378550I2362J-1D01*
G01X1709917Y379976D02*
G03X1710051Y380726I-2032J750D01*
G01X1714382D02*
G03X1714516Y379976I2165J0D01*
G01X1700208Y380726D02*
G03X1700343Y379976I2165J3D01*
G01X1709732Y380044D02*
G03X1709854Y380726I-1847J682D01*
G01X1714578D02*
G03X1714700Y380044I1969J0D01*
G01X1700405Y380726D02*
G03X1700527Y380044I1969J0D01*
G01X1700799Y380726D02*
G03X1700897Y380180I1575J1D01*
G01X1709363D02*
G03X1709460Y380726I-1478J544D01*
G01X1714972D02*
G03X1715070Y380180I1575J1D01*
G01X1710822Y408775D02*
X1710035D01*
G01X1696649D02*
X1695861D01*
G01X1699398D02*
X1700185D01*
G01X1713571D02*
X1714359D01*
G01X1695287Y408854D02*
X1695878D01*
G01X1700208D02*
X1700799D01*
G01X1709460D02*
X1710051D01*
G01X1714382D02*
X1714972D01*
G01X1713539Y408872D02*
X1710854D01*
G01X1699366D02*
X1696681D01*
G01X1696093Y409069D02*
X1699993D01*
G01X1710266D02*
X1714167D01*
G01Y409265D02*
X1710266D01*
G01X1699993D02*
X1696093D01*
G01X1714167Y409659D02*
X1710266D01*
G01X1699993D02*
X1696093D01*
G01X1696551Y409266D02*
X1696560Y409228D01*
X1696587Y409128D01*
X1696629Y408998D01*
X1696681Y408872D01*
G01X1696551Y409266D02*
X1696538Y409318D01*
X1696506Y409461D01*
X1696467Y409659D01*
G01X1710724Y409266D02*
X1710734Y409228D01*
X1710761Y409128D01*
X1710802Y408998D01*
X1710854Y408872D01*
G01X1710724Y409266D02*
X1710711Y409318D01*
X1710680Y409461D01*
X1710640Y409659D01*
G01X1696093Y409069D02*
Y409659D01*
G01X1699993Y409069D02*
Y409659D01*
G01X1710266Y409069D02*
Y409659D01*
G01X1714167Y409069D02*
Y409659D01*
G01X1699496Y409266D02*
X1699508Y409318D01*
X1699540Y409461D01*
X1699580Y409659D01*
G01X1713669Y409266D02*
X1713682Y409318D01*
X1713713Y409461D01*
X1713753Y409659D01*
G01X1699366Y408872D02*
X1699421Y409006D01*
X1699462Y409138D01*
X1699487Y409232D01*
X1699496Y409266D01*
G01X1713539Y408872D02*
X1713594Y409006D01*
X1713635Y409138D01*
X1713661Y409232D01*
X1713669Y409266D01*
G01X1696093Y409659D02*
G03X1695287Y408854I-1J-805D01*
G01X1696093Y409265D02*
G03X1695681Y408854I0J-412D01*
G01X1696093Y409069D02*
G03X1695878Y408854I0J-215D01*
G01X1714359Y408775D02*
G03X1713753Y409659I-948J0D01*
G01X1710640D02*
G03X1710035Y408775I343J-884D01*
G01X1700185D02*
G03X1699580Y409659I-948J0D01*
G01X1696467D02*
G03X1695861Y408775I342J-884D01*
G01X1700799Y408854D02*
G03X1699993Y409659I-805J0D01*
G01X1710266D02*
G03X1709460Y408854I-1J-805D01*
G01X1714972D02*
G03X1714167Y409659I-805J0D01*
G01X1699792Y408775D02*
G03X1699496Y409266I-555J0D01*
G01X1696551D02*
G03X1696255Y408775I258J-491D01*
G01X1713965D02*
G03X1713669Y409266I-554J0D01*
G01X1710724D02*
G03X1710428Y408775I259J-491D01*
G01X1710266Y409265D02*
G03X1709854Y408854I0J-412D01*
G01X1714578D02*
G03X1714167Y409265I-412J-1D01*
G01X1700405Y408854D02*
G03X1699993Y409265I-412J-1D01*
G01X1714382Y408854D02*
G03X1714167Y409069I-215J0D01*
G01X1710266D02*
G03X1710051Y408854I0J-215D01*
G01X1700208D02*
G03X1699993Y409069I-215J0D01*
G01X1710854Y408872D02*
G03X1710822Y408775I129J-96D01*
G01X1713571D02*
G03X1713539Y408872I-161J1D01*
G01X1696681D02*
G03X1696649Y408775I129J-96D01*
G01X1699398D02*
G03X1699366Y408872I-161J1D01*
G01X1703988Y422258D02*
G03I-708J0D01*
G01X1736582Y376588D02*
X1736706Y376615D01*
X1736811Y376688D01*
G01X1722409Y376588D02*
X1722533Y376615D01*
X1722637Y376688D01*
G01X1736706Y376614D02*
X1736582Y376588D01*
G01X1722533Y376614D02*
X1722409Y376588D01*
G01X1742331Y378646D02*
X1742705Y378713D01*
G01X1728532D02*
X1728158Y378646D01*
G01X1722171Y376588D02*
X1764297D01*
G01X1722171Y376903D02*
X1722324D01*
G01X1722954D02*
X1736498D01*
G01X1737128D02*
X1750671D01*
G01X1737787Y377076D02*
X1735425D01*
G01X1723614D02*
X1722171D01*
G01X1716364D02*
X1721777D01*
G01X1730537D02*
X1735065D01*
G01X1744710D02*
X1749238D01*
G01X1724602Y378950D02*
X1728138D01*
G01X1738775D02*
X1742311D01*
G01X1738397Y380726D02*
X1737807D01*
G01X1723634D02*
X1724224D01*
G01X1728555D02*
X1729145D01*
G01X1742728D02*
X1743319D01*
G01X1749238Y384462D02*
X1744710D01*
G01X1735065D02*
X1730537D01*
G01X1723614D02*
X1722171D01*
G01X1721777D02*
X1716364D01*
G01X1735425D02*
X1737787D01*
G01X1724602Y378645D02*
X1724208Y378715D01*
G01X1738775Y378645D02*
X1738381Y378715D01*
G01X1722324Y376903D02*
X1722704Y376794D01*
G01X1723614Y376882D02*
X1723694Y376859D01*
G01X1736498Y376903D02*
X1736877Y376794D01*
G01X1737787Y376882D02*
X1737867Y376859D01*
G01X1723536Y380180D02*
X1724090Y379976D01*
G01X1737709Y380180D02*
X1738263Y379976D01*
G01X1715651Y376903D02*
X1715902Y376794D01*
G01X1729824Y376903D02*
X1730075Y376794D01*
G01X1743998Y376903D02*
X1744248Y376794D01*
G01X1715969Y376687D02*
X1716074Y376613D01*
X1716197Y376588D01*
G01X1730142Y376687D02*
X1730247Y376613D01*
X1730370Y376588D01*
G01X1744315Y376687D02*
X1744420Y376613D01*
X1744543Y376588D01*
G01X1724568Y378554D02*
X1724574Y378548D01*
X1724587Y378533D01*
X1724604Y378508D01*
X1724617Y378474D01*
X1724622Y378432D01*
X1724619Y378382D01*
X1724607Y378324D01*
X1724586Y378260D01*
X1724558Y378192D01*
X1724522Y378119D01*
X1724480Y378041D01*
X1724432Y377963D01*
X1724387Y377896D01*
X1724347Y377840D01*
X1724313Y377796D01*
X1724287Y377763D01*
X1724271Y377744D01*
X1724267Y377738D01*
G01X1738741Y378554D02*
X1738747Y378548D01*
X1738761Y378533D01*
X1738777Y378508D01*
X1738790Y378474D01*
X1738796Y378432D01*
X1738793Y378382D01*
X1738780Y378324D01*
X1738759Y378260D01*
X1738731Y378192D01*
X1738696Y378119D01*
X1738653Y378041D01*
X1738605Y377963D01*
X1738560Y377896D01*
X1738520Y377840D01*
X1738487Y377796D01*
X1738461Y377763D01*
X1738445Y377744D01*
X1738440Y377738D01*
G01X1728471Y377741D02*
X1728466Y377747D01*
X1728450Y377767D01*
X1728425Y377799D01*
X1728392Y377843D01*
X1728353Y377897D01*
X1728309Y377962D01*
X1728263Y378038D01*
X1728219Y378117D01*
X1728183Y378192D01*
X1728155Y378260D01*
X1728135Y378323D01*
X1728122Y378380D01*
X1728119Y378430D01*
X1728125Y378471D01*
X1728137Y378505D01*
X1728154Y378529D01*
X1728167Y378544D01*
X1728172Y378550D01*
G01X1742645Y377741D02*
X1742639Y377747D01*
X1742624Y377767D01*
X1742598Y377799D01*
X1742565Y377843D01*
X1742526Y377897D01*
X1742482Y377962D01*
X1742436Y378038D01*
X1742392Y378117D01*
X1742356Y378192D01*
X1742328Y378260D01*
X1742308Y378323D01*
X1742296Y378380D01*
X1742293Y378430D01*
X1742298Y378471D01*
X1742311Y378505D01*
X1742327Y378529D01*
X1742340Y378544D01*
X1742346Y378550D01*
G01X1715969Y376687D02*
X1715902Y376794D01*
G01X1730142Y376687D02*
X1730075Y376794D01*
G01X1744315Y376687D02*
X1744248Y376794D01*
G01X1728172Y378550D02*
X1728471Y377741D01*
G01X1729164Y377003D02*
X1728532Y378713D01*
G01X1729824Y376903D02*
X1728689Y379976D01*
G01X1728874Y380044D02*
X1730075Y376794D01*
G01X1729243Y380180D02*
X1730454Y376903D01*
G01X1742346Y378550D02*
X1742645Y377741D01*
G01X1743337Y377003D02*
X1742705Y378713D01*
G01X1743998Y376903D02*
X1742862Y379976D01*
G01X1744248Y376794D02*
X1743047Y380044D01*
G01X1743416Y380180D02*
X1744627Y376903D01*
G01X1715651D02*
Y376588D01*
G01X1716281Y376903D02*
Y376588D01*
G01X1716364Y384462D02*
Y376588D01*
G01X1721777D02*
Y415171D01*
G01X1722171D02*
Y376588D01*
G01X1722324Y376903D02*
Y376588D01*
G01X1722954Y376903D02*
Y376588D01*
G01X1723614Y376822D02*
Y384462D01*
G01X1723634Y408854D02*
Y380726D01*
G01X1724027Y408854D02*
Y380726D01*
G01X1724208Y378715D02*
Y408775D01*
G01X1724224Y380726D02*
Y408854D01*
G01X1724602Y408775D02*
Y378645D01*
G01X1724995Y408775D02*
Y376588D01*
G01X1727745Y408775D02*
Y376588D01*
G01X1728138Y408775D02*
Y378950D01*
G01X1728532Y408775D02*
Y378713D01*
G01X1728555Y408854D02*
Y380726D01*
G01X1728752D02*
Y408854D01*
G01X1729145Y380726D02*
Y408854D01*
G01X1729824Y376903D02*
Y376588D01*
G01X1730454D02*
Y376903D01*
G01X1730537Y384462D02*
Y376588D01*
G01X1735065Y384462D02*
Y376588D01*
G01X1735425Y384462D02*
Y376588D01*
G01X1736498Y376903D02*
Y376588D01*
G01X1737128Y376903D02*
Y376588D01*
G01X1737787Y376822D02*
Y384462D01*
G01X1737807Y408854D02*
Y380726D01*
G01X1738200Y408854D02*
Y380726D01*
G01X1738381Y378715D02*
Y408775D01*
G01X1738397Y380726D02*
Y408854D01*
G01X1738775Y378645D02*
Y408775D01*
G01X1739169D02*
Y376588D01*
G01X1741918D02*
Y408775D01*
G01X1742311D02*
Y378950D01*
G01X1742705Y408775D02*
Y378713D01*
G01X1742728Y408854D02*
Y380726D01*
G01X1742925Y408854D02*
Y380726D01*
G01X1743319D02*
Y408854D01*
G01X1743998Y376903D02*
Y376588D01*
G01X1744627Y376903D02*
Y376588D01*
G01X1744710Y384462D02*
Y376588D01*
G01X1722324Y376903D02*
X1723536Y380180D01*
G01X1723905Y380044D02*
X1722704Y376794D01*
G01X1724090Y379976D02*
X1722954Y376903D01*
G01X1724208Y378715D02*
X1723614Y377108D01*
G01X1724602Y378645D02*
X1724080Y377233D01*
G01X1736498Y376903D02*
X1737709Y380180D01*
G01X1738078Y380044D02*
X1736877Y376794D01*
G01X1738263Y379976D02*
X1737128Y376903D01*
G01X1738381Y378715D02*
X1737787Y377108D01*
G01X1738253Y377233D02*
X1738775Y378645D01*
G01X1724080Y377233D02*
X1724001Y377101D01*
X1723877Y376978D01*
X1723694Y376859D01*
G01X1722704Y376794D02*
X1722637Y376687D01*
G01X1738253Y377233D02*
X1738174Y377101D01*
X1738050Y376978D01*
X1737867Y376859D01*
G01X1736877Y376794D02*
X1736810Y376687D01*
G01X1723614Y377013D02*
X1723241Y376793D01*
X1722832Y376646D01*
X1722365Y376588D01*
G01X1737787Y377013D02*
X1737414Y376793D01*
X1737006Y376646D01*
X1736538Y376588D01*
G01X1723694Y376859D02*
X1723668Y376846D01*
X1723641Y376833D01*
X1723614Y376822D01*
G01X1722954Y376903D02*
X1722858Y376862D01*
X1722778Y376828D01*
X1722724Y376804D01*
X1722704Y376794D01*
G01X1728689Y379976D02*
X1729243Y380180D01*
G01X1715902Y376794D02*
X1716281Y376903D01*
G01X1737867Y376859D02*
X1737815Y376833D01*
X1737787Y376822D01*
G01X1737128Y376903D02*
X1737032Y376862D01*
X1736951Y376828D01*
X1736897Y376804D01*
X1736877Y376794D01*
G01X1742862Y379976D02*
X1743416Y380180D01*
G01X1730075Y376794D02*
X1730454Y376903D01*
G01X1744248Y376794D02*
X1744627Y376903D01*
G01X1715902Y376794D02*
G03X1716197Y376588I296J109D01*
G01X1722409D02*
G03X1722704Y376794I-1J315D01*
G01X1730075D02*
G03X1730370Y376588I296J109D01*
G01X1736582D02*
G03X1736877Y376794I-1J315D01*
G01X1728471Y377741D02*
G03X1730500Y376588I2029J1209D01*
G01X1728138Y378950D02*
G03X1728172Y378550I2362J-1D01*
G01X1724568Y378556D02*
G03X1724602Y378950I-2328J399D01*
G01X1723611Y377028D02*
G03X1724267Y377738I-1370J1924D01*
G01X1738741Y378556D02*
G03X1738775Y378950I-2328J399D01*
G01X1737784Y377028D02*
G03X1738440Y377738I-1370J1924D01*
G01X1728555Y380726D02*
G03X1728689Y379976I2165J0D01*
G01X1724090D02*
G03X1724224Y380726I-2031J750D01*
G01X1738263Y379976D02*
G03X1738397Y380726I-2031J750D01*
G01X1723905Y380044D02*
G03X1724027Y380726I-1846J682D01*
G01X1728752D02*
G03X1728874Y380044I1968J0D01*
G01X1738078D02*
G03X1738200Y380726I-1846J682D01*
G01X1737709Y380180D02*
G03X1737807Y380726I-1477J547D01*
G01X1723536Y380180D02*
G03X1723634Y380726I-1477J547D01*
G01X1729145D02*
G03X1729243Y380180I1575J1D01*
G01X1744248Y376794D02*
G03X1744543Y376588I296J109D01*
G01X1742645Y377741D02*
G03X1744674Y376588I2029J1209D01*
G01X1742311Y378950D02*
G03X1742346Y378550I2362J5D01*
G01X1742728Y380726D02*
G03X1742862Y379976I2165J0D01*
G01X1742925Y380726D02*
G03X1743047Y380044I1968J0D01*
G01X1743319Y380726D02*
G03X1743416Y380180I1575J-2D01*
G01X1721777Y403524D02*
X1721288D01*
G01X1722171D02*
X1721843D01*
G01X1739169Y408775D02*
X1738381D01*
G01X1724208D02*
X1724995D01*
G01X1727745D02*
X1728532D01*
G01X1741918D02*
X1742705D01*
G01X1724224Y408854D02*
X1723634D01*
G01X1728555D02*
X1729145D01*
G01X1737807D02*
X1738397D01*
G01X1742728D02*
X1743319D01*
G01X1741885Y408872D02*
X1739201D01*
G01X1727712D02*
X1725028D01*
G01X1724439Y409069D02*
X1728340D01*
G01X1738612D02*
X1742513D01*
G01Y409265D02*
X1738612D01*
G01X1728340D02*
X1724439D01*
G01X1742513Y409659D02*
X1738612D01*
G01X1728340D02*
X1724439D01*
G01X1764297Y411762D02*
X1722171D01*
G01X1764297Y411959D02*
X1722171D01*
G01X1764297Y414580D02*
X1722171D01*
G01X1764297Y415171D02*
X1721843D01*
G01X1724897Y409266D02*
X1724907Y409228D01*
X1724934Y409128D01*
X1724975Y408998D01*
X1725028Y408872D01*
G01X1739071Y409266D02*
X1739080Y409228D01*
X1739107Y409128D01*
X1739148Y408998D01*
X1739201Y408872D01*
G01X1739071Y409266D02*
X1739058Y409318D01*
X1739026Y409461D01*
X1738987Y409659D01*
G01X1724813D02*
X1724853Y409463D01*
X1724885Y409318D01*
X1724897Y409266D01*
G01X1721288Y403524D02*
Y479049D01*
G01X1721843D02*
Y403524D01*
G01X1724439Y409069D02*
Y409659D01*
G01X1728340Y409069D02*
Y409659D01*
G01X1738612Y409069D02*
Y409659D01*
G01X1742513Y409069D02*
Y409659D01*
G01X1727926D02*
X1727887Y409462D01*
X1727855Y409318D01*
X1727842Y409266D01*
G01X1742015D02*
X1742028Y409318D01*
X1742060Y409461D01*
X1742099Y409659D01*
G01X1727712Y408872D02*
X1727767Y409006D01*
X1727808Y409138D01*
X1727834Y409232D01*
X1727842Y409266D01*
G01X1741885Y408872D02*
X1741940Y409006D01*
X1741982Y409138D01*
X1742007Y409232D01*
X1742015Y409266D01*
G01X1718161Y422258D02*
G03I-708J0D01*
G01X1728532Y408775D02*
G03X1727926Y409659I-948J0D01*
G01X1724813D02*
G03X1724208Y408775I343J-884D01*
G01X1742705D02*
G03X1742099Y409659I-948J0D01*
G01X1738987D02*
G03X1738381Y408775I342J-884D01*
G01X1738612Y409659D02*
G03X1737807Y408854I0J-805D01*
G01X1724439Y409659D02*
G03X1723634Y408854I0J-805D01*
G01X1729145D02*
G03X1728340Y409659I-805J0D01*
G01X1724897Y409266D02*
G03X1724602Y408775I259J-490D01*
G01X1728138D02*
G03X1727842Y409266I-554J1D01*
G01X1742311Y408775D02*
G03X1742015Y409266I-554J1D01*
G01X1739071D02*
G03X1738775Y408775I258J-490D01*
G01X1724439Y409265D02*
G03X1724027Y408854I0J-412D01*
G01X1728752D02*
G03X1728340Y409265I-412J-1D01*
G01X1738612D02*
G03X1738200Y408854I0J-412D01*
G01X1728555D02*
G03X1728340Y409069I-215J0D01*
G01X1724439D02*
G03X1724224Y408854I0J-215D01*
G01X1738612Y409069D02*
G03X1738397Y408854I0J-215D01*
G01X1725028Y408872D02*
G03X1724995Y408775I128J-98D01*
G01X1727745D02*
G03X1727712Y408872I-161J-1D01*
G01X1739201D02*
G03X1739169Y408775I128J-96D01*
G01X1741918D02*
G03X1741885Y408872I-161J-1D01*
G01X1732335Y422258D02*
G03I-709J0D01*
G01X1743319Y408854D02*
G03X1742513Y409659I-806J-1D01*
G01X1742925Y408854D02*
G03X1742513Y409265I-412J-1D01*
G01X1742728Y408854D02*
G03X1742513Y409069I-215J0D01*
G01X1746508Y422258D02*
G03I-709J0D01*
G01X1750755Y376588D02*
X1750879Y376615D01*
X1750984Y376688D01*
G01X1750879Y376614D02*
X1750755Y376588D01*
G01X1751301Y376903D02*
X1764297D01*
G01X1751960Y377076D02*
X1749598D01*
G01X1752571Y380726D02*
X1751980D01*
G01X1749598Y384462D02*
X1751960D01*
G01X1752948Y378645D02*
X1752554Y378715D01*
G01X1750671Y376903D02*
X1751050Y376794D01*
G01X1751960Y376882D02*
X1752040Y376859D01*
G01X1751882Y380180D02*
X1752436Y379976D01*
G01X1752915Y378554D02*
X1752920Y378548D01*
X1752934Y378533D01*
X1752950Y378508D01*
X1752963Y378474D01*
X1752969Y378432D01*
X1752966Y378382D01*
X1752953Y378324D01*
X1752932Y378260D01*
X1752904Y378192D01*
X1752869Y378119D01*
X1752826Y378041D01*
X1752778Y377963D01*
X1752733Y377896D01*
X1752693Y377840D01*
X1752660Y377796D01*
X1752634Y377763D01*
X1752618Y377744D01*
X1752613Y377738D01*
G01X1749238Y384462D02*
Y376588D01*
G01X1749598Y384462D02*
Y376588D01*
G01X1750671Y376903D02*
Y376588D01*
G01X1751301Y376903D02*
Y376588D01*
G01X1751960Y376822D02*
Y384462D01*
G01X1751980Y408854D02*
Y380726D01*
G01X1752374Y408854D02*
Y380726D01*
G01X1752554Y378715D02*
Y408775D01*
G01X1752571Y380726D02*
Y408854D01*
G01X1750671Y376903D02*
X1751882Y380180D01*
G01X1752252Y380044D02*
X1751050Y376794D01*
G01X1752436Y379976D02*
X1751301Y376903D01*
G01X1752554Y378715D02*
X1751960Y377108D01*
G01X1752426Y377233D02*
X1752948Y378645D01*
G01X1752426Y377233D02*
X1752347Y377101D01*
X1752223Y376978D01*
X1752040Y376859D01*
G01X1751050Y376794D02*
X1750984Y376687D01*
G01X1751960Y377013D02*
X1751587Y376793D01*
X1751179Y376646D01*
X1750711Y376588D01*
G01X1752040Y376859D02*
X1752015Y376846D01*
X1751988Y376833D01*
X1751960Y376822D01*
G01X1751301Y376903D02*
X1751205Y376862D01*
X1751124Y376828D01*
X1751070Y376804D01*
X1751050Y376794D01*
G01X1750755Y376588D02*
G03X1751050Y376794I-1J315D01*
G01X1751958Y377028D02*
G03X1752613Y377738I-1372J1923D01*
G01X1752436Y379976D02*
G03X1752571Y380726I-2030J753D01*
G01X1752252Y380044D02*
G03X1752374Y380726I-1847J682D01*
G01X1751882Y380180D02*
G03X1751980Y380726I-1477J547D01*
G01X1753342Y408775D02*
X1752554D01*
G01X1751980Y408854D02*
X1752571D01*
G01X1753160Y409659D02*
G03X1752554Y408775I342J-884D01*
G01X1752785Y409659D02*
G03X1751980Y408854I0J-805D01*
G01X1752785Y409265D02*
G03X1752374Y408854I0J-411D01*
G01X1752785Y409069D02*
G03X1752571Y408854I1J-215D01*
G01X1696902Y431313D02*
G03I-709J0D01*
G01X1703988Y426588D02*
G03I-708J0D01*
G01Y432100D02*
G03I-708J0D01*
G01X1711075Y431313D02*
G03I-709J0D01*
G01X1716197Y438557D02*
X1712181D01*
G01X1690921D02*
X1694937D01*
G01X1698008D02*
X1702023D01*
G01X1705094D02*
X1709110D01*
G01X1714779Y439679D02*
X1713598D01*
G01X1707693D02*
X1706511D01*
G01X1700606D02*
X1699425D01*
G01X1693519D02*
X1692338D01*
G01X1691157Y441725D02*
X1694700D01*
G01X1698244D02*
X1701787D01*
G01X1705330D02*
X1708874D01*
G01X1712417D02*
X1715960D01*
G01X1711393Y456273D02*
X1709897D01*
G01X1704307D02*
X1702811D01*
G01X1697220D02*
X1695724D01*
G01X1720094Y458869D02*
X1715370D01*
G01X1694110D02*
X1698834D01*
G01X1701197D02*
X1705921D01*
G01X1708283D02*
X1713008D01*
G01X1712023Y461391D02*
X1709267D01*
G01X1704937D02*
X1702181D01*
G01X1697850D02*
X1695094D01*
G01X1692338Y439679D02*
X1690950Y442083D01*
G01X1699425Y439679D02*
X1698037Y442083D01*
G01X1706511Y439679D02*
X1705124Y442083D01*
G01X1697220Y456273D02*
X1698008Y454909D01*
G01X1713598Y439679D02*
X1712210Y442083D01*
G01X1704307Y456273D02*
X1705094Y454909D01*
G01X1711393Y456273D02*
X1712181Y454909D01*
G01X1690921D02*
Y452439D01*
G01Y450659D02*
Y445352D01*
G01Y443572D02*
Y438557D01*
G01X1690950Y442083D02*
Y443617D01*
G01Y445308D02*
Y450704D01*
G01Y452394D02*
Y455830D01*
G01X1691748Y460407D02*
Y438557D01*
G01X1694110Y460407D02*
Y438557D01*
G01X1694907Y455830D02*
Y452394D01*
G01Y450704D02*
Y445308D01*
G01Y443617D02*
Y442083D01*
G01X1694937Y438557D02*
Y443572D01*
G01Y445352D02*
Y450659D01*
G01Y452439D02*
Y454909D01*
G01X1698008D02*
Y452439D01*
G01Y450659D02*
Y445352D01*
G01Y443572D02*
Y438557D01*
G01X1698037Y442083D02*
Y443617D01*
G01Y445308D02*
Y450704D01*
G01Y452394D02*
Y455830D01*
G01X1698834Y460407D02*
Y438557D01*
G01X1701197Y460407D02*
Y438557D01*
G01X1701994Y455830D02*
Y452394D01*
G01Y450704D02*
Y445308D01*
G01Y443617D02*
Y442083D01*
G01X1702023Y438557D02*
Y443572D01*
G01Y445352D02*
Y450659D01*
G01Y452439D02*
Y454909D01*
G01X1705094D02*
Y452439D01*
G01Y450659D02*
Y445352D01*
G01Y443572D02*
Y438557D01*
G01X1705124Y442083D02*
Y443617D01*
G01Y445308D02*
Y450704D01*
G01Y452394D02*
Y455830D01*
G01X1705921Y460407D02*
Y438557D01*
G01X1708283Y460407D02*
Y438557D01*
G01X1709080Y455830D02*
Y452394D01*
G01Y450704D02*
Y445308D01*
G01Y443617D02*
Y442083D01*
G01X1709110Y438557D02*
Y443572D01*
G01Y445352D02*
Y450659D01*
G01Y452439D02*
Y454909D01*
G01X1712181D02*
Y452439D01*
G01Y450659D02*
Y445352D01*
G01Y443572D02*
Y438557D01*
G01X1712210Y442083D02*
Y443617D01*
G01Y445308D02*
Y450704D01*
G01Y452394D02*
Y455830D01*
G01X1713008Y460407D02*
Y438557D01*
G01X1715370Y460407D02*
Y438557D01*
G01X1695724Y456273D02*
X1694937Y454909D01*
G01X1702811Y456273D02*
X1702023Y454909D01*
G01X1694907Y442083D02*
X1693519Y439679D01*
G01X1709897Y456273D02*
X1709110Y454909D01*
G01X1701994Y442083D02*
X1700606Y439679D01*
G01X1709080Y442083D02*
X1707693Y439679D01*
G01X1716167Y442083D02*
X1714779Y439679D01*
G01X1696902Y436825D02*
G03I-709J0D01*
G01Y441155D02*
G03I-709J0D01*
G01X1690921Y443572D02*
G03Y445352I-1299J890D01*
G01X1696902Y445486D02*
G03I-709J0D01*
G01X1703988Y436431D02*
G03I-708J0D01*
G01Y440762D02*
G03I-708J0D01*
G01X1694937Y445352D02*
G03Y443572I1299J-890D01*
G01X1698008D02*
G03Y445352I-1300J890D01*
G01X1702023D02*
G03Y443572I1299J-890D01*
G01X1705094D02*
G03Y445352I-1299J890D01*
G01X1703988Y446273D02*
G03I-708J0D01*
G01X1711075Y436825D02*
G03I-709J0D01*
G01Y441155D02*
G03I-709J0D01*
G01X1709110Y445352D02*
G03Y443572I1299J-890D01*
G01X1712181D02*
G03Y445352I-1299J890D01*
G01X1711075Y445486D02*
G03I-709J0D01*
G01X1690921Y450659D02*
G03Y452439I-1299J890D01*
G01X1694937D02*
G03Y450659I1299J-890D01*
G01X1696902Y450998D02*
G03I-709J0D01*
G01Y455329D02*
G03I-709J0D01*
G01X1695094Y461391D02*
G03X1694110Y460407I0J-984D01*
G01X1691748D02*
G03X1690763Y461391I-984J0D01*
G01X1696902Y459659D02*
G03I-709J0D01*
G01X1698008Y450659D02*
G03Y452439I-1300J890D01*
G01X1702023D02*
G03Y450659I1299J-890D01*
G01X1705094D02*
G03Y452439I-1299J890D01*
G01X1703988Y450604D02*
G03I-708J0D01*
G01Y454935D02*
G03I-708J0D01*
G01X1705124Y455830D02*
G03X1701994I-1565J0D01*
G01X1698037D02*
G03X1694907I-1565J0D01*
G01X1705921Y460407D02*
G03X1704937Y461391I-984J0D01*
G01X1702181D02*
G03X1701197Y460407I0J-984D01*
G01X1698834D02*
G03X1697850Y461391I-984J0D01*
G01X1703988Y460447D02*
G03I-708J0D01*
G01X1709110Y452439D02*
G03Y450659I1299J-890D01*
G01X1712181D02*
G03Y452439I-1299J890D01*
G01X1711075Y450998D02*
G03I-709J0D01*
G01Y455329D02*
G03I-709J0D01*
G01X1712210Y455830D02*
G03X1709080I-1565J0D01*
G01X1716354Y461391D02*
G03X1715370Y460407I0J-984D01*
G01X1713008D02*
G03X1712023Y461391I-984J0D01*
G01X1709267D02*
G03X1708283Y460407I0J-984D01*
G01X1711075Y459659D02*
G03I-709J0D01*
G01X1698441Y463124D02*
G03I-1969J0D01*
G01X1705527D02*
G03I-1968J0D01*
G01X1712614D02*
G03I-1969J0D01*
G01X1690921Y469009D02*
X1694937D01*
G01X1698008D02*
X1702023D01*
G01X1705094D02*
X1709110D01*
G01X1712181D02*
X1716197D01*
G01X1716538Y469403D02*
X1711839D01*
G01X1709451D02*
X1704753D01*
G01X1702365D02*
X1697666D01*
G01X1712181Y476883D02*
X1709110D01*
G01X1705094D02*
X1702023D01*
G01X1698008D02*
X1694937D01*
G01X1711000Y478065D02*
X1710291D01*
G01X1703913D02*
X1703204D01*
G01X1696826D02*
X1696118D01*
G01X1696826D02*
X1698008Y476883D01*
G01X1703913Y478065D02*
X1705094Y476883D01*
G01X1711000Y478065D02*
X1712181Y476883D01*
G01X1695278Y469403D02*
X1695062Y469683D01*
X1694937Y470000D01*
G01X1702365Y469403D02*
X1702148Y469683D01*
X1702023Y470000D01*
G01X1709451Y469403D02*
X1709235Y469683D01*
X1709110Y470000D01*
G01X1694907Y470661D02*
X1694953Y470202D01*
X1695080Y469777D01*
X1695278Y469403D01*
G01X1701994Y470661D02*
X1702039Y470202D01*
X1702166Y469777D01*
X1702365Y469403D01*
G01X1709080Y470661D02*
X1709126Y470202D01*
X1709253Y469777D01*
X1709451Y469403D01*
G01X1694907Y470242D02*
X1694915Y470118D01*
X1694937Y469995D01*
G01X1701994Y470242D02*
X1702001Y470118D01*
X1702023Y469995D01*
G01X1709080Y470242D02*
X1709088Y470118D01*
X1709110Y469995D01*
G01X1690921Y476883D02*
Y469009D01*
G01X1690950Y476490D02*
Y470242D01*
G01X1694907Y476490D02*
Y470242D01*
G01X1694937Y469009D02*
Y476883D01*
G01X1698008D02*
Y469009D01*
G01X1698037Y476490D02*
Y470242D01*
G01X1701994Y476490D02*
Y470242D01*
G01X1702023Y469009D02*
Y476883D01*
G01X1705094D02*
Y469009D01*
G01X1705124Y476490D02*
Y470242D01*
G01X1709080Y476490D02*
Y470242D01*
G01X1709110Y469009D02*
Y476883D01*
G01X1712181D02*
Y469009D01*
G01X1712210Y476490D02*
Y470242D01*
G01X1690950D02*
X1690943Y470119D01*
X1690921Y469995D01*
G01X1698037Y470242D02*
X1698030Y470119D01*
X1698008Y469995D01*
G01X1705124Y470242D02*
X1705116Y470119D01*
X1705094Y469995D01*
G01X1712210Y470242D02*
X1712203Y470119D01*
X1712181Y469995D01*
G01X1698008Y470000D02*
X1697880Y469680D01*
X1697666Y469403D01*
G01X1705094Y470000D02*
X1704967Y469680D01*
X1704753Y469403D01*
G01X1712181Y470000D02*
X1712054Y469680D01*
X1711839Y469403D01*
G01X1697666D02*
X1697865Y469778D01*
X1697991Y470202D01*
X1698037Y470661D01*
G01X1704753Y469403D02*
X1704951Y469778D01*
X1705078Y470202D01*
X1705124Y470661D01*
G01X1711839Y469403D02*
X1712038Y469778D01*
X1712165Y470202D01*
X1712210Y470661D01*
G01X1696118Y478065D02*
X1694937Y476883D01*
G01X1703204Y478065D02*
X1702023Y476883D01*
G01X1710291Y478065D02*
X1709110Y476883D01*
G01X1696902Y465171D02*
G03I-709J0D01*
G01Y469502D02*
G03I-709J0D01*
G01X1703988Y464777D02*
G03I-708J0D01*
G01X1695278Y469403D02*
G03X1697666I1194J1012D01*
G01X1702365D02*
G03X1704753I1194J1012D01*
G01X1711075Y465171D02*
G03I-709J0D01*
G01X1709451Y469403D02*
G03X1711839I1194J1012D01*
G01X1711075Y469502D02*
G03I-709J0D01*
G01X1718161Y426588D02*
G03I-708J0D01*
G01Y432100D02*
G03I-708J0D01*
G01X1725248Y431313D02*
G03I-709J0D01*
G01X1732335Y432100D02*
G03I-709J0D01*
G01Y426588D02*
G03I-709J0D01*
G01X1739421Y431313D02*
G03I-708J0D01*
G01X1746508Y432100D02*
G03I-709J0D01*
G01Y426588D02*
G03I-709J0D01*
G01X1719267Y438557D02*
X1721288D01*
G01X1721843D02*
X1723283D01*
G01X1726354D02*
X1730370D01*
G01X1733441D02*
X1737456D01*
G01X1740527D02*
X1744543D01*
G01X1743126Y439679D02*
X1741945D01*
G01X1736039D02*
X1734858D01*
G01X1728952D02*
X1727771D01*
G01X1721866D02*
X1720685D01*
G01X1719504Y441725D02*
X1723047D01*
G01X1726590D02*
X1730134D01*
G01X1733677D02*
X1737220D01*
G01X1740763D02*
X1744307D01*
G01X1746826Y456273D02*
X1745330D01*
G01X1739740D02*
X1738244D01*
G01X1718480D02*
X1716984D01*
G01X1724071D02*
X1725567D01*
G01X1731157D02*
X1732653D01*
G01X1734267Y458869D02*
X1729543D01*
G01X1727181D02*
X1722456D01*
G01X1736630D02*
X1741354D01*
G01X1743716D02*
X1748441D01*
G01X1747456Y461391D02*
X1744700D01*
G01X1740370D02*
X1737614D01*
G01X1733283D02*
X1730527D01*
G01X1726197D02*
X1723441D01*
G01X1719110D02*
X1716354D01*
G01X1720685Y439679D02*
X1719297Y442083D01*
G01X1727771Y439679D02*
X1726384Y442083D01*
G01X1718480Y456273D02*
X1719267Y454909D01*
G01X1734858Y439679D02*
X1733470Y442083D01*
G01X1725567Y456273D02*
X1726354Y454909D01*
G01X1741945Y439679D02*
X1740557Y442083D01*
G01X1732653Y456273D02*
X1733441Y454909D01*
G01X1739740Y456273D02*
X1740527Y454909D01*
G01X1716167Y455830D02*
Y452394D01*
G01Y450704D02*
Y445308D01*
G01Y443617D02*
Y442083D01*
G01X1716197Y454909D02*
Y452439D01*
G01Y450659D02*
Y445352D01*
G01Y443572D02*
Y438557D01*
G01X1719267Y454909D02*
Y452439D01*
G01Y450659D02*
Y445352D01*
G01Y443572D02*
Y438557D01*
G01X1719297Y442083D02*
Y443617D01*
G01Y445308D02*
Y450704D01*
G01Y452394D02*
Y455830D01*
G01X1720094Y438557D02*
Y460407D01*
G01X1722456D02*
Y438557D01*
G01X1723254Y455830D02*
Y452394D01*
G01Y450704D02*
Y445308D01*
G01Y443617D02*
Y442083D01*
G01X1723283Y438557D02*
Y443572D01*
G01Y445352D02*
Y450659D01*
G01Y452439D02*
Y454909D01*
G01X1726354D02*
Y452439D01*
G01Y450659D02*
Y445352D01*
G01Y443572D02*
Y438557D01*
G01X1726384Y442083D02*
Y443617D01*
G01Y445308D02*
Y450704D01*
G01Y452394D02*
Y455830D01*
G01X1727181Y438557D02*
Y460407D01*
G01X1729543D02*
Y438557D01*
G01X1730340Y455830D02*
Y452394D01*
G01Y450704D02*
Y445308D01*
G01Y443617D02*
Y442083D01*
G01X1730370Y438557D02*
Y443572D01*
G01Y445352D02*
Y450659D01*
G01Y452439D02*
Y454909D01*
G01X1733441D02*
Y452439D01*
G01Y450659D02*
Y445352D01*
G01Y443572D02*
Y438557D01*
G01X1733470Y442083D02*
Y443617D01*
G01Y445308D02*
Y450704D01*
G01Y452394D02*
Y455830D01*
G01X1734267Y438557D02*
Y460407D01*
G01X1736630D02*
Y438557D01*
G01X1737427Y455830D02*
Y452394D01*
G01Y450704D02*
Y445308D01*
G01Y443617D02*
Y442083D01*
G01X1737456Y438557D02*
Y443572D01*
G01Y445352D02*
Y450659D01*
G01Y452439D02*
Y454909D01*
G01X1740527D02*
Y452439D01*
G01Y450659D02*
Y445352D01*
G01Y443572D02*
Y438557D01*
G01X1740557Y442083D02*
Y443617D01*
G01Y445308D02*
Y450704D01*
G01Y452394D02*
Y455830D01*
G01X1741354Y460407D02*
Y438557D01*
G01X1743716Y460407D02*
Y438557D01*
G01X1744513Y455830D02*
Y452394D01*
G01Y450704D02*
Y445308D01*
G01Y443617D02*
Y442083D01*
G01X1744543Y438557D02*
Y443572D01*
G01Y445352D02*
Y450659D01*
G01Y452439D02*
Y454909D01*
G01X1716984Y456273D02*
X1716197Y454909D01*
G01X1724071Y456273D02*
X1723283Y454909D01*
G01X1731157Y456273D02*
X1730370Y454909D01*
G01X1723254Y442083D02*
X1721866Y439679D01*
G01X1738244Y456273D02*
X1737456Y454909D01*
G01X1730340Y442083D02*
X1728952Y439679D01*
G01X1745330Y456273D02*
X1744543Y454909D01*
G01X1737427Y442083D02*
X1736039Y439679D01*
G01X1744513Y442083D02*
X1743126Y439679D01*
G01X1718161Y436431D02*
G03I-708J0D01*
G01Y440762D02*
G03I-708J0D01*
G01X1716197Y445352D02*
G03Y443572I1299J-890D01*
G01X1718161Y446273D02*
G03I-708J0D01*
G01X1716197Y452439D02*
G03Y450659I1299J-890D01*
G01X1718161Y450604D02*
G03I-708J0D01*
G01Y454935D02*
G03I-708J0D01*
G01X1719297Y455830D02*
G03X1716167I-1565J0D01*
G01X1718161Y460447D02*
G03I-708J0D01*
G01X1719700Y463124D02*
G03I-1968J0D01*
G01X1725248Y441155D02*
G03I-709J0D01*
G01Y436825D02*
G03I-709J0D01*
G01X1719267Y443572D02*
G03Y445352I-1299J890D01*
G01X1726354Y443572D02*
G03Y445352I-1299J890D01*
G01X1723283D02*
G03Y443572I1299J-890D01*
G01X1725248Y445486D02*
G03I-709J0D01*
G01X1732335Y440762D02*
G03I-709J0D01*
G01Y436431D02*
G03I-709J0D01*
G01X1739421Y441155D02*
G03I-708J0D01*
G01Y436825D02*
G03I-708J0D01*
G01X1737456Y445352D02*
G03Y443572I1299J-890D01*
G01X1733441D02*
G03Y445352I-1300J890D01*
G01X1730370D02*
G03Y443572I1299J-890D01*
G01X1732335Y446273D02*
G03I-709J0D01*
G01X1739421Y445486D02*
G03I-708J0D01*
G01X1746508Y440762D02*
G03I-709J0D01*
G01Y436431D02*
G03I-709J0D01*
G01X1740527Y443572D02*
G03Y445352I-1299J890D01*
G01X1744543D02*
G03Y443572I1299J-890D01*
G01X1746508Y446273D02*
G03I-709J0D01*
G01X1719267Y450659D02*
G03Y452439I-1299J890D01*
G01X1726354Y450659D02*
G03Y452439I-1299J890D01*
G01X1723283D02*
G03Y450659I1299J-890D01*
G01X1725248Y455329D02*
G03I-709J0D01*
G01Y450998D02*
G03I-709J0D01*
G01X1726384Y455830D02*
G03X1723254I-1565J0D01*
G01X1720094Y460407D02*
G03X1719110Y461391I-984J0D01*
G01X1727181Y460407D02*
G03X1726197Y461391I-984J0D01*
G01X1723441D02*
G03X1722456Y460407I-1J-984D01*
G01X1725248Y459659D02*
G03I-709J0D01*
G01X1737456Y452439D02*
G03Y450659I1299J-890D01*
G01X1733441D02*
G03Y452439I-1300J890D01*
G01X1730370D02*
G03Y450659I1299J-890D01*
G01X1732335Y454935D02*
G03I-709J0D01*
G01Y450604D02*
G03I-709J0D01*
G01X1739421Y455329D02*
G03I-708J0D01*
G01Y450998D02*
G03I-708J0D01*
G01X1740557Y455830D02*
G03X1737427I-1565J0D01*
G01X1733470D02*
G03X1730340I-1565J0D01*
G01X1737614Y461391D02*
G03X1736630Y460407I0J-984D01*
G01X1734267D02*
G03X1733283Y461391I-984J0D01*
G01X1730527D02*
G03X1729543Y460407I0J-984D01*
G01X1732335Y460447D02*
G03I-709J0D01*
G01X1739421Y459659D02*
G03I-708J0D01*
G01X1726787Y463124D02*
G03I-1969J0D01*
G01X1733874D02*
G03I-1969J0D01*
G01X1740960D02*
G03I-1968J0D01*
G01X1740527Y450659D02*
G03Y452439I-1299J890D01*
G01X1744543D02*
G03Y450659I1299J-890D01*
G01X1746508Y454935D02*
G03I-709J0D01*
G01Y450604D02*
G03I-709J0D01*
G01X1747643Y455830D02*
G03X1744513I-1565J0D01*
G01X1744700Y461391D02*
G03X1743716Y460407I0J-984D01*
G01X1741354D02*
G03X1740370Y461391I-984J0D01*
G01X1746508Y460447D02*
G03I-709J0D01*
G01X1748047Y463124D02*
G03I-1969J0D01*
G01X1719267Y469009D02*
X1721288D01*
G01X1721843D02*
X1723283D01*
G01X1726354D02*
X1730370D01*
G01X1733441D02*
X1737456D01*
G01X1740527D02*
X1744543D01*
G01X1744884Y469403D02*
X1740186D01*
G01X1737798D02*
X1733099D01*
G01X1730711D02*
X1726013D01*
G01X1723624D02*
X1718926D01*
G01X1721843Y475309D02*
X1763808D01*
G01X1747614Y476883D02*
X1744543D01*
G01X1740527D02*
X1737456D01*
G01X1733441D02*
X1730370D01*
G01X1726354D02*
X1723283D01*
G01X1719267D02*
X1716197D01*
G01X1739346Y478065D02*
X1738637D01*
G01X1732259D02*
X1731551D01*
G01X1725173D02*
X1724464D01*
G01X1718086D02*
X1717378D01*
G01X1721843Y479049D02*
X1763808D01*
G01X1718086Y478065D02*
X1719267Y476883D01*
G01X1725173Y478065D02*
X1726354Y476883D01*
G01X1732259Y478065D02*
X1733441Y476883D01*
G01X1739346Y478065D02*
X1740527Y476883D01*
G01X1716538Y469403D02*
X1716322Y469683D01*
X1716197Y470000D01*
G01X1723624Y469403D02*
X1723408Y469683D01*
X1723283Y470000D01*
G01X1730711Y469403D02*
X1730495Y469683D01*
X1730370Y470000D01*
G01X1737798Y469403D02*
X1737582Y469683D01*
X1737456Y470000D01*
G01X1744884Y469403D02*
X1744668Y469683D01*
X1744543Y470000D01*
G01X1716167Y470661D02*
X1716213Y470202D01*
X1716339Y469777D01*
X1716538Y469403D01*
G01X1723254Y470661D02*
X1723299Y470202D01*
X1723426Y469777D01*
X1723624Y469403D01*
G01X1730340Y470661D02*
X1730386Y470202D01*
X1730513Y469777D01*
X1730711Y469403D01*
G01X1737427Y470661D02*
X1737472Y470202D01*
X1737599Y469777D01*
X1737798Y469403D01*
G01X1744513Y470661D02*
X1744559Y470202D01*
X1744686Y469777D01*
X1744884Y469403D01*
G01X1716167Y470242D02*
X1716174Y470118D01*
X1716197Y469995D01*
G01X1723254Y470242D02*
X1723261Y470118D01*
X1723283Y469995D01*
G01X1730340Y470242D02*
X1730348Y470118D01*
X1730370Y469995D01*
G01X1737427Y470242D02*
X1737434Y470118D01*
X1737456Y469995D01*
G01X1744513Y470242D02*
X1744521Y470118D01*
X1744543Y469995D01*
G01X1716167Y476490D02*
Y470242D01*
G01X1716197Y469009D02*
Y476883D01*
G01X1719267D02*
Y469009D01*
G01X1719297Y476490D02*
Y470242D01*
G01X1723254Y476490D02*
Y470242D01*
G01X1723283Y469009D02*
Y476883D01*
G01X1726354D02*
Y469009D01*
G01X1726384Y476490D02*
Y470242D01*
G01X1730340Y476490D02*
Y470242D01*
G01X1730370Y469009D02*
Y476883D01*
G01X1733441D02*
Y469009D01*
G01X1733470Y476490D02*
Y470242D01*
G01X1719297D02*
X1719289Y470119D01*
X1719267Y469995D01*
G01X1737427Y476490D02*
Y470242D01*
G01X1737456Y469009D02*
Y476883D01*
G01X1740527D02*
Y469009D01*
G01X1740557Y476490D02*
Y470242D01*
G01X1744513Y476490D02*
Y470242D01*
G01X1744543Y469009D02*
Y476883D01*
G01X1726384Y470242D02*
X1726376Y470119D01*
X1726354Y469995D01*
G01X1733470Y470242D02*
X1733463Y470119D01*
X1733441Y469995D01*
G01X1740557Y470242D02*
X1740549Y470119D01*
X1740527Y469995D01*
G01X1719267Y470000D02*
X1719140Y469680D01*
X1718926Y469403D01*
G01X1726354Y470000D02*
X1726227Y469680D01*
X1726013Y469403D01*
G01X1733441Y470000D02*
X1733313Y469680D01*
X1733099Y469403D01*
G01X1740527Y470000D02*
X1740400Y469680D01*
X1740186Y469403D01*
G01X1718926D02*
X1719124Y469778D01*
X1719251Y470202D01*
X1719297Y470661D01*
G01X1726013Y469403D02*
X1726211Y469778D01*
X1726338Y470202D01*
X1726384Y470661D01*
G01X1733099Y469403D02*
X1733298Y469778D01*
X1733424Y470202D01*
X1733470Y470661D01*
G01X1740186Y469403D02*
X1740384Y469778D01*
X1740511Y470202D01*
X1740557Y470661D01*
G01X1717378Y478065D02*
X1716197Y476883D01*
G01X1724464Y478065D02*
X1723283Y476883D01*
G01X1731551Y478065D02*
X1730370Y476883D01*
G01X1738637Y478065D02*
X1737456Y476883D01*
G01X1745724Y478065D02*
X1744543Y476883D01*
G01X1718161Y464777D02*
G03I-708J0D01*
G01X1716538Y469403D02*
G03X1718926I1194J1012D01*
G01X1723624D02*
G03X1726013I1195J1012D01*
G01X1730711D02*
G03X1733099I1194J1012D01*
G01X1737798D02*
G03X1740186I1194J1012D01*
G01X1725248Y469502D02*
G03I-709J0D01*
G01X1732335Y464777D02*
G03I-709J0D01*
G01X1725248Y465171D02*
G03I-709J0D01*
G01X1739421Y469502D02*
G03I-708J0D01*
G01Y465171D02*
G03I-708J0D01*
G01X1744884Y469403D02*
G03X1747272I1194J1012D01*
G01X1746508Y464777D02*
G03I-709J0D01*
G01X1753595Y431313D02*
G03I-709J0D01*
G01X1747614Y438557D02*
X1751630D01*
G01X1750212Y439679D02*
X1749031D01*
G01X1747850Y441725D02*
X1751393D01*
G01X1753913Y456273D02*
X1752417D01*
G01X1750803Y458869D02*
X1755527D01*
G01X1754543Y461391D02*
X1751787D01*
G01X1749031Y439679D02*
X1747643Y442083D01*
G01X1746826Y456273D02*
X1747614Y454909D01*
G01D02*
Y452439D01*
G01Y450659D02*
Y445352D01*
G01Y443572D02*
Y438557D01*
G01X1747643Y442083D02*
Y443617D01*
G01Y445308D02*
Y450704D01*
G01Y452394D02*
Y455830D01*
G01X1748441Y460407D02*
Y438557D01*
G01X1750803Y460407D02*
Y438557D01*
G01X1751600Y455830D02*
Y452394D01*
G01Y450704D02*
Y445308D01*
G01Y443617D02*
Y442083D01*
G01X1751630Y438557D02*
Y443572D01*
G01Y445352D02*
Y450659D01*
G01Y452439D02*
Y454909D01*
G01X1752417Y456273D02*
X1751630Y454909D01*
G01X1751600Y442083D02*
X1750212Y439679D01*
G01X1747614Y443572D02*
G03Y445352I-1299J890D01*
G01X1753595Y441155D02*
G03I-709J0D01*
G01Y436825D02*
G03I-709J0D01*
G01X1751630Y445352D02*
G03Y443572I1299J-890D01*
G01X1753595Y445486D02*
G03I-709J0D01*
G01X1747614Y450659D02*
G03Y452439I-1299J890D01*
G01X1748441Y460407D02*
G03X1747456Y461391I-984J0D01*
G01X1751630Y452439D02*
G03Y450659I1299J-890D01*
G01X1753595Y455329D02*
G03I-709J0D01*
G01Y450998D02*
G03I-709J0D01*
G01X1754730Y455830D02*
G03X1751600I-1565J0D01*
G01X1751787Y461391D02*
G03X1750803Y460407I0J-984D01*
G01X1753595Y459659D02*
G03I-709J0D01*
G01X1755134Y463124D02*
G03I-1969J0D01*
G01X1747614Y469009D02*
X1751630D01*
G01X1751971Y469403D02*
X1747272D01*
G01X1754700Y476883D02*
X1751630D01*
G01X1746433Y478065D02*
X1745724D01*
G01X1746433D02*
X1747614Y476883D01*
G01X1751971Y469403D02*
X1751755Y469683D01*
X1751630Y470000D01*
G01X1751600Y470661D02*
X1751646Y470202D01*
X1751772Y469777D01*
X1751971Y469403D01*
G01X1751600Y470242D02*
X1751608Y470118D01*
X1751630Y469995D01*
G01X1747614Y476883D02*
Y469009D01*
G01X1747643Y476490D02*
Y470242D01*
G01X1751600Y476490D02*
Y470242D01*
G01X1751630Y469009D02*
Y476883D01*
G01X1747643Y470242D02*
X1747636Y470119D01*
X1747614Y469995D01*
G01Y470000D02*
X1747487Y469680D01*
X1747272Y469403D01*
G01D02*
X1747471Y469778D01*
X1747598Y470202D01*
X1747643Y470661D01*
G01X1752811Y478065D02*
X1751630Y476883D01*
G01X1751971Y469403D02*
G03X1754359I1194J1012D01*
G01X1753595Y469502D02*
G03I-709J0D01*
G01Y465171D02*
G03I-709J0D01*
G01X1733595Y615171D02*
Y745092D01*
G01X1692564Y783450D02*
X1693795Y783869D01*
G01Y782194D02*
X1692564Y781775D01*
G01X1699126Y783450D02*
X1700356Y783869D01*
G01X1699946Y782194D02*
X1699126Y781775D01*
G01X1691744Y782613D02*
X1692564Y783450D01*
G01Y781775D02*
X1691744Y780937D01*
G01X1697896Y782194D02*
X1699126Y783450D01*
G01Y781775D02*
X1698716Y781356D01*
G01D02*
X1698306Y780518D01*
G01X1691744Y783869D02*
Y782613D01*
G01Y780937D02*
Y770466D01*
G01X1696255D02*
Y780518D01*
G01X1698306D02*
Y770466D01*
G01X1702817D02*
Y780518D01*
G01X1704867D02*
Y770466D01*
G01D02*
X1702817D01*
G01X1698306D02*
X1696255D01*
G01X1701176Y782194D02*
X1699946D01*
G01X1694615D02*
X1693795D01*
G01Y783869D02*
X1695435D01*
G01X1700356D02*
X1701997D01*
G01X1696255Y780518D02*
X1695845Y781356D01*
G01X1704047Y782613D02*
X1704867Y780518D01*
G01X1695435Y783869D02*
X1696665Y783450D01*
G01X1701997Y783869D02*
X1703227Y783450D01*
G01X1695435Y781775D02*
X1694615Y782194D01*
G01X1701997Y781775D02*
X1701176Y782194D01*
G01X1695845Y781356D02*
X1695435Y781775D01*
G01X1696665Y783450D02*
X1697896Y782194D01*
G01X1702407Y781356D02*
X1701997Y781775D01*
G01X1703227Y783450D02*
X1704047Y782613D01*
G01X1702817Y780518D02*
X1702407Y781356D01*
G01X1759185Y787651D02*
G03I-11811J0D01*
G01X1753280D02*
G03I-5906J0D01*
G01X1751311D02*
X1780675D01*
G01X1752036Y784026D02*
X1801838Y745306D01*
G01X1747374Y791588D02*
Y816703D01*
G01X1752608Y798239D02*
X1904406Y1105328D01*
G01X1708014Y884856D02*
Y908478D01*
G01D02*
X1963909D01*
G01X1691438Y917637D02*
G03X1708014Y937076I-3109J19438D01*
G01X1691438Y917637D02*
G03X1708014Y937076I-3109J19438D01*
G01Y979344D02*
Y937076D01*
G01Y979344D02*
Y937076D01*
G01X1715888Y987218D02*
G03X1708014Y979344I0J-7874D01*
G01X1715888Y987218D02*
G03X1708014Y979344I0J-7874D01*
G01X1766075Y947848D02*
G03I-18701J0D01*
G01X1754264D02*
G03I-6890J0D01*
G01X1748321Y954672D02*
X1758306Y1026588D01*
G01X1748852Y966491D02*
X1763770Y1154706D01*
G01X1708014Y983281D02*
Y1022258D01*
G01X1715888Y987218D02*
X2034776D01*
G01X1715888D02*
X2034776D01*
G01X1813971Y-380869D02*
G03I-11810J0D01*
G01X1808066D02*
G03I-5905J0D01*
G01X1808694Y49307D02*
X1809872Y49909D01*
G01X1806928Y51713D02*
X1805750Y50510D01*
G01X1808105Y48706D02*
X1808694Y49307D01*
G01X1816350Y51713D02*
X1814584Y49909D01*
G01X1807517Y47503D02*
X1808105Y48706D01*
G01X1805750Y50510D02*
X1804572Y47503D01*
G01D02*
Y33068D01*
G01X1807517D02*
Y47503D01*
G01X1813995D02*
Y33068D01*
G01X1804572D02*
X1807517D01*
G01X1813995D02*
X1816939D01*
G01X1809872Y49909D02*
X1811639D01*
G01X1813406Y48706D02*
X1813995Y47503D01*
G01X1811639Y49909D02*
X1812817Y49307D01*
G01D02*
X1813406Y48706D01*
G01X1814584Y49909D02*
X1812817Y51713D01*
G01X1757258Y104410D02*
X1762705D01*
G01D02*
X2048821D01*
G01X1808694Y52315D02*
X1806928Y51713D01*
G01X1811050Y52315D02*
X1808694D01*
G01X1812817Y51713D02*
X1811050Y52315D01*
G01X1764928Y376588D02*
X1765052Y376615D01*
X1765157Y376688D01*
G01X1765052Y376614D02*
X1764928Y376588D01*
G01X1771052Y378713D02*
X1770678Y378646D01*
G01X1756504D02*
X1756878Y378713D01*
G01X1764691Y376588D02*
X1806817D01*
G01X1764691Y376903D02*
X1764844D01*
G01X1765474D02*
X1779017D01*
G01X1766134Y377076D02*
X1764691D01*
G01X1758884D02*
X1764297D01*
G01X1773057D02*
X1777584D01*
G01X1752948Y378950D02*
X1756485D01*
G01X1767121D02*
X1770658D01*
G01X1756901Y380726D02*
X1757492D01*
G01X1766153D02*
X1766744D01*
G01X1771074D02*
X1771665D01*
G01X1777584Y384462D02*
X1773057D01*
G01X1766134D02*
X1764691D01*
G01X1764297D02*
X1758884D01*
G01X1767121Y378645D02*
X1766728Y378715D01*
G01X1764844Y376903D02*
X1765224Y376794D01*
G01X1766134Y376882D02*
X1766213Y376859D01*
G01X1766056Y380180D02*
X1766609Y379976D01*
G01X1758171Y376903D02*
X1758421Y376794D01*
G01X1772344Y376903D02*
X1772595Y376794D01*
G01X1758488Y376687D02*
X1758593Y376613D01*
X1758717Y376588D01*
G01X1772661Y376687D02*
X1772767Y376613D01*
X1772890Y376588D01*
G01X1767088Y378554D02*
X1767093Y378548D01*
X1767107Y378533D01*
X1767124Y378508D01*
X1767137Y378474D01*
X1767142Y378432D01*
X1767139Y378382D01*
X1767126Y378324D01*
X1767106Y378260D01*
X1767078Y378192D01*
X1767042Y378119D01*
X1766999Y378041D01*
X1766952Y377963D01*
X1766906Y377896D01*
X1766867Y377840D01*
X1766833Y377796D01*
X1766807Y377763D01*
X1766791Y377744D01*
X1766786Y377738D01*
G01X1756818Y377741D02*
X1756813Y377747D01*
X1756797Y377767D01*
X1756771Y377799D01*
X1756738Y377843D01*
X1756699Y377897D01*
X1756656Y377962D01*
X1756609Y378038D01*
X1756565Y378117D01*
X1756530Y378192D01*
X1756502Y378260D01*
X1756481Y378323D01*
X1756469Y378380D01*
X1756466Y378430D01*
X1756471Y378471D01*
X1756484Y378505D01*
X1756500Y378529D01*
X1756513Y378544D01*
X1756519Y378550D01*
G01X1770991Y377741D02*
X1770986Y377747D01*
X1770970Y377767D01*
X1770945Y377799D01*
X1770911Y377843D01*
X1770872Y377897D01*
X1770829Y377962D01*
X1770783Y378038D01*
X1770739Y378117D01*
X1770703Y378192D01*
X1770675Y378260D01*
X1770654Y378323D01*
X1770642Y378380D01*
X1770639Y378430D01*
X1770645Y378471D01*
X1770657Y378505D01*
X1770673Y378529D01*
X1770687Y378544D01*
X1770692Y378550D01*
G01X1758488Y376687D02*
X1758421Y376794D01*
G01X1772661Y376687D02*
X1772595Y376794D01*
G01X1756519Y378550D02*
X1756818Y377741D01*
G01X1757510Y377003D02*
X1756878Y378713D01*
G01X1758171Y376903D02*
X1757035Y379976D01*
G01X1758421Y376794D02*
X1757220Y380044D01*
G01X1757589Y380180D02*
X1758800Y376903D01*
G01X1770692Y378550D02*
X1770991Y377741D01*
G01X1771684Y377003D02*
X1771052Y378713D01*
G01X1772344Y376903D02*
X1771209Y379976D01*
G01X1771393Y380044D02*
X1772595Y376794D01*
G01X1771763Y380180D02*
X1772974Y376903D01*
G01X1752948Y378645D02*
Y408775D01*
G01X1753342D02*
Y376588D01*
G01X1756091D02*
Y408775D01*
G01X1756485D02*
Y378950D01*
G01X1756878Y408775D02*
Y378713D01*
G01X1756901Y408854D02*
Y380726D01*
G01X1757098Y408854D02*
Y380726D01*
G01X1757492D02*
Y408854D01*
G01X1758171Y376903D02*
Y376588D01*
G01X1758800Y376903D02*
Y376588D01*
G01X1758884Y384462D02*
Y376588D01*
G01X1764297D02*
Y415171D01*
G01X1764691D02*
Y376588D01*
G01X1764844Y376903D02*
Y376588D01*
G01X1765474Y376903D02*
Y376588D01*
G01X1766134Y376822D02*
Y384462D01*
G01X1766153Y408854D02*
Y380726D01*
G01X1766547Y408854D02*
Y380726D01*
G01X1766728Y378715D02*
Y408775D01*
G01X1766744Y380726D02*
Y408854D01*
G01X1767121Y408775D02*
Y378645D01*
G01X1767515Y408775D02*
Y376588D01*
G01X1770264Y408775D02*
Y376588D01*
G01X1770658Y408775D02*
Y378950D01*
G01X1771052Y408775D02*
Y378713D01*
G01X1771074Y408854D02*
Y380726D01*
G01X1771271D02*
Y408854D01*
G01X1771665Y380726D02*
Y408854D01*
G01X1772344Y376903D02*
Y376588D01*
G01X1772974D02*
Y376903D01*
G01X1773057Y384462D02*
Y376588D01*
G01X1764844Y376903D02*
X1766056Y380180D01*
G01X1766425Y380044D02*
X1765224Y376794D01*
G01X1766609Y379976D02*
X1765474Y376903D01*
G01X1766728Y378715D02*
X1766134Y377108D01*
G01X1767121Y378645D02*
X1766600Y377233D01*
G01D02*
X1766521Y377101D01*
X1766397Y376978D01*
X1766213Y376859D01*
G01X1765224Y376794D02*
X1765157Y376687D01*
G01X1766134Y377013D02*
X1765761Y376793D01*
X1765352Y376646D01*
X1764884Y376588D01*
G01X1766213Y376859D02*
X1766188Y376846D01*
X1766161Y376833D01*
X1766134Y376822D01*
G01X1765474Y376903D02*
X1765378Y376862D01*
X1765297Y376828D01*
X1765243Y376804D01*
X1765224Y376794D01*
G01X1757035Y379976D02*
X1757589Y380180D01*
G01X1771209Y379976D02*
X1771763Y380180D01*
G01X1758421Y376794D02*
X1758800Y376903D01*
G01X1772595Y376794D02*
X1772974Y376903D01*
G01X1758421Y376794D02*
G03X1758717Y376588I296J109D01*
G01X1756818Y377741D02*
G03X1758847Y376588I2029J1209D01*
G01X1756485Y378950D02*
G03X1756519Y378550I2362J-1D01*
G01X1752915Y378556D02*
G03X1752948Y378950I-2329J393D01*
G01X1756901Y380726D02*
G03X1757035Y379976I2166J0D01*
G01X1757098Y380726D02*
G03X1757220Y380044I1969J0D01*
G01X1757492Y380726D02*
G03X1757589Y380180I1575J-2D01*
G01X1764928Y376588D02*
G03X1765224Y376794I0J315D01*
G01X1772595D02*
G03X1772890Y376588I295J109D01*
G01X1770991Y377741D02*
G03X1773020Y376588I2029J1209D01*
G01X1770658Y378950D02*
G03X1770692Y378550I2362J-1D01*
G01X1767088Y378554D02*
G03X1767121Y378950I-2329J393D01*
G01X1766131Y377028D02*
G03X1766786Y377738I-1372J1923D01*
G01X1771074Y380726D02*
G03X1771209Y379976I2165J3D01*
G01X1766609D02*
G03X1766744Y380726I-2030J753D01*
G01X1766425Y380044D02*
G03X1766547Y380726I-1847J682D01*
G01X1771271D02*
G03X1771393Y380044I1969J0D01*
G01X1766056Y380180D02*
G03X1766153Y380726I-1478J544D01*
G01X1771665D02*
G03X1771763Y380180I1575J1D01*
G01X1764297Y403524D02*
X1763808D01*
G01X1764691D02*
X1764363D01*
G01X1756091Y408775D02*
X1756878D01*
G01X1766728D02*
X1767515D01*
G01X1770264D02*
X1771052D01*
G01X1766744Y408854D02*
X1766153D01*
G01X1756901D02*
X1757492D01*
G01X1771074D02*
X1771665D01*
G01X1770232Y408872D02*
X1767547D01*
G01X1756059D02*
X1753374D01*
G01X1752785Y409069D02*
X1756686D01*
G01X1766959D02*
X1770859D01*
G01Y409265D02*
X1766959D01*
G01X1756686D02*
X1752785D01*
G01X1770859Y409659D02*
X1766959D01*
G01X1756686D02*
X1752785D01*
G01X1806817Y411762D02*
X1764691D01*
G01X1806817Y411959D02*
X1764691D01*
G01X1806817Y414580D02*
X1764691D01*
G01X1806817Y415171D02*
X1764363D01*
G01X1753244Y409266D02*
X1753253Y409228D01*
X1753280Y409128D01*
X1753322Y408998D01*
X1753374Y408872D01*
G01X1767417Y409266D02*
X1767426Y409228D01*
X1767454Y409128D01*
X1767495Y408998D01*
X1767547Y408872D01*
G01X1753244Y409266D02*
X1753231Y409318D01*
X1753199Y409461D01*
X1753160Y409659D01*
G01X1767333D02*
X1767372Y409463D01*
X1767404Y409318D01*
X1767417Y409266D01*
G01X1752785Y409069D02*
Y409659D01*
G01X1756686Y409069D02*
Y409659D01*
G01X1763808Y403524D02*
Y479049D01*
G01X1764363D02*
Y403524D01*
G01X1766959Y409069D02*
Y409659D01*
G01X1770859Y409069D02*
Y409659D01*
G01X1770446D02*
X1770407Y409462D01*
X1770374Y409318D01*
X1770362Y409266D01*
G01X1756189D02*
X1756201Y409318D01*
X1756233Y409461D01*
X1756272Y409659D01*
G01X1756059Y408872D02*
X1756113Y409006D01*
X1756155Y409138D01*
X1756180Y409232D01*
X1756189Y409266D01*
G01X1770232Y408872D02*
X1770287Y409006D01*
X1770328Y409138D01*
X1770354Y409232D01*
X1770362Y409266D01*
G01X1756878Y408775D02*
G03X1756272Y409659I-948J0D01*
G01X1757492Y408854D02*
G03X1756686Y409659I-806J-1D01*
G01X1756485Y408775D02*
G03X1756189Y409266I-555J0D01*
G01X1753244D02*
G03X1752948Y408775I258J-490D01*
G01X1757098Y408854D02*
G03X1756686Y409265I-412J-1D01*
G01X1756901Y408854D02*
G03X1756686Y409069I-215J0D01*
G01X1753374Y408872D02*
G03X1753342Y408775I129J-96D01*
G01X1756091D02*
G03X1756059Y408872I-161J1D01*
G01X1760681Y422258D02*
G03I-709J0D01*
G01X1771052Y408775D02*
G03X1770446Y409659I-948J0D01*
G01X1767333D02*
G03X1766728Y408775I343J-884D01*
G01X1766959Y409659D02*
G03X1766153Y408854I-1J-805D01*
G01X1771665D02*
G03X1770859Y409659I-805J0D01*
G01X1767417Y409266D02*
G03X1767121Y408775I258J-491D01*
G01X1770658D02*
G03X1770362Y409266I-554J0D01*
G01X1766959Y409265D02*
G03X1766547Y408854I0J-412D01*
G01X1771271D02*
G03X1770859Y409265I-412J-1D01*
G01X1771074Y408854D02*
G03X1770859Y409069I-215J0D01*
G01X1766959D02*
G03X1766744Y408854I0J-215D01*
G01X1767547Y408872D02*
G03X1767515Y408775I129J-96D01*
G01X1770264D02*
G03X1770232Y408872I-161J1D01*
G01X1774854Y422258D02*
G03I-708J0D01*
G01X1793275Y376588D02*
X1793399Y376615D01*
X1793504Y376688D01*
G01X1779102Y376588D02*
X1779226Y376615D01*
X1779330Y376688D01*
G01X1793399Y376614D02*
X1793275Y376588D01*
G01X1779226Y376614D02*
X1779102Y376588D01*
G01X1799024Y378646D02*
X1799398Y378713D01*
G01X1784851Y378646D02*
X1785225Y378713D01*
G01X1779647Y376903D02*
X1793191D01*
G01X1793821D02*
X1806817D01*
G01X1794480Y377076D02*
X1792118D01*
G01X1780307D02*
X1777945D01*
G01X1787230D02*
X1791758D01*
G01X1801403D02*
X1806817D01*
G01X1781295Y378950D02*
X1784831D01*
G01X1795468D02*
X1799004D01*
G01X1795090Y380726D02*
X1794500D01*
G01X1780917D02*
X1780326D01*
G01X1785248D02*
X1785838D01*
G01X1799421D02*
X1800011D01*
G01X1806817Y384462D02*
X1801403D01*
G01X1791758D02*
X1787230D01*
G01X1777945D02*
X1780307D01*
G01X1792118D02*
X1794480D01*
G01X1781295Y378645D02*
X1780901Y378715D01*
G01X1795468Y378645D02*
X1795074Y378715D01*
G01X1779017Y376903D02*
X1779397Y376794D01*
G01X1780307Y376882D02*
X1780387Y376859D01*
G01X1793191Y376903D02*
X1793570Y376794D01*
G01X1794480Y376882D02*
X1794560Y376859D01*
G01X1780229Y380180D02*
X1780783Y379976D01*
G01X1794402Y380180D02*
X1794956Y379976D01*
G01X1786517Y376903D02*
X1786768Y376794D01*
G01X1800691Y376903D02*
X1800941Y376794D01*
G01X1786835Y376687D02*
X1786940Y376613D01*
X1787063Y376588D01*
G01X1801008Y376687D02*
X1801113Y376613D01*
X1801236Y376588D01*
G01X1781261Y378554D02*
X1781267Y378548D01*
X1781280Y378533D01*
X1781297Y378508D01*
X1781310Y378474D01*
X1781315Y378432D01*
X1781312Y378382D01*
X1781300Y378324D01*
X1781279Y378260D01*
X1781251Y378192D01*
X1781215Y378119D01*
X1781172Y378041D01*
X1781125Y377963D01*
X1781080Y377896D01*
X1781040Y377840D01*
X1781006Y377796D01*
X1780980Y377763D01*
X1780964Y377744D01*
X1780959Y377738D01*
G01X1795434Y378554D02*
X1795440Y378548D01*
X1795454Y378533D01*
X1795470Y378508D01*
X1795483Y378474D01*
X1795489Y378432D01*
X1795485Y378382D01*
X1795473Y378324D01*
X1795452Y378260D01*
X1795424Y378192D01*
X1795389Y378119D01*
X1795346Y378041D01*
X1795298Y377963D01*
X1795253Y377896D01*
X1795213Y377840D01*
X1795180Y377796D01*
X1795154Y377763D01*
X1795137Y377744D01*
X1795133Y377738D01*
G01X1785164Y377741D02*
X1785159Y377747D01*
X1785143Y377767D01*
X1785118Y377799D01*
X1785085Y377843D01*
X1785046Y377897D01*
X1785002Y377962D01*
X1784956Y378038D01*
X1784912Y378117D01*
X1784876Y378192D01*
X1784848Y378260D01*
X1784828Y378323D01*
X1784815Y378380D01*
X1784812Y378430D01*
X1784818Y378471D01*
X1784830Y378505D01*
X1784847Y378529D01*
X1784860Y378544D01*
X1784865Y378550D01*
G01X1799337Y377741D02*
X1799332Y377747D01*
X1799317Y377767D01*
X1799291Y377799D01*
X1799258Y377843D01*
X1799219Y377897D01*
X1799175Y377962D01*
X1799129Y378038D01*
X1799085Y378117D01*
X1799049Y378192D01*
X1799021Y378260D01*
X1799001Y378323D01*
X1798989Y378380D01*
X1798985Y378430D01*
X1798991Y378471D01*
X1799004Y378505D01*
X1799020Y378529D01*
X1799033Y378544D01*
X1799039Y378550D01*
G01X1786835Y376687D02*
X1786768Y376794D01*
G01X1801008Y376687D02*
X1800941Y376794D01*
G01X1784865Y378550D02*
X1785164Y377741D01*
G01X1785857Y377003D02*
X1785225Y378713D01*
G01X1786517Y376903D02*
X1785382Y379976D01*
G01X1786768Y376794D02*
X1785567Y380044D01*
G01X1785936Y380180D02*
X1787147Y376903D01*
G01X1799039Y378550D02*
X1799337Y377741D01*
G01X1800030Y377003D02*
X1799398Y378713D01*
G01X1800691Y376903D02*
X1799555Y379976D01*
G01X1800941Y376794D02*
X1799740Y380044D01*
G01X1800109Y380180D02*
X1801320Y376903D01*
G01X1777584Y384462D02*
Y376588D01*
G01X1777945Y384462D02*
Y376588D01*
G01X1779017Y376903D02*
Y376588D01*
G01X1779647Y376903D02*
Y376588D01*
G01X1780307Y376822D02*
Y384462D01*
G01X1780326Y408854D02*
Y380726D01*
G01X1780720Y408854D02*
Y380726D01*
G01X1780901Y378715D02*
Y408775D01*
G01X1780917Y380726D02*
Y408854D01*
G01X1781295Y378645D02*
Y408775D01*
G01X1781688D02*
Y376588D01*
G01X1784437D02*
Y408775D01*
G01X1784831D02*
Y378950D01*
G01X1785225Y408775D02*
Y378713D01*
G01X1785248Y408854D02*
Y380726D01*
G01X1785445Y408854D02*
Y380726D01*
G01X1785838D02*
Y408854D01*
G01X1786517Y376903D02*
Y376588D01*
G01X1787147Y376903D02*
Y376588D01*
G01X1787230Y384462D02*
Y376588D01*
G01X1791758Y384462D02*
Y376588D01*
G01X1792118Y384462D02*
Y376588D01*
G01X1793191Y376903D02*
Y376588D01*
G01X1793821Y376903D02*
Y376588D01*
G01X1794480Y376822D02*
Y384462D01*
G01X1794500Y408854D02*
Y380726D01*
G01X1794893Y408854D02*
Y380726D01*
G01X1795074Y378715D02*
Y408775D01*
G01X1795090Y380726D02*
Y408854D01*
G01X1795468Y378645D02*
Y408775D01*
G01X1795861D02*
Y376588D01*
G01X1798611D02*
Y408775D01*
G01X1799004D02*
Y378950D01*
G01X1799398Y408775D02*
Y378713D01*
G01X1799421Y408854D02*
Y380726D01*
G01X1799618Y408854D02*
Y380726D01*
G01X1800011D02*
Y408854D01*
G01X1800691Y376903D02*
Y376588D01*
G01X1801320Y376903D02*
Y376588D01*
G01X1801403Y384462D02*
Y376588D01*
G01X1779017Y376903D02*
X1780229Y380180D01*
G01X1780598Y380044D02*
X1779397Y376794D01*
G01X1780783Y379976D02*
X1779647Y376903D01*
G01X1780901Y378715D02*
X1780307Y377108D01*
G01X1780773Y377233D02*
X1781295Y378645D01*
G01X1793191Y376903D02*
X1794402Y380180D01*
G01X1794771Y380044D02*
X1793570Y376794D01*
G01X1794956Y379976D02*
X1793821Y376903D01*
G01X1795074Y378715D02*
X1794480Y377108D01*
G01X1794946Y377233D02*
X1795468Y378645D01*
G01X1780773Y377233D02*
X1780694Y377101D01*
X1780570Y376978D01*
X1780387Y376859D01*
G01X1794946Y377233D02*
X1794867Y377101D01*
X1794743Y376978D01*
X1794560Y376859D01*
G01X1779397Y376794D02*
X1779330Y376687D01*
G01X1793570Y376794D02*
X1793503Y376687D01*
G01X1780307Y377013D02*
X1779934Y376793D01*
X1779525Y376646D01*
X1779058Y376588D01*
G01X1794480Y377013D02*
X1794107Y376793D01*
X1793698Y376646D01*
X1793231Y376588D01*
G01X1780387Y376859D02*
X1780361Y376846D01*
X1780334Y376833D01*
X1780307Y376822D01*
G01X1794560Y376859D02*
X1794508Y376833D01*
X1794480Y376822D01*
G01X1779647Y376903D02*
X1779551Y376862D01*
X1779471Y376828D01*
X1779417Y376804D01*
X1779397Y376794D01*
G01X1793821Y376903D02*
X1793724Y376862D01*
X1793644Y376828D01*
X1793590Y376804D01*
X1793570Y376794D01*
G01X1785382Y379976D02*
X1785936Y380180D01*
G01X1799555Y379976D02*
X1800109Y380180D01*
G01X1786768Y376794D02*
X1787147Y376903D01*
G01X1800941Y376794D02*
X1801320Y376903D01*
G01X1779102Y376588D02*
G03X1779397Y376794I-1J315D01*
G01X1781261Y378556D02*
G03X1781295Y378950I-2328J399D01*
G01X1780304Y377028D02*
G03X1780959Y377738I-1372J1923D01*
G01X1780783Y379976D02*
G03X1780917Y380726I-2031J750D01*
G01X1780598Y380044D02*
G03X1780720Y380726I-1846J682D01*
G01X1780229Y380180D02*
G03X1780326Y380726I-1478J544D01*
G01X1786768Y376794D02*
G03X1787063Y376588I296J109D01*
G01X1793275D02*
G03X1793570Y376794I-1J315D01*
G01X1800941D02*
G03X1801236Y376588I296J109D01*
G01X1799337Y377741D02*
G03X1801367Y376588I2029J1209D01*
G01X1799004Y378950D02*
G03X1799039Y378550I2362J5D01*
G01X1795434Y378556D02*
G03X1795468Y378950I-2328J399D01*
G01X1794477Y377028D02*
G03X1795133Y377738I-1370J1924D01*
G01X1785164Y377741D02*
G03X1787193Y376588I2029J1209D01*
G01X1784831Y378950D02*
G03X1784865Y378550I2362J-1D01*
G01X1794956Y379976D02*
G03X1795090Y380726I-2031J750D01*
G01X1799421D02*
G03X1799555Y379976I2165J0D01*
G01X1785248Y380726D02*
G03X1785382Y379976I2165J0D01*
G01X1794771Y380044D02*
G03X1794893Y380726I-1846J682D01*
G01X1799618D02*
G03X1799740Y380044I1968J0D01*
G01X1785445Y380726D02*
G03X1785567Y380044I1968J0D01*
G01X1785838Y380726D02*
G03X1785936Y380180I1575J1D01*
G01X1794402D02*
G03X1794500Y380726I-1477J547D01*
G01X1800011D02*
G03X1800109Y380180I1575J1D01*
G01X1795861Y408775D02*
X1795074D01*
G01X1781688D02*
X1780901D01*
G01X1784437D02*
X1785225D01*
G01X1798611D02*
X1799398D01*
G01X1780326Y408854D02*
X1780917D01*
G01X1785248D02*
X1785838D01*
G01X1794500D02*
X1795090D01*
G01X1799421D02*
X1800011D01*
G01X1798578Y408872D02*
X1795894D01*
G01X1784405D02*
X1781721D01*
G01X1781132Y409069D02*
X1785033D01*
G01X1795305D02*
X1799206D01*
G01Y409265D02*
X1795305D01*
G01X1785033D02*
X1781132D01*
G01X1799206Y409659D02*
X1795305D01*
G01X1785033D02*
X1781132D01*
G01X1781590Y409266D02*
X1781600Y409228D01*
X1781627Y409128D01*
X1781668Y408998D01*
X1781721Y408872D01*
G01X1795763Y409266D02*
X1795773Y409228D01*
X1795800Y409128D01*
X1795841Y408998D01*
X1795894Y408872D01*
G01X1781590Y409266D02*
X1781578Y409318D01*
X1781546Y409461D01*
X1781506Y409659D01*
G01X1795763Y409266D02*
X1795751Y409318D01*
X1795719Y409461D01*
X1795680Y409659D01*
G01X1781132Y409069D02*
Y409659D01*
G01X1785033Y409069D02*
Y409659D01*
G01X1795305Y409069D02*
Y409659D01*
G01X1799206Y409069D02*
Y409659D01*
G01X1784535Y409266D02*
X1784548Y409318D01*
X1784580Y409461D01*
X1784619Y409659D01*
G01X1798708Y409266D02*
X1798721Y409318D01*
X1798753Y409461D01*
X1798792Y409659D01*
G01X1784405Y408872D02*
X1784460Y409006D01*
X1784501Y409138D01*
X1784527Y409232D01*
X1784535Y409266D01*
G01X1798578Y408872D02*
X1798633Y409006D01*
X1798674Y409138D01*
X1798700Y409232D01*
X1798708Y409266D01*
G01X1785225Y408775D02*
G03X1784619Y409659I-948J0D01*
G01X1781506D02*
G03X1780901Y408775I343J-884D01*
G01X1781132Y409659D02*
G03X1780326Y408854I0J-806D01*
G01X1784831Y408775D02*
G03X1784535Y409266I-554J1D01*
G01X1781590D02*
G03X1781295Y408775I259J-490D01*
G01X1781132Y409265D02*
G03X1780720Y408854I0J-412D01*
G01X1781132Y409069D02*
G03X1780917Y408854I0J-215D01*
G01X1781721Y408872D02*
G03X1781688Y408775I128J-98D01*
G01X1784437D02*
G03X1784405Y408872I-160J1D01*
G01X1799398Y408775D02*
G03X1798792Y409659I-948J0D01*
G01X1795680D02*
G03X1795074Y408775I342J-884D01*
G01X1785838Y408854D02*
G03X1785033Y409659I-805J0D01*
G01X1795305D02*
G03X1794500Y408854I0J-805D01*
G01X1800011D02*
G03X1799206Y409659I-805J0D01*
G01X1799004Y408775D02*
G03X1798708Y409266I-554J1D01*
G01X1795763D02*
G03X1795468Y408775I259J-490D01*
G01X1795305Y409265D02*
G03X1794893Y408854I0J-412D01*
G01X1799618D02*
G03X1799206Y409265I-412J-1D01*
G01X1785445Y408854D02*
G03X1785033Y409265I-412J-1D01*
G01X1799421Y408854D02*
G03X1799206Y409069I-215J0D01*
G01X1795305D02*
G03X1795090Y408854I0J-215D01*
G01X1785248D02*
G03X1785033Y409069I-215J0D01*
G01X1795894Y408872D02*
G03X1795861Y408775I128J-98D01*
G01X1798611D02*
G03X1798578Y408872I-161J-1D01*
G01X1803201Y422258D02*
G03I-709J0D01*
G01X1789028D02*
G03I-709J0D01*
G01X1806817Y376588D02*
Y415171D01*
G01Y403524D02*
X1806328D01*
G01D02*
Y479049D01*
G01X1760681Y432100D02*
G03I-709J0D01*
G01Y426588D02*
G03I-709J0D01*
G01X1767768Y431313D02*
G03I-709J0D01*
G01X1774854Y432100D02*
G03I-708J0D01*
G01Y426588D02*
G03I-708J0D01*
G01X1758716Y438557D02*
X1754700D01*
G01X1761787D02*
X1763808D01*
G01X1764363D02*
X1765803D01*
G01X1768874D02*
X1772889D01*
G01X1771472Y439679D02*
X1770291D01*
G01X1764385D02*
X1763204D01*
G01X1757299D02*
X1756118D01*
G01X1754937Y441725D02*
X1758480D01*
G01X1762023D02*
X1765567D01*
G01X1769110D02*
X1772653D01*
G01X1761000Y456273D02*
X1759504D01*
G01X1766590D02*
X1768086D01*
G01X1773677D02*
X1775173D01*
G01X1776787Y458869D02*
X1772063D01*
G01X1769700D02*
X1764976D01*
G01X1762614D02*
X1757889D01*
G01X1775803Y461391D02*
X1773047D01*
G01X1768716D02*
X1765960D01*
G01X1761630D02*
X1758874D01*
G01X1756118Y439679D02*
X1754730Y442083D01*
G01X1763204Y439679D02*
X1761817Y442083D01*
G01X1753913Y456273D02*
X1754700Y454909D01*
G01X1770291Y439679D02*
X1768903Y442083D01*
G01X1761000Y456273D02*
X1761787Y454909D01*
G01X1768086Y456273D02*
X1768874Y454909D01*
G01X1775173Y456273D02*
X1775960Y454909D01*
G01X1754700D02*
Y452439D01*
G01Y450659D02*
Y445352D01*
G01Y443572D02*
Y438557D01*
G01X1754730Y442083D02*
Y443617D01*
G01Y445308D02*
Y450704D01*
G01Y452394D02*
Y455830D01*
G01X1755527Y460407D02*
Y438557D01*
G01X1757889Y460407D02*
Y438557D01*
G01X1758687Y455830D02*
Y452394D01*
G01Y450704D02*
Y445308D01*
G01Y443617D02*
Y442083D01*
G01X1758716Y454909D02*
Y452439D01*
G01Y450659D02*
Y445352D01*
G01Y443572D02*
Y438557D01*
G01X1761787Y454909D02*
Y452439D01*
G01Y450659D02*
Y445352D01*
G01Y443572D02*
Y438557D01*
G01X1761817Y442083D02*
Y443617D01*
G01Y445308D02*
Y450704D01*
G01Y452394D02*
Y455830D01*
G01X1762614Y438557D02*
Y460407D01*
G01X1764976D02*
Y438557D01*
G01X1765773Y455830D02*
Y452394D01*
G01Y450704D02*
Y445308D01*
G01Y443617D02*
Y442083D01*
G01X1765803Y438557D02*
Y443572D01*
G01Y445352D02*
Y450659D01*
G01Y452439D02*
Y454909D01*
G01X1768874D02*
Y452439D01*
G01Y450659D02*
Y445352D01*
G01Y443572D02*
Y438557D01*
G01X1768903Y442083D02*
Y443617D01*
G01Y445308D02*
Y450704D01*
G01Y452394D02*
Y455830D01*
G01X1769700Y438557D02*
Y460407D01*
G01X1772063D02*
Y438557D01*
G01X1772860Y455830D02*
Y452394D01*
G01Y450704D02*
Y445308D01*
G01Y443617D02*
Y442083D01*
G01X1772889Y438557D02*
Y443572D01*
G01Y445352D02*
Y450659D01*
G01Y452439D02*
Y454909D01*
G01X1759504Y456273D02*
X1758716Y454909D01*
G01X1766590Y456273D02*
X1765803Y454909D01*
G01X1758687Y442083D02*
X1757299Y439679D01*
G01X1773677Y456273D02*
X1772889Y454909D01*
G01X1765773Y442083D02*
X1764385Y439679D01*
G01X1772860Y442083D02*
X1771472Y439679D01*
G01X1760681Y440762D02*
G03I-709J0D01*
G01Y436431D02*
G03I-709J0D01*
G01X1754700Y443572D02*
G03Y445352I-1299J890D01*
G01X1758716D02*
G03Y443572I1299J-890D01*
G01X1761787D02*
G03Y445352I-1299J890D01*
G01X1760681Y446273D02*
G03I-709J0D01*
G01X1754700Y450659D02*
G03Y452439I-1299J890D01*
G01X1761787Y450659D02*
G03Y452439I-1299J890D01*
G01X1758716D02*
G03Y450659I1299J-890D01*
G01X1760681Y454935D02*
G03I-709J0D01*
G01Y450604D02*
G03I-709J0D01*
G01X1761817Y455830D02*
G03X1758687I-1565J0D01*
G01X1758874Y461391D02*
G03X1757889Y460407I-1J-984D01*
G01X1755527D02*
G03X1754543Y461391I-984J0D01*
G01X1760681Y460447D02*
G03I-709J0D01*
G01X1762220Y463124D02*
G03I-1968J0D01*
G01X1774854Y440762D02*
G03I-708J0D01*
G01X1767768Y441155D02*
G03I-709J0D01*
G01X1774854Y436431D02*
G03I-708J0D01*
G01X1767768Y436825D02*
G03I-709J0D01*
G01X1772889Y445352D02*
G03Y443572I1299J-890D01*
G01X1768874D02*
G03Y445352I-1299J890D01*
G01X1765803D02*
G03Y443572I1299J-890D01*
G01X1774854Y446273D02*
G03I-708J0D01*
G01X1767768Y445486D02*
G03I-709J0D01*
G01X1768874Y450659D02*
G03Y452439I-1299J890D01*
G01X1765803D02*
G03Y450659I1299J-890D01*
G01X1767768Y455329D02*
G03I-709J0D01*
G01Y450998D02*
G03I-709J0D01*
G01X1768903Y455830D02*
G03X1765773I-1565J0D01*
G01X1762614Y460407D02*
G03X1761630Y461391I-984J0D01*
G01X1769700Y460407D02*
G03X1768716Y461391I-984J0D01*
G01X1765960D02*
G03X1764976Y460407I0J-984D01*
G01X1767768Y459659D02*
G03I-709J0D01*
G01X1772889Y452439D02*
G03Y450659I1299J-890D01*
G01X1774854Y454935D02*
G03I-708J0D01*
G01Y450604D02*
G03I-708J0D01*
G01X1775990Y455830D02*
G03X1772860I-1565J0D01*
G01X1773047Y461391D02*
G03X1772063Y460407I0J-984D01*
G01X1774854Y460447D02*
G03I-708J0D01*
G01X1769307Y463124D02*
G03I-1969J0D01*
G01X1776393D02*
G03I-1968J0D01*
G01X1754700Y469009D02*
X1758716D01*
G01X1761787D02*
X1763808D01*
G01X1764363D02*
X1765803D01*
G01X1768874D02*
X1772889D01*
G01X1773231Y469403D02*
X1768532D01*
G01X1766144D02*
X1761446D01*
G01X1759058D02*
X1754359D01*
G01X1764363Y475309D02*
X1806328D01*
G01X1775960Y476883D02*
X1772889D01*
G01X1768874D02*
X1765803D01*
G01X1761787D02*
X1758716D01*
G01X1774779Y478065D02*
X1774071D01*
G01X1767693D02*
X1766984D01*
G01X1760606D02*
X1759897D01*
G01X1753519D02*
X1752811D01*
G01X1764363Y479049D02*
X1806328D01*
G01X1753519Y478065D02*
X1754700Y476883D01*
G01X1760606Y478065D02*
X1761787Y476883D01*
G01X1767693Y478065D02*
X1768874Y476883D01*
G01X1774779Y478065D02*
X1775960Y476883D01*
G01X1759058Y469403D02*
X1758841Y469683D01*
X1758716Y470000D01*
G01X1766144Y469403D02*
X1765928Y469683D01*
X1765803Y470000D01*
G01X1773231Y469403D02*
X1773015Y469683D01*
X1772889Y470000D01*
G01X1758687Y470661D02*
X1758732Y470202D01*
X1758859Y469777D01*
X1759058Y469403D01*
G01X1765773Y470661D02*
X1765819Y470202D01*
X1765946Y469777D01*
X1766144Y469403D01*
G01X1772860Y470661D02*
X1772906Y470202D01*
X1773032Y469777D01*
X1773231Y469403D01*
G01X1758687Y470242D02*
X1758694Y470118D01*
X1758716Y469995D01*
G01X1765773Y470242D02*
X1765781Y470118D01*
X1765803Y469995D01*
G01X1772860Y470242D02*
X1772867Y470118D01*
X1772889Y469995D01*
G01X1754700Y476883D02*
Y469009D01*
G01X1754730Y476490D02*
Y470242D01*
G01X1758687Y476490D02*
Y470242D01*
G01X1758716Y469009D02*
Y476883D01*
G01X1761787D02*
Y469009D01*
G01X1761817Y476490D02*
Y470242D01*
G01X1765773Y476490D02*
Y470242D01*
G01X1765803Y469009D02*
Y476883D01*
G01X1768874D02*
Y469009D01*
G01X1768903Y476490D02*
Y470242D01*
G01X1754730D02*
X1754722Y470119D01*
X1754700Y469995D01*
G01X1772860Y476490D02*
Y470242D01*
G01X1772889Y469009D02*
Y476883D01*
G01X1761817Y470242D02*
X1761809Y470119D01*
X1761787Y469995D01*
G01X1768903Y470242D02*
X1768896Y470119D01*
X1768874Y469995D01*
G01X1754700Y470000D02*
X1754573Y469680D01*
X1754359Y469403D01*
G01X1761787Y470000D02*
X1761660Y469680D01*
X1761446Y469403D01*
G01X1768874Y470000D02*
X1768747Y469680D01*
X1768532Y469403D01*
G01X1754359D02*
X1754558Y469778D01*
X1754684Y470202D01*
X1754730Y470661D01*
G01X1761446Y469403D02*
X1761644Y469778D01*
X1761771Y470202D01*
X1761817Y470661D01*
G01X1768532Y469403D02*
X1768731Y469778D01*
X1768858Y470202D01*
X1768903Y470661D01*
G01X1759897Y478065D02*
X1758716Y476883D01*
G01X1766984Y478065D02*
X1765803Y476883D01*
G01X1774071Y478065D02*
X1772889Y476883D01*
G01X1759058Y469403D02*
G03X1761446I1194J1012D01*
G01X1760681Y464777D02*
G03I-709J0D01*
G01X1766144Y469403D02*
G03X1768532I1194J1012D01*
G01X1773231D02*
G03X1775619I1194J1012D01*
G01X1767768Y469502D02*
G03I-709J0D01*
G01X1774854Y464777D02*
G03I-708J0D01*
G01X1767768Y465171D02*
G03I-709J0D01*
G01X1781941Y431313D02*
G03I-709J0D01*
G01X1789028Y432100D02*
G03I-709J0D01*
G01Y426588D02*
G03I-709J0D01*
G01X1803201Y432100D02*
G03I-709J0D01*
G01X1796114Y431313D02*
G03I-709J0D01*
G01X1803201Y426588D02*
G03I-709J0D01*
G01X1801236Y438557D02*
X1797220D01*
G01X1775960D02*
X1779976D01*
G01X1783047D02*
X1787063D01*
G01X1790134D02*
X1794149D01*
G01X1804307D02*
X1806328D01*
G01X1799819Y439679D02*
X1798637D01*
G01X1792732D02*
X1791551D01*
G01X1785645D02*
X1784464D01*
G01X1778559D02*
X1777378D01*
G01X1776197Y441725D02*
X1779740D01*
G01X1783283D02*
X1786826D01*
G01X1790370D02*
X1793913D01*
G01X1797456D02*
X1801000D01*
G01X1803519Y456273D02*
X1802023D01*
G01X1796433D02*
X1794937D01*
G01X1789346D02*
X1787850D01*
G01X1782259D02*
X1780763D01*
G01X1804750Y457395D02*
X1802771D01*
G01X1805134Y458869D02*
X1800409D01*
G01X1779149D02*
X1783874D01*
G01X1786236D02*
X1790960D01*
G01X1793322D02*
X1798047D01*
G01X1804149Y461391D02*
X1801393D01*
G01X1797063D02*
X1794307D01*
G01X1789976D02*
X1787220D01*
G01X1782889D02*
X1780134D01*
G01X1777378Y439679D02*
X1775990Y442083D01*
G01X1784464Y439679D02*
X1783076Y442083D01*
G01X1791551Y439679D02*
X1790163Y442083D01*
G01X1782259Y456273D02*
X1783047Y454909D01*
G01X1798637Y439679D02*
X1797250Y442083D01*
G01X1789346Y456273D02*
X1790134Y454909D01*
G01X1796433Y456273D02*
X1797220Y454909D01*
G01X1803519Y456273D02*
X1804307Y454909D01*
G01X1775960D02*
Y452439D01*
G01Y450659D02*
Y445352D01*
G01Y443572D02*
Y438557D01*
G01X1775990Y442083D02*
Y443617D01*
G01Y445308D02*
Y450704D01*
G01Y452394D02*
Y455830D01*
G01X1776787Y438557D02*
Y460407D01*
G01X1779149D02*
Y438557D01*
G01X1779947Y455830D02*
Y452394D01*
G01Y450704D02*
Y445308D01*
G01Y443617D02*
Y442083D01*
G01X1779976Y438557D02*
Y443572D01*
G01Y445352D02*
Y450659D01*
G01Y452439D02*
Y454909D01*
G01X1783047D02*
Y452439D01*
G01Y450659D02*
Y445352D01*
G01Y443572D02*
Y438557D01*
G01X1783076Y442083D02*
Y443617D01*
G01Y445308D02*
Y450704D01*
G01Y452394D02*
Y455830D01*
G01X1783874Y460407D02*
Y438557D01*
G01X1786236Y460407D02*
Y438557D01*
G01X1787033Y455830D02*
Y452394D01*
G01Y450704D02*
Y445308D01*
G01Y443617D02*
Y442083D01*
G01X1787063Y438557D02*
Y443572D01*
G01Y445352D02*
Y450659D01*
G01Y452439D02*
Y454909D01*
G01X1790134D02*
Y452439D01*
G01Y450659D02*
Y445352D01*
G01Y443572D02*
Y438557D01*
G01X1790163Y442083D02*
Y443617D01*
G01Y445308D02*
Y450704D01*
G01Y452394D02*
Y455830D01*
G01X1790960Y460407D02*
Y438557D01*
G01X1793322Y460407D02*
Y438557D01*
G01X1794120Y455830D02*
Y452394D01*
G01Y450704D02*
Y445308D01*
G01Y443617D02*
Y442083D01*
G01X1794149Y438557D02*
Y443572D01*
G01Y445352D02*
Y450659D01*
G01Y452439D02*
Y454909D01*
G01X1797220D02*
Y452439D01*
G01Y450659D02*
Y445352D01*
G01Y443572D02*
Y438557D01*
G01X1797250Y442083D02*
Y443617D01*
G01Y445308D02*
Y450704D01*
G01Y452394D02*
Y455830D01*
G01X1798047Y460407D02*
Y438557D01*
G01X1800409Y460407D02*
Y438557D01*
G01X1801206Y455830D02*
Y452394D01*
G01Y450704D02*
Y445308D01*
G01Y443617D02*
Y442083D01*
G01X1801236Y454909D02*
Y452439D01*
G01Y450659D02*
Y445352D01*
G01Y443572D02*
Y438557D01*
G01X1804307Y454909D02*
Y452439D01*
G01Y450659D02*
Y445352D01*
G01Y443572D02*
Y438557D01*
G01X1805134D02*
Y460407D01*
G01X1780763Y456273D02*
X1779976Y454909D01*
G01X1787850Y456273D02*
X1787063Y454909D01*
G01X1779947Y442083D02*
X1778559Y439679D01*
G01X1794937Y456273D02*
X1794149Y454909D01*
G01X1787033Y442083D02*
X1785645Y439679D01*
G01X1802023Y456273D02*
X1801236Y454909D01*
G01X1794120Y442083D02*
X1792732Y439679D01*
G01X1801206Y442083D02*
X1799819Y439679D01*
G01X1781941Y441155D02*
G03I-709J0D01*
G01Y436825D02*
G03I-709J0D01*
G01X1779976Y445352D02*
G03Y443572I1299J-890D01*
G01X1783047D02*
G03Y445352I-1299J890D01*
G01X1775960Y443572D02*
G03Y445352I-1299J890D01*
G01X1781941Y445486D02*
G03I-709J0D01*
G01X1789028Y440762D02*
G03I-709J0D01*
G01Y436431D02*
G03I-709J0D01*
G01X1796114Y441155D02*
G03I-709J0D01*
G01Y436825D02*
G03I-709J0D01*
G01X1787063Y445352D02*
G03Y443572I1299J-890D01*
G01X1790134D02*
G03Y445352I-1300J890D01*
G01X1794149D02*
G03Y443572I1299J-890D01*
G01X1789028Y446273D02*
G03I-709J0D01*
G01X1796114Y445486D02*
G03I-709J0D01*
G01X1803201Y440762D02*
G03I-709J0D01*
G01Y436431D02*
G03I-709J0D01*
G01X1797220Y443572D02*
G03Y445352I-1299J890D01*
G01X1804307Y443572D02*
G03Y445352I-1299J890D01*
G01X1801236D02*
G03Y443572I1299J-890D01*
G01X1803201Y446273D02*
G03I-709J0D01*
G01X1779976Y452439D02*
G03Y450659I1299J-890D01*
G01X1783047D02*
G03Y452439I-1299J890D01*
G01X1775960Y450659D02*
G03Y452439I-1299J890D01*
G01X1781941Y455329D02*
G03I-709J0D01*
G01Y450998D02*
G03I-709J0D01*
G01X1783076Y455830D02*
G03X1779947I-1564J0D01*
G01X1783874Y460407D02*
G03X1782889Y461391I-984J0D01*
G01X1780134D02*
G03X1779149Y460407I-1J-984D01*
G01X1776787D02*
G03X1775803Y461391I-984J0D01*
G01X1781941Y459659D02*
G03I-709J0D01*
G01X1783480Y463124D02*
G03I-1969J0D01*
G01X1787063Y452439D02*
G03Y450659I1299J-890D01*
G01X1790134D02*
G03Y452439I-1300J890D01*
G01X1794149D02*
G03Y450659I1299J-890D01*
G01X1797220D02*
G03Y452439I-1299J890D01*
G01X1789028Y454935D02*
G03I-709J0D01*
G01Y450604D02*
G03I-709J0D01*
G01X1796114Y455329D02*
G03I-709J0D01*
G01Y450998D02*
G03I-709J0D01*
G01X1797250Y455830D02*
G03X1794120I-1565J0D01*
G01X1790163D02*
G03X1787033I-1565J0D01*
G01X1794307Y461391D02*
G03X1793322Y460407I-1J-984D01*
G01X1790960D02*
G03X1789976Y461391I-984J0D01*
G01X1787220D02*
G03X1786236Y460407I0J-984D01*
G01X1789028Y460447D02*
G03I-709J0D01*
G01X1796114Y459659D02*
G03I-709J0D01*
G01X1804307Y450659D02*
G03Y452439I-1299J890D01*
G01X1801236D02*
G03Y450659I1299J-890D01*
G01X1803201Y454935D02*
G03I-709J0D01*
G01Y450604D02*
G03I-709J0D01*
G01X1804750Y457395D02*
G03X1806315Y458960I0J1565D01*
G01X1802771Y457395D02*
G03X1801206Y455830I0J-1565D01*
G01X1805134Y460407D02*
G03X1804149Y461391I-984J0D01*
G01X1801393D02*
G03X1800409Y460407I0J-984D01*
G01X1798047D02*
G03X1797063Y461391I-984J0D01*
G01X1803201Y460447D02*
G03I-709J0D01*
G01X1790567Y463124D02*
G03I-1969J0D01*
G01X1797653D02*
G03I-1968J0D01*
G01X1804740D02*
G03I-1969J0D01*
G01X1775960Y469009D02*
X1779976D01*
G01X1783047D02*
X1787063D01*
G01X1790134D02*
X1794149D01*
G01X1797220D02*
X1801236D01*
G01X1804307D02*
X1806328D01*
G01X1806315Y469403D02*
X1803965D01*
G01X1801577D02*
X1796879D01*
G01X1794491D02*
X1789792D01*
G01X1787404D02*
X1782706D01*
G01X1780317D02*
X1775619D01*
G01X1804307Y476883D02*
X1801236D01*
G01X1797220D02*
X1794149D01*
G01X1790134D02*
X1787063D01*
G01X1783047D02*
X1779976D01*
G01X1803126Y478065D02*
X1802417D01*
G01X1796039D02*
X1795330D01*
G01X1788952D02*
X1788244D01*
G01X1781866D02*
X1781157D01*
G01X1781866D02*
X1783047Y476883D01*
G01X1788952Y478065D02*
X1790134Y476883D01*
G01X1796039Y478065D02*
X1797220Y476883D01*
G01X1803126Y478065D02*
X1804307Y476883D01*
G01X1780317Y469403D02*
X1780101Y469683D01*
X1779976Y470000D01*
G01X1787404Y469403D02*
X1787188Y469683D01*
X1787063Y470000D01*
G01X1794491Y469403D02*
X1794274Y469683D01*
X1794149Y470000D01*
G01X1801577Y469403D02*
X1801361Y469683D01*
X1801236Y470000D01*
G01X1779947Y470661D02*
X1779992Y470202D01*
X1780119Y469777D01*
X1780317Y469403D01*
G01X1787033Y470661D02*
X1787079Y470202D01*
X1787206Y469777D01*
X1787404Y469403D01*
G01X1779947Y470242D02*
X1779954Y470118D01*
X1779976Y469995D01*
G01X1794120Y470661D02*
X1794165Y470202D01*
X1794292Y469777D01*
X1794491Y469403D01*
G01X1801206Y470661D02*
X1801252Y470202D01*
X1801379Y469777D01*
X1801577Y469403D01*
G01X1787033Y470242D02*
X1787041Y470118D01*
X1787063Y469995D01*
G01X1794120Y470242D02*
X1794127Y470118D01*
X1794149Y469995D01*
G01X1801206Y470242D02*
X1801214Y470118D01*
X1801236Y469995D01*
G01X1775960Y476883D02*
Y469009D01*
G01X1775990Y476490D02*
Y470242D01*
G01X1779947Y476490D02*
Y470242D01*
G01X1779976Y469009D02*
Y476883D01*
G01X1783047D02*
Y469009D01*
G01X1783076Y476490D02*
Y470242D01*
G01X1787033Y476490D02*
Y470242D01*
G01X1787063Y469009D02*
Y476883D01*
G01X1790134D02*
Y469009D01*
G01X1790163Y476490D02*
Y470242D01*
G01X1794120Y476490D02*
Y470242D01*
G01X1794149Y469009D02*
Y476883D01*
G01X1797220D02*
Y469009D01*
G01X1797250Y476490D02*
Y470242D01*
G01X1801206Y476490D02*
Y470242D01*
G01X1801236Y469009D02*
Y476883D01*
G01X1804307D02*
Y469009D01*
G01X1804336Y476490D02*
Y470242D01*
G01X1775990D02*
X1775982Y470119D01*
X1775960Y469995D01*
G01X1783076Y470242D02*
X1783069Y470119D01*
X1783047Y469995D01*
G01X1790163Y470242D02*
X1790156Y470119D01*
X1790134Y469995D01*
G01X1797250Y470242D02*
X1797242Y470119D01*
X1797220Y469995D01*
G01X1804336Y470242D02*
X1804329Y470119D01*
X1804307Y469995D01*
G01X1775960Y470000D02*
X1775833Y469680D01*
X1775619Y469403D01*
G01X1783047Y470000D02*
X1782920Y469680D01*
X1782706Y469403D01*
G01X1790134Y470000D02*
X1790006Y469680D01*
X1789792Y469403D01*
G01X1797220Y470000D02*
X1797093Y469680D01*
X1796879Y469403D01*
G01X1804307Y470000D02*
X1804180Y469680D01*
X1803965Y469403D01*
G01X1775619D02*
X1775817Y469778D01*
X1775944Y470202D01*
X1775990Y470661D01*
G01X1782706Y469403D02*
X1782904Y469778D01*
X1783031Y470202D01*
X1783076Y470661D01*
G01X1789792Y469403D02*
X1789991Y469778D01*
X1790117Y470202D01*
X1790163Y470661D01*
G01X1796879Y469403D02*
X1797077Y469778D01*
X1797204Y470202D01*
X1797250Y470661D01*
G01X1803965Y469403D02*
X1804164Y469778D01*
X1804291Y470202D01*
X1804336Y470661D01*
G01X1781157Y478065D02*
X1779976Y476883D01*
G01X1788244Y478065D02*
X1787063Y476883D01*
G01X1795330Y478065D02*
X1794149Y476883D01*
G01X1802417Y478065D02*
X1801236Y476883D01*
G01X1780317Y469403D02*
G03X1782706I1195J1012D01*
G01X1781941Y469502D02*
G03I-709J0D01*
G01Y465171D02*
G03I-709J0D01*
G01X1787404Y469403D02*
G03X1789792I1194J1012D01*
G01X1794491D02*
G03X1796879I1194J1012D01*
G01X1801577D02*
G03X1803965I1194J1012D01*
G01X1803201Y464777D02*
G03I-709J0D01*
G01X1789028D02*
G03I-709J0D01*
G01X1796114Y469502D02*
G03I-709J0D01*
G01Y465171D02*
G03I-709J0D01*
G01X1806321Y458960D02*
X1806328Y438557D01*
G01X1806315Y458960D02*
Y476490D01*
G01X1808398Y532494D02*
X1761343D01*
G01X2015091Y491155D02*
X1794618D01*
G01D02*
Y695880D01*
G01X1824146Y532494D02*
G03I-11811J0D01*
G01X1812335Y536431D02*
Y564004D01*
G01X1818240Y532494D02*
G03I-5905J0D01*
G01X1770996Y811293D02*
Y548970D01*
G01X1794618Y695880D02*
X2015091D01*
G01X1801838Y745306D02*
X1804988D01*
G01D02*
X1927402D01*
G01X1758306Y1026588D02*
X1761455D01*
G01D02*
X1860484D01*
G01X1763770Y1154706D02*
X1766919D01*
G01D02*
X2053035D01*
G01X1833581Y-879845D02*
Y-898782D01*
G01X1818117Y49307D02*
X1819295Y49909D01*
G01X1817528Y48706D02*
X1818117Y49307D01*
G01X1816939Y47503D02*
X1817528Y48706D01*
G01X1816939Y33068D02*
Y47503D01*
G01X1823417Y52315D02*
Y50510D01*
G01Y48104D02*
Y33068D01*
G01D02*
X1826362D01*
G01X1819295Y49909D02*
X1820473D01*
G01D02*
X1822239Y49307D01*
G01D02*
X1823417Y48104D01*
G01Y50510D02*
X1822239Y51713D01*
G01X1835195Y49307D02*
X1836373Y49909D01*
G01X1844618Y49307D02*
X1845796Y49909D01*
G01X1833429Y51713D02*
X1832251Y50510D01*
G01X1834606Y48706D02*
X1835195Y49307D01*
G01X1842851Y51713D02*
X1841084Y49909D01*
G01X1844029Y48706D02*
X1844618Y49307D01*
G01X1832251Y50510D02*
X1831073Y47503D01*
G01X1834017D02*
X1834606Y48706D01*
G01X1843440Y47503D02*
X1844029Y48706D01*
G01X1826362Y33068D02*
Y52315D01*
G01X1831073Y47503D02*
Y33068D01*
G01X1834017D02*
Y47503D01*
G01X1840495D02*
Y33068D01*
G01X1843440D02*
Y47503D01*
G01X1849918Y52315D02*
Y50510D01*
G01Y48104D02*
Y33068D01*
G01X1852863D02*
Y52315D01*
G01X1831073Y33068D02*
X1834017D01*
G01X1840495D02*
X1843440D01*
G01X1849918D02*
X1852863D01*
G01X1836373Y49909D02*
X1838140D01*
G01X1845796D02*
X1846973D01*
G01D02*
X1848740Y49307D01*
G01X1838140Y49909D02*
X1839318Y49307D01*
G01X1839906Y48706D02*
X1840495Y47503D01*
G01X1839318Y49307D02*
X1839906Y48706D01*
G01X1841084Y49909D02*
X1839318Y51713D01*
G01X1848740Y49307D02*
X1849918Y48104D01*
G01Y50510D02*
X1848740Y51713D01*
G01X1872886Y37880D02*
X1871119Y36677D01*
G01X1874653Y35474D02*
X1871708Y33670D01*
G01X1876419Y37278D02*
X1874653Y35474D01*
G01X1875241Y41489D02*
X1872886Y37880D01*
G01X1877597Y39684D02*
X1876419Y37278D01*
G01X1860519Y49307D02*
X1861107Y52916D01*
G01X1857574Y49909D02*
X1858163Y52916D01*
G01X1871119Y36677D02*
X1868174Y36076D01*
G01X1871708Y33670D02*
X1868174Y33068D01*
G01X1857574Y44496D02*
Y49909D01*
G01X1875830Y45097D02*
X1875241Y41489D01*
G01X1860519Y45097D02*
Y49307D01*
G01X1875830D02*
Y45097D01*
G01X1868174Y33068D02*
X1864641Y33670D01*
G01X1868174Y36076D02*
X1865230Y36677D01*
G01X1858752Y39684D02*
X1858163Y41489D01*
G01D02*
X1857574Y44496D01*
G01X1861107Y41489D02*
X1860519Y45097D01*
G01X1875241Y52916D02*
X1875830Y49307D01*
G01X1864641Y33670D02*
X1861696Y35474D01*
G01X1859930Y37278D02*
X1858752Y39684D01*
G01X1865230Y36677D02*
X1863463Y37880D01*
G01X1861696Y35474D02*
X1859930Y37278D01*
G01X1863463Y37880D02*
X1861107Y41489D01*
G01X1818117Y52315D02*
X1816350Y51713D01*
G01X1826362Y52315D02*
X1823417D01*
G01X1820473D02*
X1818117D01*
G01X1822239Y51713D02*
X1820473Y52315D01*
G01X1835195D02*
X1833429Y51713D01*
G01X1844618Y52315D02*
X1842851Y51713D01*
G01X1852863Y52315D02*
X1849918D01*
G01X1846973D02*
X1844618D01*
G01X1837551D02*
X1835195D01*
G01X1839318Y51713D02*
X1837551Y52315D01*
G01X1848740Y51713D02*
X1846973Y52315D01*
G01X1861696Y58930D02*
X1864641Y60735D01*
G01X1863463Y56524D02*
X1865230Y57728D01*
G01X1859930Y57126D02*
X1861696Y58930D01*
G01X1861107Y52916D02*
X1863463Y56524D01*
G01X1858752Y54720D02*
X1859930Y57126D01*
G01X1858163Y52916D02*
X1858752Y54720D01*
G01X1865230Y57728D02*
X1868174Y58329D01*
G01D02*
X1871119Y57728D01*
G01X1871708Y60735D02*
X1874653Y58930D01*
G01X1871119Y57728D02*
X1872886Y56524D01*
G01X1874653Y58930D02*
X1876419Y57126D01*
G01X1872886Y56524D02*
X1875241Y52916D01*
G01X1876419Y57126D02*
X1877597Y54720D01*
G01X1864641Y60735D02*
X1868174Y61336D01*
G01D02*
X1871708Y60735D01*
G01X1954067Y524620D02*
X1855642D01*
G01Y623045D02*
Y524620D01*
G01X1858042Y622330D02*
X1856383D01*
G01X1954067Y623045D02*
X1855642D01*
G01X1856383Y620671D02*
X1858042Y622330D01*
G01X1856383D02*
Y620671D01*
G01X1833581Y1297911D02*
Y1278974D01*
G01X1922663Y-780211D02*
Y-584690D01*
G01X1878186Y41489D02*
X1877597Y39684D01*
G01X1878775Y44496D02*
X1878186Y41489D01*
G01X1878775Y49909D02*
Y44496D01*
G01X1883486Y52315D02*
Y49909D01*
G01Y45097D02*
Y42691D01*
G01D02*
X1892908D01*
G01Y45097D02*
X1883486D01*
G01Y49909D02*
X1892908D01*
G01X1878186Y52916D02*
X1878775Y49909D01*
G01X1897620Y33068D02*
X1901153D01*
G01Y46300D02*
X1917643D01*
G01Y49909D02*
X1901153D01*
G01X1892908Y42691D02*
Y45097D01*
G01Y49909D02*
Y52315D01*
G01X1897620Y61336D02*
Y33068D01*
G01X1901153D02*
Y46300D01*
G01Y49909D02*
Y61336D01*
G01X1917643Y33068D02*
X1921176D01*
G01X1917643Y61336D02*
Y49909D01*
G01Y46300D02*
Y33068D01*
G01X1921176D02*
Y61336D01*
G01X1892908Y52315D02*
X1883486D01*
G01X1877597Y54720D02*
X1878186Y52916D01*
G01X1901153Y61336D02*
X1897620D01*
G01X1921176D02*
X1917643D01*
G01X1922409Y376588D02*
X1922533Y376614D01*
X1922637Y376687D01*
X1922704Y376794D01*
G01X1922171Y376588D02*
X1978470D01*
G01X1922171Y376903D02*
X1922324D01*
G01X1922954D02*
X1936498D01*
G01X1923614Y377076D02*
X1922171D01*
G01X1924602Y378950D02*
X1928138D01*
G01X1923634Y380726D02*
X1924224D01*
G01X1923614Y384462D02*
X1922171D01*
G01X1924602Y378645D02*
X1924208Y378715D01*
G01X1923614Y376882D02*
X1923694Y376859D01*
G01X1922324Y376903D02*
X1922704Y376794D01*
G01X1923536Y380180D02*
X1924090Y379976D01*
G01X1922171Y415171D02*
Y376588D01*
G01X1922324Y376903D02*
Y376588D01*
G01X1922954Y376903D02*
Y376588D01*
G01X1923614Y376822D02*
Y384462D01*
G01X1923634Y408854D02*
Y380726D01*
G01X1924027Y408854D02*
Y380726D01*
G01X1924208Y378715D02*
Y408775D01*
G01X1924224Y380726D02*
Y408854D01*
G01X1924602Y408775D02*
Y378645D01*
G01X1924995Y408775D02*
Y376588D01*
G01X1922324Y376903D02*
X1923536Y380180D01*
G01X1923905Y380044D02*
X1922704Y376794D01*
G01X1924090Y379976D02*
X1922954Y376903D01*
G01X1924208Y378715D02*
X1923614Y377108D01*
G01X1924602Y378645D02*
X1924080Y377233D01*
G01X1922686Y376799D02*
X1922626Y376693D01*
X1922528Y376617D01*
X1922404Y376588D01*
G01X1924080Y377233D02*
X1924002Y377102D01*
X1923878Y376979D01*
X1923694Y376859D01*
G01X1923614Y377013D02*
X1923242Y376794D01*
X1922832Y376646D01*
X1922365Y376588D01*
G01X1923694Y376859D02*
X1923668Y376846D01*
X1923641Y376833D01*
X1923614Y376822D01*
G01X1922954Y376903D02*
X1922856Y376861D01*
X1922775Y376827D01*
X1922722Y376803D01*
X1922704Y376794D01*
G01X1924267Y377738D02*
X1924269Y377741D01*
X1924280Y377754D01*
X1924297Y377775D01*
X1924321Y377806D01*
X1924351Y377845D01*
X1924385Y377893D01*
X1924423Y377950D01*
X1924465Y378016D01*
X1924506Y378089D01*
X1924543Y378159D01*
X1924572Y378224D01*
X1924594Y378283D01*
X1924610Y378338D01*
X1924620Y378387D01*
X1924623Y378430D01*
X1924619Y378465D01*
X1924610Y378495D01*
X1924597Y378519D01*
X1924584Y378538D01*
X1924572Y378549D01*
X1924568Y378554D01*
G01X1922409Y376588D02*
G03X1922704Y376794I-1J315D01*
G01X1924568Y378554D02*
G03X1924602Y378950I-2328J399D01*
G01X1923611Y377028D02*
G03X1924267Y377738I-1370J1924D01*
G01X1924090Y379976D02*
G03X1924224Y380726I-2031J750D01*
G01X1923905Y380044D02*
G03X1924027Y380726I-1846J682D01*
G01X1923536Y380180D02*
G03X1923634Y380726I-1477J547D01*
G01X1922171Y403524D02*
X1921843D01*
G01X1924208Y408775D02*
X1924995D01*
G01X1924224Y408854D02*
X1923634D01*
G01X1927712Y408872D02*
X1925028D01*
G01X1924439Y409069D02*
X1928340D01*
G01Y409265D02*
X1924439D01*
G01X1928340Y409659D02*
X1924439D01*
G01X1978470Y411762D02*
X1922171D01*
G01X1978470Y411959D02*
X1922171D01*
G01X1978470Y414580D02*
X1922171D01*
G01X1978470Y415171D02*
X1921843D01*
G01X1924897Y409266D02*
X1924907Y409229D01*
X1924934Y409130D01*
X1924975Y408999D01*
X1925028Y408872D01*
G01X1924813Y409659D02*
X1924843Y409509D01*
X1924871Y409380D01*
X1924890Y409295D01*
X1924897Y409266D01*
G01X1921843Y479049D02*
Y403524D01*
G01X1924439Y409069D02*
Y409659D01*
G01X1924813D02*
G03X1924208Y408775I343J-884D01*
G01X1924439Y409659D02*
G03X1923634Y408854I0J-805D01*
G01X1924897Y409266D02*
G03X1924602Y408775I259J-490D01*
G01X1924439Y409265D02*
G03X1924027Y408854I0J-412D01*
G01X1924439Y409069D02*
G03X1924224Y408854I0J-215D01*
G01X1925028Y408872D02*
G03X1924995Y408775I128J-98D01*
G01X1936582Y376588D02*
X1936706Y376614D01*
X1936810Y376687D01*
X1936877Y376794D01*
G01X1928532Y378713D02*
X1928158Y378646D01*
G01X1937128Y376903D02*
X1950671D01*
G01X1937787Y377076D02*
X1935425D01*
G01X1930537D02*
X1935065D01*
G01X1938775Y378950D02*
X1942311D01*
G01X1938397Y380726D02*
X1937807D01*
G01X1928555D02*
X1929145D01*
G01X1935065Y384462D02*
X1930537D01*
G01X1935425D02*
X1937787D01*
G01X1938775Y378645D02*
X1938381Y378715D01*
G01X1930370Y376588D02*
X1930246Y376614D01*
X1930142Y376687D01*
X1930075Y376794D01*
G01X1937787Y376882D02*
X1937867Y376859D01*
G01X1936498Y376903D02*
X1936877Y376794D01*
G01X1937709Y380180D02*
X1938263Y379976D01*
G01X1929824Y376903D02*
X1930075Y376794D01*
G01X1928471Y377741D02*
X1928468Y377745D01*
X1928458Y377757D01*
X1928441Y377778D01*
X1928417Y377808D01*
X1928388Y377847D01*
X1928355Y377895D01*
X1928317Y377950D01*
X1928276Y378015D01*
X1928235Y378087D01*
X1928199Y378158D01*
X1928170Y378222D01*
X1928148Y378281D01*
X1928132Y378335D01*
X1928122Y378383D01*
X1928119Y378426D01*
X1928122Y378461D01*
X1928131Y378490D01*
X1928144Y378515D01*
X1928157Y378533D01*
X1928168Y378545D01*
X1928172Y378550D01*
G01X1930075Y376794D02*
X1930121Y376711D01*
X1930190Y376645D01*
X1930276Y376603D01*
X1930370Y376588D01*
G01X1928172Y378550D02*
X1928471Y377741D01*
G01X1929164Y377003D02*
X1928532Y378713D01*
G01X1929824Y376903D02*
X1928689Y379976D01*
G01X1928874Y380044D02*
X1930075Y376794D01*
G01X1929243Y380180D02*
X1930454Y376903D01*
G01X1927745Y408775D02*
Y376588D01*
G01X1928138Y408775D02*
Y378950D01*
G01X1928532Y408775D02*
Y378713D01*
G01X1928555Y408854D02*
Y380726D01*
G01X1928752D02*
Y408854D01*
G01X1929145Y380726D02*
Y408854D01*
G01X1929824Y376903D02*
Y376588D01*
G01X1930454D02*
Y376903D01*
G01X1930537Y384462D02*
Y376588D01*
G01X1935065Y384462D02*
Y376588D01*
G01X1935425Y384462D02*
Y376588D01*
G01X1936498Y376903D02*
Y376588D01*
G01X1937128Y376903D02*
Y376588D01*
G01X1937787Y376822D02*
Y384462D01*
G01X1937807Y408854D02*
Y380726D01*
G01X1938200Y408854D02*
Y380726D01*
G01X1938381Y378715D02*
Y408775D01*
G01X1938397Y380726D02*
Y408854D01*
G01X1938775Y378645D02*
Y408775D01*
G01X1928689Y379976D02*
X1929243Y380180D01*
G01X1930075Y376794D02*
X1930454Y376903D01*
G01X1936498D02*
X1937709Y380180D01*
G01X1938078Y380044D02*
X1936877Y376794D01*
G01X1938263Y379976D02*
X1937128Y376903D01*
G01X1938381Y378715D02*
X1937787Y377108D01*
G01X1938253Y377233D02*
X1938775Y378645D01*
G01X1936859Y376799D02*
X1936800Y376693D01*
X1936701Y376617D01*
X1936578Y376588D01*
G01X1937787Y377013D02*
X1937415Y376794D01*
X1937006Y376646D01*
X1936538Y376588D01*
G01X1937867Y376859D02*
X1937815Y376833D01*
X1937787Y376822D01*
G01X1936877Y376794D02*
X1936896Y376803D01*
X1936948Y376827D01*
X1937029Y376861D01*
X1937128Y376903D01*
G01X1938253Y377233D02*
X1938175Y377102D01*
X1938052Y376979D01*
X1937867Y376859D01*
G01X1938440Y377738D02*
X1938443Y377741D01*
X1938453Y377754D01*
X1938470Y377775D01*
X1938494Y377806D01*
X1938524Y377845D01*
X1938558Y377893D01*
X1938597Y377950D01*
X1938638Y378016D01*
X1938680Y378089D01*
X1938716Y378159D01*
X1938745Y378224D01*
X1938767Y378283D01*
X1938784Y378338D01*
X1938793Y378387D01*
X1938796Y378430D01*
X1938793Y378465D01*
X1938784Y378495D01*
X1938771Y378519D01*
X1938757Y378538D01*
X1938741Y378554D01*
G01X1930075Y376794D02*
G03X1930370Y376588I296J109D01*
G01X1928471Y377741D02*
G03X1930500Y376588I2029J1209D01*
G01X1928138Y378950D02*
G03X1928172Y378550I2362J-1D01*
G01X1928555Y380726D02*
G03X1928689Y379976I2165J0D01*
G01X1928752Y380726D02*
G03X1928874Y380044I1968J0D01*
G01X1929145Y380726D02*
G03X1929243Y380180I1575J1D01*
G01X1936582Y376588D02*
G03X1936877Y376794I-1J315D01*
G01X1938741Y378554D02*
G03X1938775Y378950I-2328J399D01*
G01X1937784Y377028D02*
G03X1938440Y377738I-1370J1924D01*
G01X1938263Y379976D02*
G03X1938397Y380726I-2031J750D01*
G01X1938078Y380044D02*
G03X1938200Y380726I-1846J682D01*
G01X1937709Y380180D02*
G03X1937807Y380726I-1477J547D01*
G01X1939169Y408775D02*
X1938381D01*
G01X1927745D02*
X1928532D01*
G01X1928555Y408854D02*
X1929145D01*
G01X1937807D02*
X1938397D01*
G01X1938612Y409069D02*
X1942513D01*
G01Y409265D02*
X1938612D01*
G01X1942513Y409659D02*
X1938612D01*
G01X1939071Y409266D02*
X1939063Y409295D01*
X1939044Y409380D01*
X1939017Y409507D01*
X1938987Y409659D01*
G01X1928340Y409069D02*
Y409659D01*
G01X1938612Y409069D02*
Y409659D01*
G01X1927926D02*
X1927897Y409508D01*
X1927869Y409380D01*
X1927849Y409295D01*
X1927842Y409266D01*
G01X1927712Y408872D02*
X1927767Y409006D01*
X1927808Y409138D01*
X1927834Y409232D01*
X1927842Y409266D01*
G01X1928532Y408775D02*
G03X1927926Y409659I-948J0D01*
G01X1929145Y408854D02*
G03X1928340Y409659I-805J0D01*
G01X1928138Y408775D02*
G03X1927842Y409266I-554J1D01*
G01X1928752Y408854D02*
G03X1928340Y409265I-412J-1D01*
G01X1928555Y408854D02*
G03X1928340Y409069I-215J0D01*
G01X1927745Y408775D02*
G03X1927712Y408872I-161J-1D01*
G01X1932335Y422258D02*
G03I-709J0D01*
G01X1938987Y409659D02*
G03X1938381Y408775I342J-884D01*
G01X1938612Y409659D02*
G03X1937807Y408854I0J-805D01*
G01X1939071Y409266D02*
G03X1938775Y408775I258J-490D01*
G01X1938612Y409265D02*
G03X1938200Y408854I0J-412D01*
G01X1938612Y409069D02*
G03X1938397Y408854I0J-215D01*
G01X1922600Y427921D02*
X1922453Y427891D01*
G01X1921921Y427258D02*
X1921744D01*
G01X1923250D02*
X1923073D01*
G01X1924667D02*
X1924402D01*
G01X1923663D02*
X1923486D01*
G01X1922453Y427891D02*
X1921921D01*
G01Y428072D02*
X1922482D01*
G01Y428524D02*
X1921921D01*
G01X1921744Y428675D02*
X1922453D01*
G01X1923073D02*
X1923250D01*
G01X1924490D02*
X1924667D01*
G01X1923486D02*
X1923752D01*
G01X1922453D02*
X1922600Y428645D01*
G01X1922571Y428494D02*
X1922482Y428524D01*
G01X1922600Y428645D02*
X1922719Y428554D01*
G01X1922630Y428434D02*
X1922571Y428494D01*
G01X1922719Y428554D02*
X1922807Y428434D01*
G01X1923752Y428675D02*
X1924490Y427469D01*
G01X1924402Y427258D02*
X1923663Y428494D01*
G01X1922659Y428343D02*
X1922630Y428434D01*
G01X1922807D02*
X1922837Y428343D01*
G01X1921744Y427258D02*
Y428675D01*
G01X1921921Y427891D02*
Y427258D01*
G01Y428524D02*
Y428072D01*
G01X1922659Y428253D02*
Y428343D01*
G01X1922837D02*
Y428223D01*
G01X1923073Y427258D02*
Y428675D01*
G01X1923250D02*
Y427258D01*
G01X1923486D02*
Y428675D01*
G01X1923663Y428494D02*
Y427258D01*
G01X1924490Y427469D02*
Y428675D01*
G01X1924667D02*
Y427258D01*
G01X1922482Y428072D02*
X1922571Y428102D01*
G01X1922630Y428162D02*
X1922659Y428253D01*
G01X1922837Y428223D02*
X1922807Y428132D01*
G01X1922719Y428011D02*
X1922600Y427921D01*
G01X1922807Y428132D02*
X1922719Y428011D01*
G01X1922571Y428102D02*
X1922630Y428162D01*
G01X1926508Y431313D02*
G03I-1969J0D01*
G01X1925248D02*
G03I-709J0D01*
G01X1921843Y438557D02*
X1923283D01*
G01X1924071Y456273D02*
X1925567D01*
G01X1924819Y457395D02*
X1923391D01*
G01X1927181Y458869D02*
X1922456D01*
G01X1926197Y461391D02*
X1923441D01*
G01X1925567Y456273D02*
X1926354Y454909D01*
G01X1921826Y458960D02*
Y476490D01*
G01X1922456Y460407D02*
Y438557D01*
G01X1923283D02*
Y443572D01*
G01Y445352D02*
Y450659D01*
G01Y452439D02*
Y454909D01*
G01X1924071Y456273D02*
X1923283Y454909D01*
G01X1925248Y436825D02*
G03I-709J0D01*
G01Y441155D02*
G03I-709J0D01*
G01X1923283Y445352D02*
G03Y443572I1299J-890D01*
G01X1925248Y445486D02*
G03I-709J0D01*
G01X1923283Y452439D02*
G03Y450659I1299J-890D01*
G01X1925248Y450998D02*
G03I-709J0D01*
G01Y455329D02*
G03I-709J0D01*
G01X1926384Y455830D02*
G03X1924819Y457395I-1565J0D01*
G01X1921826Y458960D02*
G03X1923391Y457395I1565J0D01*
G01X1923441Y461391D02*
G03X1922456Y460407I-1J-984D01*
G01X1925248Y459659D02*
G03I-709J0D01*
G01X1926787Y463124D02*
G03I-1969J0D01*
G01X1921843Y469009D02*
X1923283D01*
G01X1923624Y469403D02*
X1921826D01*
G01Y474128D02*
X1977981D01*
G01X1921843Y475309D02*
X1977981D01*
G01X1977417Y476490D02*
X1921826D01*
G01X1926354Y476883D02*
X1923283D01*
G01X1925173Y478065D02*
X1924464D01*
G01X1921843Y479049D02*
X1977981D01*
G01X1925173Y478065D02*
X1926354Y476883D01*
G01X1923624Y469403D02*
X1923471Y469584D01*
X1923356Y469785D01*
X1923283Y470000D01*
G01X1923254Y470661D02*
X1923298Y470205D01*
X1923427Y469774D01*
X1923624Y469403D01*
G01X1923254Y470242D02*
X1923261Y470118D01*
X1923283Y469995D01*
G01X1923254Y476490D02*
Y470242D01*
G01X1923283Y469009D02*
Y476883D01*
G01X1924464Y478065D02*
X1923283Y476883D01*
G01X1923624Y469403D02*
G03X1926013I1195J1012D01*
G01X1925248Y469502D02*
G03I-709J0D01*
G01Y465171D02*
G03I-709J0D01*
G01X1926498Y427258D02*
X1926321D01*
G01X1927502D02*
X1927325D01*
G01X1928093D02*
X1927915D01*
G01X1927207Y427620D02*
X1926616D01*
G01X1927177Y427740D02*
X1926646D01*
G01X1926793Y428675D02*
X1927030D01*
G01X1927915D02*
X1928093D01*
G01X1927030D02*
X1927502Y427258D01*
G01X1927325D02*
X1927207Y427620D01*
G01X1926911Y428554D02*
X1927177Y427740D01*
G01X1927738Y428223D02*
Y428464D01*
G01X1927915Y427258D02*
Y428434D01*
G01X1928093Y428675D02*
Y427258D01*
G01X1926646Y427740D02*
X1926911Y428554D01*
G01X1926616Y427620D02*
X1926498Y427258D01*
G01X1926321D02*
X1926793Y428675D01*
G01X1927738Y428464D02*
X1927915Y428675D01*
G01Y428434D02*
X1927738Y428223D01*
G01X1932335Y426588D02*
G03I-709J0D01*
G01Y432100D02*
G03I-709J0D01*
G01X1939421Y431313D02*
G03I-708J0D01*
G01X1926354Y438557D02*
X1930370D01*
G01X1933441D02*
X1937456D01*
G01X1936039Y439679D02*
X1934858D01*
G01X1928952D02*
X1927771D01*
G01X1926590Y441725D02*
X1930134D01*
G01X1933677D02*
X1937220D01*
G01X1939740Y456273D02*
X1938244D01*
G01X1931157D02*
X1932653D01*
G01X1934267Y458869D02*
X1929543D01*
G01X1936630D02*
X1941354D01*
G01X1940370Y461391D02*
X1937614D01*
G01X1933283D02*
X1930527D01*
G01X1927771Y439679D02*
X1926384Y442083D01*
G01X1934858Y439679D02*
X1933470Y442083D01*
G01X1932653Y456273D02*
X1933441Y454909D01*
G01X1926354D02*
Y452439D01*
G01Y450659D02*
Y445352D01*
G01Y443572D02*
Y438557D01*
G01X1926384Y442083D02*
Y443617D01*
G01Y445308D02*
Y450704D01*
G01Y452394D02*
Y455830D01*
G01X1927181Y438557D02*
Y460407D01*
G01X1929543D02*
Y438557D01*
G01X1930340Y455830D02*
Y452394D01*
G01Y450704D02*
Y445308D01*
G01Y443617D02*
Y442083D01*
G01X1930370Y438557D02*
Y443572D01*
G01Y445352D02*
Y450659D01*
G01Y452439D02*
Y454909D01*
G01X1933441D02*
Y452439D01*
G01Y450659D02*
Y445352D01*
G01Y443572D02*
Y438557D01*
G01X1933470Y442083D02*
Y443617D01*
G01Y445308D02*
Y450704D01*
G01Y452394D02*
Y455830D01*
G01X1934267Y438557D02*
Y460407D01*
G01X1936630D02*
Y438557D01*
G01X1937427Y455830D02*
Y452394D01*
G01Y450704D02*
Y445308D01*
G01Y443617D02*
Y442083D01*
G01X1937456Y438557D02*
Y443572D01*
G01Y445352D02*
Y450659D01*
G01Y452439D02*
Y454909D01*
G01X1931157Y456273D02*
X1930370Y454909D01*
G01X1938244Y456273D02*
X1937456Y454909D01*
G01X1930340Y442083D02*
X1928952Y439679D01*
G01X1937427Y442083D02*
X1936039Y439679D01*
G01X1926354Y443572D02*
G03Y445352I-1299J890D01*
G01X1932335Y436431D02*
G03I-709J0D01*
G01Y440762D02*
G03I-709J0D01*
G01X1933441Y443572D02*
G03Y445352I-1300J890D01*
G01X1930370D02*
G03Y443572I1299J-890D01*
G01X1932335Y446273D02*
G03I-709J0D01*
G01X1939421Y436825D02*
G03I-708J0D01*
G01Y441155D02*
G03I-708J0D01*
G01X1937456Y445352D02*
G03Y443572I1299J-890D01*
G01X1939421Y445486D02*
G03I-708J0D01*
G01X1926354Y450659D02*
G03Y452439I-1299J890D01*
G01X1927181Y460407D02*
G03X1926197Y461391I-984J0D01*
G01X1933441Y450659D02*
G03Y452439I-1300J890D01*
G01X1930370D02*
G03Y450659I1299J-890D01*
G01X1932335Y450604D02*
G03I-709J0D01*
G01Y454935D02*
G03I-709J0D01*
G01X1933470Y455830D02*
G03X1930340I-1565J0D01*
G01X1934267Y460407D02*
G03X1933283Y461391I-984J0D01*
G01X1930527D02*
G03X1929543Y460407I0J-984D01*
G01X1932335Y460447D02*
G03I-709J0D01*
G01X1933874Y463124D02*
G03I-1969J0D01*
G01X1937456Y452439D02*
G03Y450659I1299J-890D01*
G01X1939421Y450998D02*
G03I-708J0D01*
G01Y455329D02*
G03I-708J0D01*
G01X1940557Y455830D02*
G03X1937427I-1565J0D01*
G01X1937614Y461391D02*
G03X1936630Y460407I0J-984D01*
G01X1939421Y459659D02*
G03I-708J0D01*
G01X1940960Y463124D02*
G03I-1968J0D01*
G01X1926354Y469009D02*
X1930370D01*
G01X1933441D02*
X1937456D01*
G01X1937798Y469403D02*
X1933099D01*
G01X1930711D02*
X1926013D01*
G01X1940527Y476883D02*
X1937456D01*
G01X1933441D02*
X1930370D01*
G01X1939346Y478065D02*
X1938637D01*
G01X1932259D02*
X1931551D01*
G01X1932259D02*
X1933441Y476883D01*
G01X1930711Y469403D02*
X1930558Y469584D01*
X1930443Y469785D01*
X1930370Y470000D01*
G01X1937798Y469403D02*
X1937645Y469584D01*
X1937530Y469785D01*
X1937456Y470000D01*
G01X1930340Y470661D02*
X1930385Y470205D01*
X1930514Y469774D01*
X1930711Y469403D01*
G01X1937427Y470661D02*
X1937472Y470205D01*
X1937600Y469774D01*
X1937798Y469403D01*
G01X1930340Y470242D02*
X1930348Y470118D01*
X1930370Y469995D01*
G01X1937427Y470242D02*
X1937434Y470118D01*
X1937456Y469995D01*
G01X1926354Y476883D02*
Y469009D01*
G01X1926384Y476490D02*
Y470242D01*
G01X1930340Y476490D02*
Y470242D01*
G01X1930370Y469009D02*
Y476883D01*
G01X1933441D02*
Y469009D01*
G01X1933470Y476490D02*
Y470242D01*
G01X1937427Y476490D02*
Y470242D01*
G01X1937456Y469009D02*
Y476883D01*
G01X1926384Y470242D02*
X1926376Y470119D01*
X1926354Y469995D01*
G01X1933470Y470242D02*
X1933463Y470119D01*
X1933441Y469995D01*
G01X1926354Y470000D02*
X1926281Y469786D01*
X1926165Y469583D01*
X1926013Y469403D01*
G01X1933441Y470000D02*
X1933368Y469786D01*
X1933252Y469583D01*
X1933099Y469403D01*
G01X1926013D02*
X1926210Y469774D01*
X1926339Y470205D01*
X1926384Y470661D01*
G01X1933099Y469403D02*
X1933297Y469774D01*
X1933425Y470205D01*
X1933470Y470661D01*
G01X1931551Y478065D02*
X1930370Y476883D01*
G01X1938637Y478065D02*
X1937456Y476883D01*
G01X1930711Y469403D02*
G03X1933099I1194J1012D01*
G01X1932335Y464777D02*
G03I-709J0D01*
G01X1937798Y469403D02*
G03X1940186I1194J1012D01*
G01X1939421Y465171D02*
G03I-708J0D01*
G01Y469502D02*
G03I-708J0D01*
G01X1925484Y505643D02*
X1924500D01*
G01X1930077Y509329D02*
X1925484D01*
G01Y510334D02*
X1930077D01*
G01X1924500Y513517D02*
X1925484D01*
G01X1924500Y505643D02*
Y513517D01*
G01X1925484D02*
Y510334D01*
G01Y509329D02*
Y505643D01*
G01X1939100D02*
X1938115D01*
G01X1931061D02*
X1930077D01*
G01Y513517D02*
X1931061D01*
G01X1938115D02*
X1939100D01*
G01X1933522Y509664D02*
X1935819Y508491D01*
G01X1935491Y507989D02*
X1932374Y509664D01*
G01X1935491Y511340D02*
X1935819Y510837D01*
G01X1930077Y505643D02*
Y509329D01*
G01Y510334D02*
Y513517D01*
G01X1931061D02*
Y505643D01*
G01X1937131Y511004D02*
Y512345D01*
G01X1938115Y505643D02*
Y512177D01*
G01X1932374Y509664D02*
X1935491Y511340D01*
G01X1935819Y510837D02*
X1933522Y509664D01*
G01X1937131Y512345D02*
X1938115Y513517D01*
G01Y512177D02*
X1937131Y511004D01*
G01X1935819Y508491D02*
X1935491Y507989D01*
G01X1924736Y551667D02*
X1884972D01*
G01Y595998D02*
Y551667D01*
G01X1924736Y595998D02*
X1884972D01*
G01X1924736D02*
Y551667D01*
G01X1904406Y1105328D02*
X1907555D01*
G01D02*
X2170285D01*
G01X1879357Y1278974D02*
X2387231D01*
G01X1999011Y-298192D02*
G03I-11811J0D01*
G01X1993105D02*
G03I-5905J0D01*
G01X1953735Y-83624D02*
X2012790D01*
G01X1953735Y-4884D02*
Y-83624D01*
G01X2012790Y51117D02*
G03Y-10256I-17716J-30686D01*
G01X2002357Y20430D02*
G03I-7283J0D01*
G01X1998125Y2714D02*
G03I-3051J0D01*
G01X1999208Y38147D02*
G03I-4134J0D01*
G01X1992571Y55775D02*
X1990666Y82694D01*
G01D02*
X1993906D01*
G01D02*
X2373565D01*
G01X1950755Y376588D02*
X1950880Y376614D01*
X1950984Y376687D01*
X1951050Y376794D01*
G01X1942331Y378646D02*
X1942705Y378713D01*
G01X1943998Y376588D02*
X1944544D01*
G01X1950754D02*
X1951301D01*
G01Y376903D02*
X1964844D01*
G01X1951960Y377076D02*
X1949598D01*
G01X1944710D02*
X1949238D01*
G01X1952948Y378950D02*
X1956485D01*
G01X1952571Y380726D02*
X1951980D01*
G01X1942728D02*
X1943319D01*
G01X1949238Y384462D02*
X1944710D01*
G01X1949598D02*
X1951960D01*
G01X1952948Y378645D02*
X1952554Y378715D01*
G01X1944543Y376588D02*
X1944419Y376614D01*
X1944315Y376687D01*
X1944248Y376794D01*
G01X1951960Y376882D02*
X1952040Y376859D01*
G01X1950671Y376903D02*
X1951050Y376794D01*
G01X1951882Y380180D02*
X1952436Y379976D01*
G01X1943998Y376903D02*
X1944248Y376794D01*
G01X1942645Y377741D02*
X1942641Y377745D01*
X1942632Y377757D01*
X1942614Y377778D01*
X1942591Y377808D01*
X1942561Y377847D01*
X1942528Y377895D01*
X1942490Y377950D01*
X1942449Y378015D01*
X1942408Y378087D01*
X1942372Y378158D01*
X1942343Y378222D01*
X1942321Y378281D01*
X1942305Y378335D01*
X1942295Y378383D01*
X1942293Y378426D01*
X1942296Y378461D01*
X1942304Y378490D01*
X1942317Y378515D01*
X1942330Y378533D01*
X1942341Y378545D01*
X1942346Y378550D01*
G01X1944248Y376794D02*
X1944294Y376711D01*
X1944363Y376645D01*
X1944449Y376603D01*
X1944543Y376588D01*
G01X1942346Y378550D02*
X1942645Y377741D01*
G01X1943337Y377003D02*
X1942705Y378713D01*
G01X1943998Y376903D02*
X1942862Y379976D01*
G01X1944248Y376794D02*
X1943047Y380044D01*
G01X1943416Y380180D02*
X1944627Y376903D01*
G01X1939169Y408775D02*
Y376588D01*
G01X1941918D02*
Y408775D01*
G01X1942311D02*
Y378950D01*
G01X1942705Y408775D02*
Y378713D01*
G01X1942728Y408854D02*
Y380726D01*
G01X1942925Y408854D02*
Y380726D01*
G01X1943319D02*
Y408854D01*
G01X1943998Y376903D02*
Y376588D01*
G01X1944627Y376903D02*
Y376588D01*
G01X1944710Y384462D02*
Y376588D01*
G01X1949238Y384462D02*
Y376588D01*
G01X1949598Y384462D02*
Y376588D01*
G01X1950671Y376903D02*
Y376588D01*
G01X1951301Y376903D02*
Y376588D01*
G01X1951960Y376822D02*
Y384462D01*
G01X1951980Y408854D02*
Y380726D01*
G01X1952374Y408854D02*
Y380726D01*
G01X1952554Y378715D02*
Y408775D01*
G01X1952571Y380726D02*
Y408854D01*
G01X1952948Y378645D02*
Y408775D01*
G01X1953342D02*
Y376588D01*
G01X1944248Y376794D02*
X1944627Y376903D01*
G01X1950671D02*
X1951882Y380180D01*
G01X1952252Y380044D02*
X1951050Y376794D01*
G01X1952436Y379976D02*
X1951301Y376903D01*
G01X1952554Y378715D02*
X1951960Y377108D01*
G01X1952426Y377233D02*
X1952948Y378645D01*
G01X1952040Y376859D02*
X1952015Y376846D01*
X1951988Y376833D01*
X1951960Y376822D01*
G01X1951050Y376794D02*
X1951069Y376803D01*
X1951121Y376827D01*
X1951202Y376861D01*
X1951301Y376903D01*
G01X1942862Y379976D02*
X1943416Y380180D01*
G01X1951033Y376799D02*
X1950973Y376693D01*
X1950874Y376617D01*
X1950751Y376588D01*
G01X1952426Y377233D02*
X1952348Y377102D01*
X1952225Y376979D01*
X1952040Y376859D01*
G01X1952613Y377738D02*
X1952616Y377741D01*
X1952626Y377754D01*
X1952643Y377775D01*
X1952667Y377806D01*
X1952697Y377845D01*
X1952732Y377893D01*
X1952770Y377950D01*
X1952811Y378016D01*
X1952853Y378089D01*
X1952889Y378159D01*
X1952918Y378224D01*
X1952941Y378283D01*
X1952957Y378338D01*
X1952967Y378387D01*
X1952969Y378430D01*
X1952966Y378465D01*
X1952957Y378495D01*
X1952944Y378519D01*
X1952930Y378538D01*
X1952919Y378549D01*
X1952915Y378554D01*
G01X1951960Y377013D02*
X1951588Y376794D01*
X1951179Y376646D01*
X1950711Y376588D01*
G01X1944248Y376794D02*
G03X1944543Y376588I296J109D01*
G01X1942645Y377741D02*
G03X1944674Y376588I2029J1209D01*
G01X1942311Y378950D02*
G03X1942346Y378550I2362J5D01*
G01X1942728Y380726D02*
G03X1942862Y379976I2165J0D01*
G01X1942925Y380726D02*
G03X1943047Y380044I1968J0D01*
G01X1943319Y380726D02*
G03X1943416Y380180I1575J-2D01*
G01X1950755Y376588D02*
G03X1951050Y376794I-1J315D01*
G01X1952915Y378554D02*
G03X1952948Y378950I-2329J393D01*
G01X1951958Y377028D02*
G03X1952613Y377738I-1372J1923D01*
G01X1952436Y379976D02*
G03X1952571Y380726I-2030J753D01*
G01X1952252Y380044D02*
G03X1952374Y380726I-1847J682D01*
G01X1951882Y380180D02*
G03X1951980Y380726I-1477J547D01*
G01X1953342Y408775D02*
X1952554D01*
G01X1941918D02*
X1942705D01*
G01X1942728Y408854D02*
X1943319D01*
G01X1951980D02*
X1952571D01*
G01X1956059Y408872D02*
X1953374D01*
G01X1941885D02*
X1939201D01*
G01X1952785Y409069D02*
X1956686D01*
G01Y409265D02*
X1952785D01*
G01X1956686Y409659D02*
X1952785D01*
G01X1939071Y409266D02*
X1939080Y409229D01*
X1939107Y409130D01*
X1939148Y408999D01*
X1939201Y408872D01*
G01X1953244Y409266D02*
X1953253Y409229D01*
X1953280Y409130D01*
X1953322Y408999D01*
X1953374Y408872D01*
G01X1953244Y409266D02*
X1953237Y409295D01*
X1953217Y409380D01*
X1953190Y409507D01*
X1953160Y409659D01*
G01X1942513Y409069D02*
Y409659D01*
G01X1952785Y409069D02*
Y409659D01*
G01X1942015Y409266D02*
X1942023Y409295D01*
X1942042Y409380D01*
X1942069Y409507D01*
X1942099Y409659D01*
G01X1942015Y409266D02*
X1942008Y409237D01*
X1941986Y409154D01*
X1941947Y409025D01*
X1941885Y408872D01*
G01X1942705Y408775D02*
G03X1942099Y409659I-948J0D01*
G01X1943319Y408854D02*
G03X1942513Y409659I-806J-1D01*
G01X1942311Y408775D02*
G03X1942015Y409266I-554J1D01*
G01X1942925Y408854D02*
G03X1942513Y409265I-412J-1D01*
G01X1942728Y408854D02*
G03X1942513Y409069I-215J0D01*
G01X1939201Y408872D02*
G03X1939169Y408775I128J-96D01*
G01X1941918D02*
G03X1941885Y408872I-161J-1D01*
G01X1946508Y422258D02*
G03I-709J0D01*
G01X1953160Y409659D02*
G03X1952554Y408775I342J-884D01*
G01X1952785Y409659D02*
G03X1951980Y408854I0J-805D01*
G01X1953244Y409266D02*
G03X1952948Y408775I258J-490D01*
G01X1952785Y409265D02*
G03X1952374Y408854I0J-411D01*
G01X1952785Y409069D02*
G03X1952571Y408854I1J-215D01*
G01X1953374Y408872D02*
G03X1953342Y408775I129J-96D01*
G01X1964928Y376588D02*
X1965053Y376614D01*
X1965157Y376687D01*
X1965224Y376794D01*
G01X1970678Y378646D02*
X1971052Y378713D01*
G01X1956504Y378646D02*
X1956878Y378713D01*
G01X1972344Y376588D02*
X1972891D01*
G01X1958171D02*
X1958717D01*
G01X1964927D02*
X1965474D01*
G01Y376903D02*
X1978470D01*
G01X1966134Y377076D02*
X1963771D01*
G01X1958884D02*
X1963411D01*
G01X1973057D02*
X1978470D01*
G01X1967121Y378950D02*
X1970658D01*
G01X1966744Y380726D02*
X1966153D01*
G01X1956901D02*
X1957492D01*
G01X1971074D02*
X1971665D01*
G01X1978470Y384462D02*
X1973057D01*
G01X1963411D02*
X1958884D01*
G01X1963771D02*
X1966134D01*
G01X1967121Y378645D02*
X1966728Y378715D01*
G01X1958717Y376588D02*
X1958592Y376614D01*
X1958488Y376687D01*
X1958421Y376794D01*
G01X1972890Y376588D02*
X1972765Y376614D01*
X1972661Y376687D01*
X1972595Y376794D01*
G01X1966134Y376882D02*
X1966213Y376859D01*
G01X1964844Y376903D02*
X1965224Y376794D01*
G01X1966056Y380180D02*
X1966609Y379976D01*
G01X1958171Y376903D02*
X1958421Y376794D01*
G01X1972344Y376903D02*
X1972595Y376794D01*
G01X1956818Y377741D02*
X1956815Y377745D01*
X1956805Y377757D01*
X1956787Y377778D01*
X1956764Y377808D01*
X1956735Y377847D01*
X1956701Y377895D01*
X1956663Y377950D01*
X1956622Y378015D01*
X1956582Y378087D01*
X1956545Y378158D01*
X1956517Y378222D01*
X1956494Y378281D01*
X1956478Y378335D01*
X1956469Y378383D01*
X1956466Y378426D01*
X1956469Y378461D01*
X1956478Y378490D01*
X1956490Y378515D01*
X1956504Y378533D01*
X1956514Y378545D01*
X1956519Y378550D01*
G01X1970991Y377741D02*
X1970988Y377745D01*
X1970978Y377757D01*
X1970961Y377778D01*
X1970937Y377808D01*
X1970908Y377847D01*
X1970874Y377895D01*
X1970837Y377950D01*
X1970796Y378015D01*
X1970755Y378087D01*
X1970719Y378158D01*
X1970690Y378222D01*
X1970667Y378281D01*
X1970651Y378335D01*
X1970642Y378383D01*
X1970639Y378426D01*
X1970642Y378461D01*
X1970651Y378490D01*
X1970663Y378515D01*
X1970677Y378533D01*
X1970687Y378545D01*
X1970692Y378550D01*
G01X1958421Y376794D02*
X1958467Y376711D01*
X1958536Y376645D01*
X1958622Y376603D01*
X1958717Y376588D01*
G01X1972595Y376794D02*
X1972641Y376711D01*
X1972709Y376645D01*
X1972796Y376603D01*
X1972890Y376588D01*
G01X1956519Y378550D02*
X1956818Y377741D01*
G01X1957510Y377003D02*
X1956878Y378713D01*
G01X1958171Y376903D02*
X1957035Y379976D01*
G01X1958421Y376794D02*
X1957220Y380044D01*
G01X1957589Y380180D02*
X1958800Y376903D01*
G01X1970692Y378550D02*
X1970991Y377741D01*
G01X1971684Y377003D02*
X1971052Y378713D01*
G01X1972344Y376903D02*
X1971209Y379976D01*
G01X1972595Y376794D02*
X1971393Y380044D01*
G01X1971763Y380180D02*
X1972974Y376903D01*
G01X1956091Y376588D02*
Y408775D01*
G01X1956485D02*
Y378950D01*
G01X1956878Y408775D02*
Y378713D01*
G01X1956901Y408854D02*
Y380726D01*
G01X1957098Y408854D02*
Y380726D01*
G01X1957492D02*
Y408854D01*
G01X1958171Y376903D02*
Y376588D01*
G01X1958800Y376903D02*
Y376588D01*
G01X1958884Y384462D02*
Y376588D01*
G01X1963411Y384462D02*
Y376588D01*
G01X1963771Y384462D02*
Y376588D01*
G01X1964844Y376903D02*
Y376588D01*
G01X1965474Y376903D02*
Y376588D01*
G01X1966134Y384462D02*
Y376822D01*
G01X1966153Y408854D02*
Y380726D01*
G01X1966547Y408854D02*
Y380726D01*
G01X1966728Y378715D02*
Y408775D01*
G01X1966744Y380726D02*
Y408854D01*
G01X1967121Y408775D02*
Y378645D01*
G01X1967515Y408775D02*
Y376588D01*
G01X1970264Y408775D02*
Y376588D01*
G01X1970658Y408775D02*
Y378950D01*
G01X1971052Y408775D02*
Y378713D01*
G01X1971074Y408854D02*
Y380726D01*
G01X1971271Y408854D02*
Y380726D01*
G01X1971665D02*
Y408854D01*
G01X1972344Y376903D02*
Y376588D01*
G01X1972974Y376903D02*
Y376588D01*
G01X1973057Y384462D02*
Y376588D01*
G01X1978470D02*
Y415171D01*
G01X1958421Y376794D02*
X1958800Y376903D01*
G01X1965224Y376794D02*
X1965242Y376803D01*
X1965295Y376827D01*
X1965376Y376861D01*
X1965474Y376903D01*
G01X1957035Y379976D02*
X1957589Y380180D01*
G01X1971209Y379976D02*
X1971763Y380180D01*
G01X1972595Y376794D02*
X1972974Y376903D01*
G01X1964844D02*
X1966056Y380180D01*
G01X1966425Y380044D02*
X1965224Y376794D01*
G01X1966609Y379976D02*
X1965474Y376903D01*
G01X1966728Y378715D02*
X1966134Y377108D01*
G01X1967121Y378645D02*
X1966600Y377233D01*
G01X1965206Y376799D02*
X1965146Y376693D01*
X1965048Y376617D01*
X1964924Y376588D01*
G01X1966600Y377233D02*
X1966522Y377102D01*
X1966398Y376979D01*
X1966213Y376859D01*
G01X1966786Y377738D02*
X1966789Y377741D01*
X1966799Y377754D01*
X1966817Y377775D01*
X1966841Y377806D01*
X1966871Y377845D01*
X1966905Y377893D01*
X1966943Y377950D01*
X1966984Y378016D01*
X1967026Y378089D01*
X1967062Y378159D01*
X1967091Y378224D01*
X1967114Y378283D01*
X1967130Y378338D01*
X1967140Y378387D01*
X1967143Y378430D01*
X1967139Y378465D01*
X1967130Y378495D01*
X1967117Y378519D01*
X1967103Y378538D01*
X1967092Y378549D01*
X1967088Y378554D01*
G01X1966134Y377013D02*
X1965761Y376794D01*
X1965352Y376646D01*
X1964884Y376588D01*
G01X1966213Y376859D02*
X1966188Y376846D01*
X1966161Y376833D01*
X1966134Y376822D01*
G01X1958421Y376794D02*
G03X1958717Y376588I296J109D01*
G01X1956818Y377741D02*
G03X1958847Y376588I2029J1209D01*
G01X1956485Y378950D02*
G03X1956519Y378550I2362J-1D01*
G01X1956901Y380726D02*
G03X1957035Y379976I2166J0D01*
G01X1957098Y380726D02*
G03X1957220Y380044I1969J0D01*
G01X1957492Y380726D02*
G03X1957589Y380180I1575J-2D01*
G01X1964928Y376588D02*
G03X1965224Y376794I0J315D01*
G01X1972595D02*
G03X1972890Y376588I295J109D01*
G01X1970991Y377741D02*
G03X1973020Y376588I2029J1209D01*
G01X1970658Y378950D02*
G03X1970692Y378550I2362J-1D01*
G01X1967088Y378554D02*
G03X1967121Y378950I-2329J393D01*
G01X1966131Y377028D02*
G03X1966786Y377738I-1372J1923D01*
G01X1966609Y379976D02*
G03X1966744Y380726I-2030J753D01*
G01X1971074D02*
G03X1971209Y379976I2165J3D01*
G01X1966425Y380044D02*
G03X1966547Y380726I-1847J682D01*
G01X1971271D02*
G03X1971393Y380044I1969J0D01*
G01X1966056Y380180D02*
G03X1966153Y380726I-1478J544D01*
G01X1971665D02*
G03X1971763Y380180I1575J1D01*
G01X1978470Y403524D02*
X1977981D01*
G01X1967515Y408775D02*
X1966728D01*
G01X1956091D02*
X1956878D01*
G01X1970264D02*
X1971052D01*
G01X1956901Y408854D02*
X1957492D01*
G01X1966153D02*
X1966744D01*
G01X1971074D02*
X1971665D01*
G01X1970232Y408872D02*
X1967547D01*
G01X1966959Y409069D02*
X1970859D01*
G01Y409265D02*
X1966959D01*
G01X1970859Y409659D02*
X1966959D01*
G01X1967417Y409266D02*
X1967426Y409229D01*
X1967453Y409130D01*
X1967495Y408999D01*
X1967547Y408872D01*
G01X1967417Y409266D02*
X1967410Y409295D01*
X1967390Y409380D01*
X1967363Y409507D01*
X1967333Y409659D01*
G01X1956686Y409069D02*
Y409659D01*
G01X1966959Y409069D02*
Y409659D01*
G01X1970859Y409069D02*
Y409659D01*
G01X1977981Y403524D02*
Y479049D01*
G01X1956189Y409266D02*
X1956196Y409295D01*
X1956215Y409380D01*
X1956243Y409507D01*
X1956272Y409659D01*
G01X1956189Y409266D02*
X1956182Y409237D01*
X1956159Y409154D01*
X1956120Y409025D01*
X1956059Y408872D01*
G01X1970362Y409266D02*
X1970369Y409295D01*
X1970389Y409380D01*
X1970416Y409507D01*
X1970446Y409659D01*
G01X1970362Y409266D02*
X1970355Y409237D01*
X1970332Y409154D01*
X1970293Y409025D01*
X1970232Y408872D01*
G01X1956878Y408775D02*
G03X1956272Y409659I-948J0D01*
G01X1957492Y408854D02*
G03X1956686Y409659I-806J-1D01*
G01X1956485Y408775D02*
G03X1956189Y409266I-555J0D01*
G01X1957098Y408854D02*
G03X1956686Y409265I-412J-1D01*
G01X1956901Y408854D02*
G03X1956686Y409069I-215J0D01*
G01X1956091Y408775D02*
G03X1956059Y408872I-161J1D01*
G01X1960681Y422258D02*
G03I-709J0D01*
G01X1971052Y408775D02*
G03X1970446Y409659I-948J0D01*
G01X1967333D02*
G03X1966728Y408775I343J-884D01*
G01X1966959Y409659D02*
G03X1966153Y408854I-1J-805D01*
G01X1971665D02*
G03X1970859Y409659I-805J0D01*
G01X1970658Y408775D02*
G03X1970362Y409266I-554J0D01*
G01X1967417D02*
G03X1967121Y408775I258J-491D01*
G01X1971271Y408854D02*
G03X1970859Y409265I-412J-1D01*
G01X1966959D02*
G03X1966547Y408854I0J-412D01*
G01X1971074D02*
G03X1970859Y409069I-215J0D01*
G01X1966959D02*
G03X1966744Y408854I0J-215D01*
G01X1967547Y408872D02*
G03X1967515Y408775I129J-96D01*
G01X1970264D02*
G03X1970232Y408872I-161J1D01*
G01X1974854Y422258D02*
G03I-708J0D01*
G01X1946508Y426588D02*
G03I-709J0D01*
G01Y432100D02*
G03I-709J0D01*
G01X1953595Y431313D02*
G03I-709J0D01*
G01X1940527Y438557D02*
X1944543D01*
G01X1947614D02*
X1951630D01*
G01X1954700D02*
X1958716D01*
G01X1950212Y439679D02*
X1949031D01*
G01X1943126D02*
X1941945D01*
G01X1940763Y441725D02*
X1944307D01*
G01X1947850D02*
X1951393D01*
G01X1954937D02*
X1958480D01*
G01X1953913Y456273D02*
X1952417D01*
G01X1946826D02*
X1945330D01*
G01X1943716Y458869D02*
X1948441D01*
G01X1950803D02*
X1955527D01*
G01X1954543Y461391D02*
X1951787D01*
G01X1947456D02*
X1944700D01*
G01X1941945Y439679D02*
X1940557Y442083D01*
G01X1949031Y439679D02*
X1947643Y442083D01*
G01X1939740Y456273D02*
X1940527Y454909D01*
G01X1956118Y439679D02*
X1954730Y442083D01*
G01X1946826Y456273D02*
X1947614Y454909D01*
G01X1953913Y456273D02*
X1954700Y454909D01*
G01X1940527D02*
Y452439D01*
G01Y450659D02*
Y445352D01*
G01Y443572D02*
Y438557D01*
G01X1940557Y442083D02*
Y443617D01*
G01Y445308D02*
Y450704D01*
G01Y452394D02*
Y455830D01*
G01X1941354Y460407D02*
Y438557D01*
G01X1943716Y460407D02*
Y438557D01*
G01X1944513Y455830D02*
Y452394D01*
G01Y450704D02*
Y445308D01*
G01Y443617D02*
Y442083D01*
G01X1944543Y438557D02*
Y443572D01*
G01Y445352D02*
Y450659D01*
G01Y452439D02*
Y454909D01*
G01X1947614D02*
Y452439D01*
G01Y450659D02*
Y445352D01*
G01Y443572D02*
Y438557D01*
G01X1947643Y442083D02*
Y443617D01*
G01Y445308D02*
Y450704D01*
G01Y452394D02*
Y455830D01*
G01X1948441Y460407D02*
Y438557D01*
G01X1950803Y460407D02*
Y438557D01*
G01X1951600Y455830D02*
Y452394D01*
G01Y450704D02*
Y445308D01*
G01Y443617D02*
Y442083D01*
G01X1951630Y438557D02*
Y443572D01*
G01Y445352D02*
Y450659D01*
G01Y452439D02*
Y454909D01*
G01X1954700D02*
Y452439D01*
G01Y450659D02*
Y445352D01*
G01Y443572D02*
Y438557D01*
G01X1954730Y442083D02*
Y443617D01*
G01Y445308D02*
Y450704D01*
G01Y452394D02*
Y455830D01*
G01X1955527Y460407D02*
Y438557D01*
G01X1945330Y456273D02*
X1944543Y454909D01*
G01X1952417Y456273D02*
X1951630Y454909D01*
G01X1944513Y442083D02*
X1943126Y439679D01*
G01X1951600Y442083D02*
X1950212Y439679D01*
G01X1940527Y443572D02*
G03Y445352I-1299J890D01*
G01X1946508Y436431D02*
G03I-709J0D01*
G01Y440762D02*
G03I-709J0D01*
G01X1944543Y445352D02*
G03Y443572I1299J-890D01*
G01X1947614D02*
G03Y445352I-1299J890D01*
G01X1946508Y446273D02*
G03I-709J0D01*
G01X1940527Y450659D02*
G03Y452439I-1299J890D01*
G01X1941354Y460407D02*
G03X1940370Y461391I-984J0D01*
G01X1944543Y452439D02*
G03Y450659I1299J-890D01*
G01X1947614D02*
G03Y452439I-1299J890D01*
G01X1946508Y450604D02*
G03I-709J0D01*
G01Y454935D02*
G03I-709J0D01*
G01X1947643Y455830D02*
G03X1944513I-1565J0D01*
G01X1948441Y460407D02*
G03X1947456Y461391I-984J0D01*
G01X1944700D02*
G03X1943716Y460407I0J-984D01*
G01X1946508Y460447D02*
G03I-709J0D01*
G01X1948047Y463124D02*
G03I-1969J0D01*
G01X1953595Y436825D02*
G03I-709J0D01*
G01Y441155D02*
G03I-709J0D01*
G01X1951630Y445352D02*
G03Y443572I1299J-890D01*
G01X1954700D02*
G03Y445352I-1299J890D01*
G01X1953595Y445486D02*
G03I-709J0D01*
G01X1951630Y452439D02*
G03Y450659I1299J-890D01*
G01X1954700D02*
G03Y452439I-1299J890D01*
G01X1953595Y450998D02*
G03I-709J0D01*
G01Y455329D02*
G03I-709J0D01*
G01X1954730Y455830D02*
G03X1951600I-1565J0D01*
G01X1955527Y460407D02*
G03X1954543Y461391I-984J0D01*
G01X1951787D02*
G03X1950803Y460407I0J-984D01*
G01X1953595Y459659D02*
G03I-709J0D01*
G01X1955134Y463124D02*
G03I-1969J0D01*
G01X1940527Y469009D02*
X1944543D01*
G01X1947614D02*
X1951630D01*
G01X1954700D02*
X1958716D01*
G01X1959058Y469403D02*
X1954359D01*
G01X1951971D02*
X1947272D01*
G01X1944884D02*
X1940186D01*
G01X1954700Y476883D02*
X1951630D01*
G01X1947614D02*
X1944543D01*
G01X1953519Y478065D02*
X1952811D01*
G01X1946433D02*
X1945724D01*
G01X1939346D02*
X1940527Y476883D01*
G01X1946433Y478065D02*
X1947614Y476883D01*
G01X1953519Y478065D02*
X1954700Y476883D01*
G01X1944884Y469403D02*
X1944731Y469584D01*
X1944616Y469785D01*
X1944543Y470000D01*
G01X1951971Y469403D02*
X1951818Y469584D01*
X1951703Y469785D01*
X1951630Y470000D01*
G01X1944513Y470661D02*
X1944558Y470205D01*
X1944687Y469774D01*
X1944884Y469403D01*
G01X1951600Y470661D02*
X1951645Y470205D01*
X1951774Y469774D01*
X1951971Y469403D01*
G01X1944513Y470242D02*
X1944521Y470118D01*
X1944543Y469995D01*
G01X1951600Y470242D02*
X1951608Y470118D01*
X1951630Y469995D01*
G01X1940527Y476883D02*
Y469009D01*
G01X1940557Y476490D02*
Y470242D01*
G01X1944513Y476490D02*
Y470242D01*
G01X1944543Y469009D02*
Y476883D01*
G01X1947614D02*
Y469009D01*
G01X1947643Y476490D02*
Y470242D01*
G01X1951600Y476490D02*
Y470242D01*
G01X1951630Y469009D02*
Y476883D01*
G01X1954700D02*
Y469009D01*
G01X1954730Y476490D02*
Y470242D01*
G01X1940557D02*
X1940549Y470119D01*
X1940527Y469995D01*
G01X1947643Y470242D02*
X1947636Y470119D01*
X1947614Y469995D01*
G01X1954730Y470242D02*
X1954722Y470119D01*
X1954700Y469995D01*
G01X1940527Y470000D02*
X1940454Y469786D01*
X1940339Y469583D01*
X1940186Y469403D01*
G01X1947614Y470000D02*
X1947541Y469786D01*
X1947425Y469583D01*
X1947272Y469403D01*
G01X1954700Y470000D02*
X1954628Y469786D01*
X1954512Y469583D01*
X1954359Y469403D01*
G01X1940186D02*
X1940383Y469774D01*
X1940512Y470205D01*
X1940557Y470661D01*
G01X1947272Y469403D02*
X1947470Y469774D01*
X1947598Y470205D01*
X1947643Y470661D01*
G01X1945724Y478065D02*
X1944543Y476883D01*
G01X1952811Y478065D02*
X1951630Y476883D01*
G01X1954359Y469403D02*
X1954556Y469774D01*
X1954685Y470205D01*
X1954730Y470661D01*
G01X1944884Y469403D02*
G03X1947272I1194J1012D01*
G01X1946508Y464777D02*
G03I-709J0D01*
G01X1951971Y469403D02*
G03X1954359I1194J1012D01*
G01X1953595Y465171D02*
G03I-709J0D01*
G01Y469502D02*
G03I-709J0D01*
G01X1960681Y426588D02*
G03I-709J0D01*
G01Y432100D02*
G03I-709J0D01*
G01X1974854Y426588D02*
G03I-708J0D01*
G01Y432100D02*
G03I-708J0D01*
G01X1967768Y431313D02*
G03I-709J0D01*
G01X1972889Y438557D02*
X1968874D01*
G01X1961787D02*
X1965803D01*
G01X1975960D02*
X1977981D01*
G01X1971472Y439679D02*
X1970291D01*
G01X1964385D02*
X1963204D01*
G01X1957299D02*
X1956118D01*
G01X1962023Y441725D02*
X1965567D01*
G01X1969110D02*
X1972653D01*
G01X1975173Y456273D02*
X1973677D01*
G01X1968086D02*
X1966590D01*
G01X1961000D02*
X1959504D01*
G01X1975852Y457395D02*
X1974425D01*
G01X1976787Y458869D02*
X1972063D01*
G01X1957889D02*
X1962614D01*
G01X1964976D02*
X1969700D01*
G01X1975803Y461391D02*
X1973047D01*
G01X1968716D02*
X1965960D01*
G01X1961630D02*
X1958874D01*
G01X1963204Y439679D02*
X1961817Y442083D01*
G01X1970291Y439679D02*
X1968903Y442083D01*
G01X1961000Y456273D02*
X1961787Y454909D01*
G01X1968086Y456273D02*
X1968874Y454909D01*
G01X1975173Y456273D02*
X1975960Y454909D01*
G01X1957889Y460407D02*
Y438557D01*
G01X1958687Y455830D02*
Y452394D01*
G01Y450704D02*
Y445308D01*
G01Y443617D02*
Y442083D01*
G01X1958716Y438557D02*
Y443572D01*
G01Y445352D02*
Y450659D01*
G01Y452439D02*
Y454909D01*
G01X1961787D02*
Y452439D01*
G01Y450659D02*
Y445352D01*
G01Y443572D02*
Y438557D01*
G01X1961817Y442083D02*
Y443617D01*
G01Y445308D02*
Y450704D01*
G01Y452394D02*
Y455830D01*
G01X1962614Y460407D02*
Y438557D01*
G01X1964976Y460407D02*
Y438557D01*
G01X1965773Y455830D02*
Y452394D01*
G01Y450704D02*
Y445308D01*
G01Y443617D02*
Y442083D01*
G01X1965803Y438557D02*
Y443572D01*
G01Y445352D02*
Y450659D01*
G01Y452439D02*
Y454909D01*
G01X1968874D02*
Y452439D01*
G01Y450659D02*
Y445352D01*
G01Y443572D02*
Y438557D01*
G01X1968903Y442083D02*
Y443617D01*
G01Y445308D02*
Y450704D01*
G01Y452394D02*
Y455830D01*
G01X1969700Y460407D02*
Y438557D01*
G01X1972063Y460407D02*
Y438557D01*
G01X1972860Y455830D02*
Y452394D01*
G01Y450704D02*
Y445308D01*
G01Y443617D02*
Y442083D01*
G01X1972889Y454909D02*
Y452439D01*
G01Y450659D02*
Y445352D01*
G01Y443572D02*
Y438557D01*
G01X1975960Y454909D02*
Y452439D01*
G01Y450659D02*
Y445352D01*
G01Y443572D02*
Y438557D01*
G01X1976787D02*
Y460407D01*
G01X1977417Y476490D02*
Y458960D01*
G01X1959504Y456273D02*
X1958716Y454909D01*
G01X1966590Y456273D02*
X1965803Y454909D01*
G01X1958687Y442083D02*
X1957299Y439679D01*
G01X1973677Y456273D02*
X1972889Y454909D01*
G01X1965773Y442083D02*
X1964385Y439679D01*
G01X1972860Y442083D02*
X1971472Y439679D01*
G01X1960681Y436431D02*
G03I-709J0D01*
G01Y440762D02*
G03I-709J0D01*
G01X1958716Y445352D02*
G03Y443572I1299J-890D01*
G01X1961787D02*
G03Y445352I-1299J890D01*
G01X1960681Y446273D02*
G03I-709J0D01*
G01X1967768Y436825D02*
G03I-709J0D01*
G01Y441155D02*
G03I-709J0D01*
G01X1965803Y445352D02*
G03Y443572I1299J-890D01*
G01X1968874D02*
G03Y445352I-1299J890D01*
G01X1967768Y445486D02*
G03I-709J0D01*
G01X1974854Y436431D02*
G03I-708J0D01*
G01Y440762D02*
G03I-708J0D01*
G01X1975960Y443572D02*
G03Y445352I-1299J890D01*
G01X1972889D02*
G03Y443572I1299J-890D01*
G01X1974854Y446273D02*
G03I-708J0D01*
G01X1958716Y452439D02*
G03Y450659I1299J-890D01*
G01X1961787D02*
G03Y452439I-1299J890D01*
G01X1960681Y450604D02*
G03I-709J0D01*
G01Y454935D02*
G03I-709J0D01*
G01X1961817Y455830D02*
G03X1958687I-1565J0D01*
G01X1962614Y460407D02*
G03X1961630Y461391I-984J0D01*
G01X1958874D02*
G03X1957889Y460407I-1J-984D01*
G01X1960681Y460447D02*
G03I-709J0D01*
G01X1962220Y463124D02*
G03I-1968J0D01*
G01X1965803Y452439D02*
G03Y450659I1299J-890D01*
G01X1968874D02*
G03Y452439I-1299J890D01*
G01X1967768Y450998D02*
G03I-709J0D01*
G01Y455329D02*
G03I-709J0D01*
G01X1968903Y455830D02*
G03X1965773I-1565J0D01*
G01X1969700Y460407D02*
G03X1968716Y461391I-984J0D01*
G01X1965960D02*
G03X1964976Y460407I0J-984D01*
G01X1967768Y459659D02*
G03I-709J0D01*
G01X1975960Y450659D02*
G03Y452439I-1299J890D01*
G01X1972889D02*
G03Y450659I1299J-890D01*
G01X1974854Y450604D02*
G03I-708J0D01*
G01Y454935D02*
G03I-708J0D01*
G01X1975852Y457395D02*
G03X1977417Y458960I0J1565D01*
G01X1974425Y457395D02*
G03X1972860Y455830I0J-1565D01*
G01X1976787Y460407D02*
G03X1975803Y461391I-984J0D01*
G01X1973047D02*
G03X1972063Y460407I0J-984D01*
G01X1974854Y460447D02*
G03I-708J0D01*
G01X1969307Y463124D02*
G03I-1969J0D01*
G01X1976393D02*
G03I-1968J0D01*
G01X1961787Y469009D02*
X1965803D01*
G01X1968874D02*
X1972889D01*
G01X1975960D02*
X1977981D01*
G01X1977417Y469403D02*
X1975619D01*
G01X1973231D02*
X1968532D01*
G01X1966144D02*
X1961446D01*
G01X1975960Y476883D02*
X1972889D01*
G01X1968874D02*
X1965803D01*
G01X1961787D02*
X1958716D01*
G01X1974779Y478065D02*
X1974071D01*
G01X1967693D02*
X1966984D01*
G01X1960606D02*
X1959897D01*
G01X1960606D02*
X1961787Y476883D01*
G01X1967693Y478065D02*
X1968874Y476883D01*
G01X1974779Y478065D02*
X1975960Y476883D01*
G01X1959058Y469403D02*
X1958904Y469584D01*
X1958789Y469785D01*
X1958716Y470000D01*
G01X1966144Y469403D02*
X1965991Y469584D01*
X1965876Y469785D01*
X1965803Y470000D01*
G01X1973231Y469403D02*
X1973078Y469584D01*
X1972963Y469785D01*
X1972889Y470000D01*
G01X1958687Y470661D02*
X1958732Y470205D01*
X1958860Y469774D01*
X1959058Y469403D01*
G01X1965773Y470661D02*
X1965818Y470205D01*
X1965947Y469774D01*
X1966144Y469403D01*
G01X1972860Y470661D02*
X1972905Y470205D01*
X1973034Y469774D01*
X1973231Y469403D01*
G01X1958687Y470242D02*
X1958694Y470118D01*
X1958716Y469995D01*
G01X1965773Y470242D02*
X1965781Y470118D01*
X1965803Y469995D01*
G01X1972860Y470242D02*
X1972867Y470118D01*
X1972889Y469995D01*
G01X1958687Y476490D02*
Y470242D01*
G01X1958716Y469009D02*
Y476883D01*
G01X1961787D02*
Y469009D01*
G01X1961817Y476490D02*
Y470242D01*
G01X1965773Y476490D02*
Y470242D01*
G01X1965803Y469009D02*
Y476883D01*
G01X1968874D02*
Y469009D01*
G01X1968903Y476490D02*
Y470242D01*
G01X1972860Y476490D02*
Y470242D01*
G01X1972889Y469009D02*
Y476883D01*
G01X1975960D02*
Y469009D01*
G01X1975990Y476490D02*
Y470242D01*
G01X1961817D02*
X1961809Y470119D01*
X1961787Y469995D01*
G01X1968903Y470242D02*
X1968896Y470119D01*
X1968874Y469995D01*
G01X1975990Y470242D02*
X1975982Y470119D01*
X1975960Y469995D01*
G01X1961787Y470000D02*
X1961714Y469786D01*
X1961598Y469583D01*
X1961446Y469403D01*
G01X1959897Y478065D02*
X1958716Y476883D01*
G01X1966984Y478065D02*
X1965803Y476883D01*
G01X1968874Y470000D02*
X1968801Y469786D01*
X1968685Y469583D01*
X1968532Y469403D01*
G01X1975960Y470000D02*
X1975887Y469786D01*
X1975772Y469583D01*
X1975619Y469403D01*
G01X1961446D02*
X1961643Y469774D01*
X1961772Y470205D01*
X1961817Y470661D01*
G01X1968532Y469403D02*
X1968730Y469774D01*
X1968858Y470205D01*
X1968903Y470661D01*
G01X1975619Y469403D02*
X1975816Y469774D01*
X1975945Y470205D01*
X1975990Y470661D01*
G01X1974071Y478065D02*
X1972889Y476883D01*
G01X1959058Y469403D02*
G03X1961446I1194J1012D01*
G01X1960681Y464777D02*
G03I-709J0D01*
G01X1966144Y469403D02*
G03X1968532I1194J1012D01*
G01X1973231D02*
G03X1975619I1194J1012D01*
G01X1974854Y464777D02*
G03I-708J0D01*
G01X1967768Y465171D02*
G03I-709J0D01*
G01Y469502D02*
G03I-709J0D01*
G01X1945497Y506481D02*
X1946317Y506649D01*
G01X1945497Y512680D02*
X1944677Y512512D01*
G01X1945497Y505643D02*
X1946482Y505811D01*
G01X1945497Y513517D02*
X1944513Y513350D01*
G01X1955832Y505643D02*
X1955012D01*
G01X1953207D02*
X1952387D01*
G01X1950583D02*
X1949762D01*
G01X1941232D02*
X1940412D01*
G01Y506481D02*
X1941232D01*
G01X1954356Y510334D02*
X1953863D01*
G01X1951731D02*
X1951403D01*
G01X1949762Y511004D02*
X1950583D01*
G01X1951403D02*
X1952059D01*
G01X1954028D02*
X1954684D01*
G01X1944513Y505811D02*
X1945497Y505643D01*
G01X1946482Y513350D02*
X1945497Y513517D01*
G01X1944677Y506649D02*
X1945497Y506481D01*
G01X1946317Y512512D02*
X1945497Y512680D01*
G01X1952059Y511004D02*
X1952551Y510837D01*
G01X1954684Y511004D02*
X1955176Y510837D01*
G01X1952059Y510167D02*
X1951731Y510334D01*
G01X1954684Y510167D02*
X1954356Y510334D01*
G01X1943693Y506314D02*
X1944513Y505811D01*
G01X1947302Y512847D02*
X1946482Y513350D01*
G01X1944185Y506984D02*
X1944677Y506649D01*
G01X1946809Y512177D02*
X1946317Y512512D01*
G01X1943201Y506816D02*
X1943693Y506314D01*
G01X1947794Y512345D02*
X1947302Y512847D01*
G01X1952223Y509999D02*
X1952059Y510167D01*
G01X1952551Y510837D02*
X1953043Y510334D01*
G01X1954848Y509999D02*
X1954684Y510167D01*
G01X1955176Y510837D02*
X1955504Y510502D01*
G01X1943529Y507989D02*
X1944185Y506984D01*
G01X1947466Y511172D02*
X1946809Y512177D01*
G01X1942872Y507486D02*
X1943201Y506816D01*
G01X1948122Y511675D02*
X1947794Y512345D01*
G01X1952387Y509664D02*
X1952223Y509999D01*
G01X1955012Y509664D02*
X1954848Y509999D01*
G01X1955504Y510502D02*
X1955832Y509664D01*
G01X1942709Y507989D02*
X1942872Y507486D01*
G01X1950911Y510837D02*
X1951403Y511004D01*
G01Y510334D02*
X1950911Y510167D01*
G01X1953535Y510837D02*
X1954028Y511004D01*
G01X1948286Y511172D02*
X1948122Y511675D01*
G01X1942545Y508827D02*
X1942709Y507989D01*
G01X1939100Y513517D02*
Y505643D01*
G01X1940412D02*
Y506481D01*
G01X1941232D02*
Y505643D01*
G01X1942545Y510334D02*
Y508827D01*
G01X1943365Y510167D02*
Y508994D01*
G01X1944677Y512512D02*
X1944185Y512177D01*
G01X1944513Y513350D02*
X1943693Y512847D01*
G01X1946482Y505811D02*
X1947302Y506314D01*
G01X1953863Y510334D02*
X1953535Y510167D01*
G01X1948450Y510334D02*
X1948286Y511172D01*
G01X1943365Y508994D02*
X1943529Y507989D01*
G01X1947630Y510167D02*
X1947466Y511172D01*
G01X1947630Y508994D02*
Y510167D01*
G01X1948450Y508827D02*
Y510334D01*
G01X1949762Y505643D02*
Y511004D01*
G01X1950583D02*
Y510502D01*
G01Y509832D02*
Y505643D01*
G01X1952387D02*
Y509664D01*
G01X1953207D02*
Y505643D01*
G01X1955012D02*
Y509664D01*
G01X1943529Y511172D02*
X1943365Y510167D01*
G01X1947466Y507989D02*
X1947630Y508994D01*
G01X1942709Y511172D02*
X1942545Y510334D01*
G01X1948286Y507989D02*
X1948450Y508827D01*
G01X1943693Y512847D02*
X1943201Y512345D01*
G01X1950583Y510502D02*
X1950911Y510837D01*
G01Y510167D02*
X1950583Y509832D01*
G01X1947302Y506314D02*
X1947794Y506816D01*
G01X1953043Y510334D02*
X1953535Y510837D01*
G01X1946317Y506649D02*
X1946809Y506984D01*
G01X1942872Y511675D02*
X1942709Y511172D01*
G01X1948122Y507486D02*
X1948286Y507989D01*
G01X1943201Y512345D02*
X1942872Y511675D01*
G01X1947794Y506816D02*
X1948122Y507486D01*
G01X1953371Y509999D02*
X1953207Y509664D01*
G01X1944185Y512177D02*
X1943529Y511172D01*
G01X1946809Y506984D02*
X1947466Y507989D01*
G01X1953535Y510167D02*
X1953371Y509999D01*
G01X1954067Y623045D02*
Y524620D01*
G01X1963214Y505643D02*
X1962394D01*
G01X1960589D02*
X1959769D01*
G01X1957965D02*
X1957144D01*
G01X1961737Y510334D02*
X1961245D01*
G01X1959113D02*
X1958785D01*
G01X1957144Y511004D02*
X1957965D01*
G01X1958785D02*
X1959441D01*
G01X1961409D02*
X1962065D01*
G01X1959441D02*
X1959933Y510837D01*
G01X1962065Y511004D02*
X1962558Y510837D01*
G01X1959441Y510167D02*
X1959113Y510334D01*
G01X1962065Y510167D02*
X1961737Y510334D01*
G01X1959605Y509999D02*
X1959441Y510167D01*
G01X1959933Y510837D02*
X1960425Y510334D01*
G01X1962230Y509999D02*
X1962065Y510167D01*
G01X1962558Y510837D02*
X1962886Y510502D01*
G01X1959769Y509664D02*
X1959605Y509999D01*
G01X1962394Y509664D02*
X1962230Y509999D01*
G01X1958293Y510837D02*
X1958785Y511004D01*
G01Y510334D02*
X1958293Y510167D01*
G01X1960917Y510837D02*
X1961409Y511004D01*
G01X1962886Y510502D02*
X1963214Y509664D01*
G01X1961245Y510334D02*
X1960917Y510167D01*
G01X1955832Y509664D02*
Y505643D01*
G01X1957144D02*
Y511004D01*
G01X1957965D02*
Y510502D01*
G01Y509832D02*
Y505643D01*
G01X1959769D02*
Y509664D01*
G01X1960589D02*
Y505643D01*
G01X1962394D02*
Y509664D01*
G01X1963214D02*
Y505643D01*
G01X1960753Y509999D02*
X1960589Y509664D01*
G01X1957965Y510502D02*
X1958293Y510837D01*
G01Y510167D02*
X1957965Y509832D01*
G01X1960425Y510334D02*
X1960917Y510837D01*
G01Y510167D02*
X1960753Y509999D01*
G01X2009185Y615171D02*
G03I-11811J0D01*
G01X2003280D02*
G03I-5906J0D01*
G01X1997374Y619108D02*
Y625230D01*
G01X1963909Y829738D02*
X2022965D01*
G01X1963909Y908478D02*
Y829738D01*
G01X2111019Y940639D02*
G03I-77952J0D01*
G01X2022965Y964479D02*
G03Y903107I-17717J-30686D01*
G01Y964479D02*
G03Y903107I-17717J-30686D01*
G01Y964479D02*
G03Y903107I-17717J-30686D01*
G01X2012532Y933793D02*
G03I-7284J0D01*
G01D02*
G03I-7284J0D01*
G01X2052304Y-879845D02*
Y-898782D01*
G01X2024601Y-497010D02*
X2012790D01*
G01Y73856D02*
Y-497010D01*
G01X2032475Y65982D02*
Y-489136D01*
G01Y65982D02*
Y-489136D01*
G01X2024601Y-497010D02*
G03X2032475Y-489136I0J7874D01*
G01X2024601Y-497010D02*
G03X2032475Y-489136I0J7874D01*
G01X2022654Y-314740D02*
X2015979D01*
G01Y-313378D02*
X2022654D01*
G01Y-310383D02*
X2015979D01*
G01Y-309022D02*
X2022654D01*
G01X2024879Y-306026D02*
X2024044D01*
G01X2022932D02*
X2015979D01*
G01Y-304665D02*
X2024879D01*
G01X2022654Y-302486D02*
X2015979D01*
G01Y-301124D02*
X2022654D01*
G01X2023210Y-310656D02*
X2022654Y-310383D01*
G01X2024044Y-301941D02*
X2022654Y-302486D01*
G01X2023488Y-310928D02*
X2023210Y-310656D01*
G01X2023766Y-310111D02*
X2024601Y-310928D01*
G01X2023488Y-306571D02*
X2022932Y-306026D01*
G01X2024044D02*
X2024601Y-306571D01*
G01X2022654Y-301124D02*
X2023210Y-300852D01*
G01X2022654Y-309022D02*
X2023210Y-308749D01*
G01X2022654Y-313378D02*
X2023210Y-313106D01*
G01X2024044Y-314195D02*
X2022654Y-314740D01*
G01X2023766Y-311472D02*
X2023488Y-310928D01*
G01X2023210Y-300852D02*
X2023488Y-300580D01*
G01X2024601Y-301397D02*
X2024044Y-301941D01*
G01X2023210Y-308749D02*
X2023488Y-308477D01*
G01X2024601Y-309294D02*
X2023766Y-310111D01*
G01X2023210Y-313106D02*
X2023488Y-312834D01*
G01X2024601Y-313651D02*
X2024044Y-314195D01*
G01X2024601Y-310928D02*
X2024879Y-311745D01*
G01X2023766Y-307388D02*
X2023488Y-306571D01*
G01X2024601D02*
X2024879Y-307388D01*
G01X2015979Y-314740D02*
Y-313378D01*
G01Y-310383D02*
Y-309022D01*
G01Y-306026D02*
Y-304665D01*
G01Y-302486D02*
Y-301124D01*
G01X2023766Y-312289D02*
Y-311472D01*
G01Y-307932D02*
Y-307388D01*
G01X2024879Y-304665D02*
Y-306026D01*
G01Y-307388D02*
Y-308477D01*
G01Y-311745D02*
Y-312834D01*
G01X2023488Y-308477D02*
X2023766Y-307932D01*
G01X2023488Y-312834D02*
X2023766Y-312289D01*
G01X2024879Y-300580D02*
X2024601Y-301397D01*
G01X2024879Y-308477D02*
X2024601Y-309294D01*
G01X2024879Y-312834D02*
X2024601Y-313651D01*
G01X2027104Y-289960D02*
X2025991Y-290232D01*
G01X2023766Y-274711D02*
X2025157Y-274438D01*
G01X2023488Y-273349D02*
X2025157Y-273077D01*
G01X2022654Y-298129D02*
X2015979D01*
G01Y-296768D02*
X2022654D01*
G01X2024879Y-293772D02*
X2024044D01*
G01X2022932D02*
X2015979D01*
G01Y-292411D02*
X2024879D01*
G01X2025991Y-290232D02*
X2025435D01*
G01X2017370D02*
X2015979D01*
G01X2025435Y-288598D02*
X2025991D01*
G01X2015979Y-280429D02*
X2017370D01*
G01Y-278250D02*
X2015979D01*
G01Y-276889D02*
X2017370D01*
G01X2021264Y-274711D02*
X2023766D01*
G01X2021542Y-273349D02*
X2023488D01*
G01X2019873Y-273077D02*
X2021542Y-273349D01*
G01X2019873Y-274438D02*
X2021264Y-274711D01*
G01X2025435Y-290232D02*
X2024323Y-289960D01*
G01X2025991Y-280701D02*
X2027104Y-280974D01*
G01X2019039Y-274166D02*
X2019873Y-274438D01*
G01X2023210Y-298402D02*
X2022654Y-298129D01*
G01X2024323Y-288054D02*
X2025435Y-288598D01*
G01X2017926Y-273621D02*
X2019039Y-274166D01*
G01X2024323Y-289960D02*
X2023488Y-289415D01*
G01X2026825Y-282608D02*
X2025991Y-282063D01*
G01X2018204Y-271987D02*
X2019873Y-273077D01*
G01X2025157Y-274438D02*
X2025991Y-274166D01*
G01D02*
X2027104Y-273621D01*
G01X2023488Y-298674D02*
X2023210Y-298402D01*
G01X2023766Y-297857D02*
X2024601Y-298674D01*
G01X2023488Y-294317D02*
X2022932Y-293772D01*
G01X2024044D02*
X2024601Y-294317D01*
G01X2017092Y-272804D02*
X2017926Y-273621D01*
G01X2027104Y-280974D02*
X2028216Y-282063D01*
G01X2022654Y-296768D02*
X2023210Y-296495D01*
G01X2017370Y-280429D02*
X2024323Y-288054D01*
G01X2023488Y-289415D02*
X2017370Y-282608D01*
G01X2025157Y-273077D02*
X2026825Y-271987D01*
G01X2025991Y-288598D02*
X2026825Y-288054D01*
G01X2017648Y-271171D02*
X2018204Y-271987D01*
G01X2027382Y-283424D02*
X2026825Y-282608D01*
G01X2027104Y-273621D02*
X2027938Y-272804D01*
G01X2016258Y-271443D02*
X2017092Y-272804D01*
G01X2023766Y-299219D02*
X2023488Y-298674D01*
G01X2028216Y-282063D02*
X2028772Y-283152D01*
G01X2026825Y-271987D02*
X2027382Y-271171D01*
G01X2028216Y-288871D02*
X2027104Y-289960D01*
G01X2023210Y-296495D02*
X2023488Y-296223D01*
G01X2024601Y-297040D02*
X2023766Y-297857D01*
G01X2024601Y-298674D02*
X2024879Y-299491D01*
G01X2023766Y-295134D02*
X2023488Y-294317D01*
G01X2024601D02*
X2024879Y-295134D01*
G01X2015979Y-298129D02*
Y-296768D01*
G01Y-293772D02*
Y-292411D01*
G01Y-290232D02*
Y-280429D01*
G01Y-278250D02*
Y-276889D01*
G01X2017370D02*
Y-278250D01*
G01Y-282608D02*
Y-290232D01*
G01X2023766Y-300035D02*
Y-299219D01*
G01Y-295678D02*
Y-295134D01*
G01X2024879Y-292411D02*
Y-293772D01*
G01Y-295134D02*
Y-296223D01*
G01Y-299491D02*
Y-300580D01*
G01X2023488Y-296223D02*
X2023766Y-295678D01*
G01X2028772Y-287782D02*
X2028216Y-288871D01*
G01X2023488Y-300580D02*
X2023766Y-300035D01*
G01X2027938Y-272804D02*
X2028772Y-271443D01*
G01X2026825Y-288054D02*
X2027382Y-287237D01*
G01X2017370Y-269809D02*
X2017648Y-271171D01*
G01X2027660Y-284786D02*
X2027382Y-283424D01*
G01X2015979Y-269809D02*
X2016258Y-271443D01*
G01X2028772Y-283152D02*
X2029050Y-285058D01*
G01X2025991Y-282063D02*
Y-280701D01*
G01X2027660Y-285875D02*
Y-284786D01*
G01X2029050Y-285058D02*
Y-286148D01*
G01X2028772Y-271443D02*
X2029050Y-269809D01*
G01Y-286148D02*
X2028772Y-287782D01*
G01X2027382Y-271171D02*
X2027660Y-269809D01*
G01X2027382Y-287237D02*
X2027660Y-285875D01*
G01X2024879Y-296223D02*
X2024601Y-297040D01*
G01X2021264Y-264908D02*
X2019873Y-265180D01*
G01X2021542Y-266269D02*
X2019873Y-266541D01*
G01X2023488Y-266269D02*
X2021542D01*
G01X2023766Y-264908D02*
X2021264D01*
G01X2025157Y-266541D02*
X2023488Y-266269D01*
G01X2025157Y-265180D02*
X2023766Y-264908D01*
G01X2025991Y-265452D02*
X2025157Y-265180D01*
G01X2027104Y-265996D02*
X2025991Y-265452D01*
G01X2019873Y-265180D02*
X2019039Y-265452D01*
G01X2026825Y-267630D02*
X2025157Y-266541D01*
G01X2020707Y-262729D02*
X2019873Y-262184D01*
G01X2019039Y-265452D02*
X2017926Y-265996D01*
G01X2025435Y-262184D02*
X2024601Y-262729D01*
G01X2019873Y-266541D02*
X2018204Y-267630D01*
G01X2027938Y-266813D02*
X2027104Y-265996D01*
G01X2027382Y-268447D02*
X2026825Y-267630D01*
G01X2017926Y-265996D02*
X2017092Y-266813D01*
G01X2028772Y-268175D02*
X2027938Y-266813D01*
G01X2022654Y-257010D02*
X2025435Y-262184D01*
G01X2024601Y-262729D02*
X2022654Y-258917D01*
G01X2017092Y-266813D02*
X2016258Y-268175D01*
G01X2018204Y-267630D02*
X2017648Y-268447D01*
G01X2016258Y-268175D02*
X2015979Y-269809D01*
G01X2017648Y-268447D02*
X2017370Y-269809D01*
G01X2022654Y-258917D02*
X2020707Y-262729D01*
G01X2019873Y-262184D02*
X2022654Y-257010D01*
G01X2027660Y-269809D02*
X2027382Y-268447D01*
G01X2029050Y-269809D02*
X2028772Y-268175D01*
G01X2029050Y-254832D02*
X2015979D01*
G01Y-253198D02*
X2022098D01*
G01X2023766D02*
X2029050D01*
G01Y-245573D02*
X2023766D01*
G01X2022098D02*
X2015979D01*
G01Y-243939D02*
X2029050D01*
G01X2015979Y-254832D02*
Y-253198D01*
G01Y-245573D02*
Y-243939D01*
G01X2022098Y-253198D02*
Y-245573D01*
G01X2023766D02*
Y-253198D01*
G01X2029050Y-243939D02*
Y-245573D01*
G01Y-253198D02*
Y-254832D01*
G01X2032475Y65982D02*
G03X2024601Y73856I-7874J0D01*
G01X2032475Y65982D02*
G03X2024601Y73856I-7874J0D01*
G01X2042650Y420289D02*
Y381313D01*
G01X2034776Y416352D02*
X2022965D01*
G01Y987218D02*
Y416352D01*
G01X2034776D02*
G03X2042650Y424226I0J7874D01*
G01X2034776Y416352D02*
G03X2042650Y424226I0J7874D01*
G01Y979344D02*
Y424226D01*
G01Y979344D02*
Y424226D01*
G01X2015091Y695880D02*
Y491155D01*
G01X2001311Y615171D02*
X2082117D01*
G01X2037190Y731893D02*
X2036185Y731647D01*
G01X2033169Y709502D02*
X2027138D01*
G01Y710732D02*
X2033169D01*
G01Y713439D02*
X2027138D01*
G01Y714669D02*
X2033169D01*
G01X2035179Y717376D02*
X2034425D01*
G01X2033420D02*
X2027138D01*
G01Y718606D02*
X2035179D01*
G01X2033169Y720574D02*
X2027138D01*
G01Y721805D02*
X2033169D01*
G01Y724511D02*
X2027138D01*
G01Y725742D02*
X2033169D01*
G01X2035179Y728448D02*
X2034425D01*
G01X2033420D02*
X2027138D01*
G01Y729679D02*
X2035179D01*
G01X2036185Y731647D02*
X2035682D01*
G01X2028394D02*
X2027138D01*
G01X2034425Y721067D02*
X2033169Y720574D01*
G01Y725742D02*
X2033672Y725988D01*
G01X2033169Y721805D02*
X2033672Y722051D01*
G01X2034425Y709994D02*
X2033169Y709502D01*
G01Y714669D02*
X2033672Y714915D01*
G01X2033169Y710732D02*
X2033672Y710978D01*
G01X2035682Y731647D02*
X2034677Y731893D01*
G01X2033672Y713193D02*
X2033169Y713439D01*
G01X2033672Y724265D02*
X2033169Y724511D01*
G01X2038195Y732878D02*
X2037190Y731893D01*
G01X2033672Y725988D02*
X2033923Y726234D01*
G01X2034928Y725496D02*
X2034174Y724758D01*
G01X2033672Y722051D02*
X2033923Y722297D01*
G01X2034928Y721559D02*
X2034425Y721067D01*
G01X2033672Y714915D02*
X2033923Y715161D01*
G01X2034928Y714423D02*
X2034174Y713685D01*
G01X2033672Y710978D02*
X2033923Y711224D01*
G01X2034928Y710486D02*
X2034425Y709994D01*
G01X2034677Y731893D02*
X2033923Y732385D01*
G01Y712946D02*
X2033672Y713193D01*
G01X2034174Y713685D02*
X2034928Y712946D01*
G01X2033923Y716883D02*
X2033420Y717376D01*
G01X2034425D02*
X2034928Y716883D01*
G01X2033923Y726234D02*
X2034174Y726726D01*
G01X2033923Y722297D02*
X2034174Y722789D01*
G01X2033923Y715161D02*
X2034174Y715653D01*
G01X2033923Y711224D02*
X2034174Y711716D01*
G01X2033923Y724019D02*
X2033672Y724265D01*
G01X2034174Y724758D02*
X2034928Y724019D01*
G01X2033923Y727956D02*
X2033420Y728448D01*
G01X2034425D02*
X2034928Y727956D01*
G01X2033923Y732385D02*
X2028394Y738537D01*
G01X2035179Y726234D02*
X2034928Y725496D01*
G01X2035179Y722297D02*
X2034928Y721559D01*
G01X2035179Y715161D02*
X2034928Y714423D01*
G01X2035179Y711224D02*
X2034928Y710486D01*
G01X2034174Y712454D02*
X2033923Y712946D01*
G01X2034174Y723527D02*
X2033923Y724019D01*
G01X2027138Y709502D02*
Y710732D01*
G01Y713439D02*
Y714669D01*
G01Y717376D02*
Y718606D01*
G01Y720574D02*
Y721805D01*
G01Y724511D02*
Y725742D01*
G01Y728448D02*
Y729679D01*
G01Y731647D02*
Y740506D01*
G01X2028394Y738537D02*
Y731647D01*
G01X2034174Y711716D02*
Y712454D01*
G01Y715653D02*
Y716145D01*
G01Y722789D02*
Y723527D01*
G01Y726726D02*
Y727218D01*
G01X2035179Y729679D02*
Y728448D01*
G01Y727218D02*
Y726234D01*
G01Y723281D02*
Y722297D01*
G01Y718606D02*
Y717376D01*
G01Y716145D02*
Y715161D01*
G01Y712208D02*
Y711224D01*
G01X2034928Y712946D02*
X2035179Y712208D01*
G01X2034174Y716145D02*
X2033923Y716883D01*
G01X2034928D02*
X2035179Y716145D01*
G01X2034928Y724019D02*
X2035179Y723281D01*
G01X2034174Y727218D02*
X2033923Y727956D01*
G01X2034928D02*
X2035179Y727218D01*
G01X2035682Y733124D02*
X2036185D01*
G01D02*
X2036938Y733616D01*
G01X2034677D02*
X2035682Y733124D01*
G01X2036938Y733616D02*
X2037441Y734354D01*
G01X2038698Y733862D02*
X2038195Y732878D01*
G01X2028394Y740506D02*
X2034677Y733616D01*
G01X2038949Y735338D02*
X2038698Y733862D01*
G01X2034174Y745673D02*
X2035431Y745919D01*
G01X2031912Y754531D02*
X2030656Y754285D01*
G01X2033923Y746903D02*
X2035431Y747149D01*
G01X2032164Y753301D02*
X2030656Y753055D01*
G01Y754285D02*
X2029902Y754039D01*
G01X2035431Y745919D02*
X2036185Y746165D01*
G01X2027138Y740506D02*
X2028394D01*
G01Y742474D02*
X2027138D01*
G01Y743704D02*
X2028394D01*
G01X2031912Y745673D02*
X2034174D01*
G01X2032164Y746903D02*
X2033923D01*
G01X2029902Y754039D02*
X2028897Y753547D01*
G01X2033923Y753301D02*
X2032164D01*
G01X2034174Y754531D02*
X2031912D01*
G01X2036185Y746165D02*
X2037190Y746657D01*
G01X2030656Y747149D02*
X2032164Y746903D01*
G01X2035431Y753055D02*
X2033923Y753301D01*
G01X2035682Y756992D02*
X2034928Y756500D01*
G01X2030656Y753055D02*
X2029148Y752071D01*
G01X2035431Y747149D02*
X2036938Y748133D01*
G01X2030656Y745919D02*
X2031912Y745673D01*
G01X2035431Y754285D02*
X2034174Y754531D01*
G01X2036185Y740259D02*
X2037190Y740013D01*
G01X2029902Y746165D02*
X2030656Y745919D01*
G01X2036185Y754039D02*
X2035431Y754285D01*
G01X2028897Y753547D02*
X2028143Y752809D01*
G01X2037190Y746657D02*
X2037944Y747395D01*
G01X2028897Y746657D02*
X2029902Y746165D01*
G01X2037190Y753547D02*
X2036185Y754039D01*
G01X2036938Y738537D02*
X2036185Y739029D01*
G01X2029148Y748133D02*
X2030656Y747149D01*
G01X2028143Y752809D02*
X2027389Y751578D01*
G01X2037944Y747395D02*
X2038698Y748626D01*
G01X2029148Y752071D02*
X2028646Y751332D01*
G01X2036938Y748133D02*
X2037441Y748872D01*
G01X2036938Y752071D02*
X2035431Y753055D01*
G01X2031410Y756500D02*
X2030656Y756992D01*
G01X2033169Y759945D02*
X2031410Y756500D01*
G01X2030656Y756992D02*
X2033169Y761667D01*
G01X2028143Y747395D02*
X2028897Y746657D01*
G01X2037190Y740013D02*
X2038195Y739029D01*
G01X2037944Y752809D02*
X2037190Y753547D01*
G01X2027389Y751578D02*
X2027138Y750102D01*
G01X2028646Y751332D02*
X2028394Y750102D01*
G01X2028646Y748872D02*
X2029148Y748133D01*
G01X2037441Y737799D02*
X2036938Y738537D01*
G01X2037441Y751332D02*
X2036938Y752071D01*
G01X2027389Y748626D02*
X2028143Y747395D01*
G01X2027138Y742474D02*
Y743704D01*
G01X2028394D02*
Y742474D01*
G01X2036185Y739029D02*
Y740259D01*
G01X2037692Y735584D02*
Y736569D01*
G01X2038949Y736322D02*
Y735338D01*
G01X2038698Y748626D02*
X2038949Y750102D01*
G01X2037441Y748872D02*
X2037692Y750102D01*
G01X2037441Y734354D02*
X2037692Y735584D01*
G01X2038698Y751578D02*
X2037944Y752809D01*
G01X2033169Y761667D02*
X2035682Y756992D01*
G01X2038195Y739029D02*
X2038698Y738045D01*
G01X2034928Y756500D02*
X2033169Y759945D01*
G01X2028394Y750102D02*
X2028646Y748872D01*
G01X2037692Y736569D02*
X2037441Y737799D01*
G01X2037692Y750102D02*
X2037441Y751332D01*
G01X2027138Y750102D02*
X2027389Y748626D01*
G01X2038949Y750102D02*
X2038698Y751578D01*
G01Y738045D02*
X2038949Y736322D01*
G01Y763635D02*
X2027138D01*
G01Y765112D02*
X2032666D01*
G01X2034174D02*
X2038949D01*
G01Y772002D02*
X2034174D01*
G01X2032666D02*
X2027138D01*
G01Y773478D02*
X2038949D01*
G01X2027138Y763635D02*
Y765112D01*
G01Y772002D02*
Y773478D01*
G01X2032666Y765112D02*
Y772002D01*
G01X2034174D02*
Y765112D01*
G01X2038949Y773478D02*
Y772002D01*
G01Y765112D02*
Y763635D01*
G01X2005248Y920013D02*
Y1022258D01*
G01X2009185Y916076D02*
X2121487D01*
G01X2008299Y916077D02*
G03I-3051J0D01*
G01D02*
G03I-3051J0D01*
G01X2022965Y903107D02*
Y964479D01*
G01Y903107D02*
Y964479D01*
G01X2009185Y933793D02*
X2121487D01*
G01X2009185Y951509D02*
X2121487D01*
G01X2009382Y951510D02*
G03I-4134J0D01*
G01D02*
G03I-4134J0D01*
G01X2042650Y979344D02*
G03X2034776Y987218I-7874J0D01*
G01X2042650Y979344D02*
G03X2034776Y987218I-7874J0D01*
G01X2053250Y1297911D02*
Y1278974D01*
G01X2067506Y-879845D02*
X2717940D01*
G01X2080237Y1002699D02*
X2097770Y1025766D01*
G01D02*
X2109581D01*
G01X2272920Y-879845D02*
Y-898782D01*
G01X2261246Y-689767D02*
Y-779897D01*
G01X2264914Y-735085D02*
X2678569D01*
G01X2272920Y1297911D02*
Y1278974D01*
G01X2387231D02*
X2717939D01*
G01X2492589Y-879845D02*
Y-898782D01*
G01X2450222Y-689767D02*
Y-779897D01*
G01X2492589Y1297911D02*
Y1278974D01*
G01X2678569Y-840475D02*
Y-584690D01*
G01X2736876Y1297911D02*
Y-898782D01*
G01X2717939Y1278974D02*
Y-879845D01*
G01X2717940Y-735160D02*
Y-879845D01*
G01X2717939Y-663963D02*
X2736876D01*
G01X2717939Y-448081D02*
X2736876D01*
G01X2717939Y-232199D02*
X2736876D01*
G01X2717939Y-16317D02*
X2736876D01*
G01X2717939Y199565D02*
X2736876D01*
G01X2717939Y415446D02*
X2736876D01*
G01X2717939Y631328D02*
X2736876D01*
G01X2717939Y847210D02*
X2736876D01*
G01X2717750Y1063092D02*
X2736687D01*
G01X2717939Y1278974D02*
Y1184486D01*
M02*
